FILE_TYPE=CROSS_REFERENCE;
ROOT_DRAWING='BASEBOARD_FAB2';
RUN_TIME='Nov 19 16:16:37 2015';
PROGRAM_VERSION='16.20-p001';
**** Part Type '2D2R2F-GP_SMD-RG1' ('2D2R2F-GP_SMD-RG1-2D2R2F-GP,64A') ****
**** Part Type '3D01R5F-GP_SMD-RG5' ('3D01R5F-GP_SMD-RG5-3D01R5F-GP,A') ****
**** Part Type '74CBTLV1G125' ('74CBTLV1G125_SMLF-IC,C88177-00A') ****
**** Part Type 'ADC128D818_SM' ('ADC128D818_SM-IC,H63642-001') ****
**** Part Type 'ADM1085_SMT' ('ADM1085_SMT-IC,H46130-001') ****
**** Part Type 'ADM1278_SM' ('ADM1278_SM-IC,G99251-001') ****
**** Part Type 'ADM4073_SM' ('ADM4073_SM-EMPTY,G12194-001') ****
**** Part Type 'ADM809' ('ADM809_SMLF-IC,D23047-001-GND=A') ****
**** Part Type 'AST1250_BGA' ('AST1250_BGA-IC,G85138-002') ****
**** Part Type 'AT24C64' ('AT24C64_SOICLF-IC,C47049-001-GA') ****
**** Part Type 'BASEBOARD_FAB2' ('BASEBOARD_FAB2') ****

PART CROSS REFERENCE (forward interface)

BATTERY  I47  BT8G1  [BATTERY_PLCLF-202168-001]

CAP  I68  C1A1   [CAP_0805LF-22UF,4V,20%,X6S,C95A]
    1  PVDDQ_KLM          A  @BASEBOARD_FAB2_LIB.BASEBOARD_FAB2(SCH_1):PVDDQ_KLM
    2  GND                B  @BASEBOARD_FAB2_LIB.BASEBOARD_FAB2(SCH_1):GND

CAP_A  I53  C1A2   [CAP_A_0402V-1.0UF,6.3V,10%,X6SA]
    1  P5V_STBY           A  @BASEBOARD_FAB2_LIB.BASEBOARD_FAB2(SCH_1):P5V_STBY
    2  GND                B  @BASEBOARD_FAB2_LIB.BASEBOARD_FAB2(SCH_1):GND

CAP  I79  C1A4   [CAP_0805-10UF,16V,10%,X7R,G106A]
    1  P12V_NVDIMM_KLM      A  @BASEBOARD_FAB2_LIB.BASEBOARD_FAB2(SCH_1):P12V_NVDIMM_KLM
    2  GND                B  @BASEBOARD_FAB2_LIB.BASEBOARD_FAB2(SCH_1):GND

CAP_A  I178  C1A5   [CAP_A_0402V-0.01UF,25V,10%,X7RA]
    1  M_M_VREF           A  @BASEBOARD_FAB2_LIB.BASEBOARD_FAB2(SCH_1):M_M_VREF
    2  GND                B  @BASEBOARD_FAB2_LIB.BASEBOARD_FAB2(SCH_1):GND

CAP_0402  I77  C1A6   [CAP_0402-1.0UF,16V,10%,X6S,D97A]
    1  VR_PVDDQ_KLM_PH2_VCIN      A  @BASEBOARD_FAB2_LIB.BASEBOARD_FAB2(SCH_1):VR_PVDDQ_KLM_PH2_VCIN
    2  GND                B  @BASEBOARD_FAB2_LIB.BASEBOARD_FAB2(SCH_1):GND

CAP_0402  I75  C1A8   [CAP_0402-0.220UF,16V,10%,X7R,AA]
    2  VR_PVDDQ_KLM_PH2_PHASE      B  @BASEBOARD_FAB2_LIB.BASEBOARD_FAB2(SCH_1):VR_PVDDQ_KLM_PH2_PHASE
    1  VR_PVDDQ_KLM_PH2_BOOT      A  @BASEBOARD_FAB2_LIB.BASEBOARD_FAB2(SCH_1):VR_PVDDQ_KLM_PH2_BOOT

CAP_0402  I79  C1A9   [CAP_0402-1.0UF,16V,10%,X6S,D97A]
    1  VR_FET_SW_P12V_STBY_PVDDQ_KLM      A  @BASEBOARD_FAB2_LIB.BASEBOARD_FAB2(SCH_1):VR_FET_SW_P12V_STBY_PVDDQ_KLM
    2  GND                B  @BASEBOARD_FAB2_LIB.BASEBOARD_FAB2(SCH_1):GND

CAP_A  I51  C1A10  [CAP_A_0402V-0.1UF,16V,10%,X7R,A]
    1  VR_FET_SW_P12V_STBY_PVDDQ_KLM      A  @BASEBOARD_FAB2_LIB.BASEBOARD_FAB2(SCH_1):VR_FET_SW_P12V_STBY_PVDDQ_KLM
    2  GND                B  @BASEBOARD_FAB2_LIB.BASEBOARD_FAB2(SCH_1):GND

CAP_A  I73  C1A11  [CAP_A_0402V-1.0UF,6.3V,10%,X6SA]
    1  P5V_STBY           A  @BASEBOARD_FAB2_LIB.BASEBOARD_FAB2(SCH_1):P5V_STBY
    2  GND                B  @BASEBOARD_FAB2_LIB.BASEBOARD_FAB2(SCH_1):GND

CAP  I6   C1A12  [CAP_0805LF-22UF,4V,20%,X6S,C95A]
    1  PVDDQ_KLM          A  @BASEBOARD_FAB2_LIB.BASEBOARD_FAB2(SCH_1):PVDDQ_KLM
    2  GND                B  @BASEBOARD_FAB2_LIB.BASEBOARD_FAB2(SCH_1):GND

CAP_0402  I72  C1A13  [CAP_0402-0.22UF,16V,10%,X7R,A3A]
    1  P5V_STBY           A  @BASEBOARD_FAB2_LIB.BASEBOARD_FAB2(SCH_1):P5V_STBY
    2  GND                B  @BASEBOARD_FAB2_LIB.BASEBOARD_FAB2(SCH_1):GND

CAP  I85  C1A16  [CAP_0805-10UF,16V,10%,X7R,G106A]
    1  P12V_NVDIMM_KLM      A  @BASEBOARD_FAB2_LIB.BASEBOARD_FAB2(SCH_1):P12V_NVDIMM_KLM
    2  GND                B  @BASEBOARD_FAB2_LIB.BASEBOARD_FAB2(SCH_1):GND

CAP_A  I182  C1A17  [CAP_A_0402V-0.01UF,25V,10%,X7RA]
    1  M_L_VREF           A  @BASEBOARD_FAB2_LIB.BASEBOARD_FAB2(SCH_1):M_L_VREF
    2  GND                B  @BASEBOARD_FAB2_LIB.BASEBOARD_FAB2(SCH_1):GND

CAP_0402  I44  C1A18  [CAP_0402-0.220UF,16V,10%,X7R,AA]
    2  VR_PVDDQ_KLM_PH1_PHASE      B  @BASEBOARD_FAB2_LIB.BASEBOARD_FAB2(SCH_1):VR_PVDDQ_KLM_PH1_PHASE
    1  VR_PVDDQ_KLM_PH1_BOOT      A  @BASEBOARD_FAB2_LIB.BASEBOARD_FAB2(SCH_1):VR_PVDDQ_KLM_PH1_BOOT

CAP_0402  I48  C1A19  [CAP_0402-1.0UF,16V,10%,X6S,D97A]
    1  VR_FET_SW_P12V_STBY_PVDDQ_KLM      A  @BASEBOARD_FAB2_LIB.BASEBOARD_FAB2(SCH_1):VR_FET_SW_P12V_STBY_PVDDQ_KLM
    2  GND                B  @BASEBOARD_FAB2_LIB.BASEBOARD_FAB2(SCH_1):GND

CAP_A  I78  C1A20  [CAP_A_0402V-0.1UF,16V,10%,X7R,A]
    1  VR_FET_SW_P12V_STBY_PVDDQ_KLM      A  @BASEBOARD_FAB2_LIB.BASEBOARD_FAB2(SCH_1):VR_FET_SW_P12V_STBY_PVDDQ_KLM
    2  GND                B  @BASEBOARD_FAB2_LIB.BASEBOARD_FAB2(SCH_1):GND

CAP_A  I44  C1B2   [CAP_A_0402V-0.1UF,16V,10%,X7R,A]
    1  VR_PVDDQ_KLM_VD12      A  @BASEBOARD_FAB2_LIB.BASEBOARD_FAB2(SCH_1):VR_PVDDQ_KLM_VD12
    2  GND                B  @BASEBOARD_FAB2_LIB.BASEBOARD_FAB2(SCH_1):GND

CAP_A  I41  C1B3   [CAP_A_0402V-1.0UF,6.3V,10%,X6SA]
    1  VR_PVDDQ_KLM_VD12      A  @BASEBOARD_FAB2_LIB.BASEBOARD_FAB2(SCH_1):VR_PVDDQ_KLM_VD12
    2  GND                B  @BASEBOARD_FAB2_LIB.BASEBOARD_FAB2(SCH_1):GND

CAP  I80  C1B4   [CAP_0402LF-1000PF,50V,10%,X7R,A]
    1  PWRGD_PVDDQ_KLM_R      A  @BASEBOARD_FAB2_LIB.BASEBOARD_FAB2(SCH_1):PWRGD_PVDDQ_KLM_R
    2  GND                B  @BASEBOARD_FAB2_LIB.BASEBOARD_FAB2(SCH_1):GND

CAP_A  I27  C1B5   [CAP_A_0402V-0.1UF,16V,10%,X7R,A]
    1  VR_PVDDQ_KLM_VDD      A  @BASEBOARD_FAB2_LIB.BASEBOARD_FAB2(SCH_1):VR_PVDDQ_KLM_VDD
    2  GND                B  @BASEBOARD_FAB2_LIB.BASEBOARD_FAB2(SCH_1):GND

CAP_A  I25  C1B6   [CAP_A_0402V-1.0UF,6.3V,10%,X6SA]
    1  VR_PVDDQ_KLM_VDD      A  @BASEBOARD_FAB2_LIB.BASEBOARD_FAB2(SCH_1):VR_PVDDQ_KLM_VDD
    2  GND                B  @BASEBOARD_FAB2_LIB.BASEBOARD_FAB2(SCH_1):GND

CAP  I82  C1B7   [CAP_0805-10UF,16V,10%,X7R,G106A]
    1  P12V_NVDIMM_KLM      A  @BASEBOARD_FAB2_LIB.BASEBOARD_FAB2(SCH_1):P12V_NVDIMM_KLM
    2  GND                B  @BASEBOARD_FAB2_LIB.BASEBOARD_FAB2(SCH_1):GND

CAP  I59  C1B8   [CAP_0402LF-1000PF,50V,10%,X7R,A]
    1  VR_PVDDQ_KLM_VINSEN      A  @BASEBOARD_FAB2_LIB.BASEBOARD_FAB2(SCH_1):VR_PVDDQ_KLM_VINSEN
    2  GND                B  @BASEBOARD_FAB2_LIB.BASEBOARD_FAB2(SCH_1):GND

CAP_A  I176  C1B9   [CAP_A_0402V-0.01UF,25V,10%,X7RA]
    1  M_K_VREF           A  @BASEBOARD_FAB2_LIB.BASEBOARD_FAB2(SCH_1):M_K_VREF
    2  GND                B  @BASEBOARD_FAB2_LIB.BASEBOARD_FAB2(SCH_1):GND

CAPP  I175  C1B10  [CAPP_2626-270UF,16V,20%,OSCON,A]
    1  VR_FET_SW_P12V_STBY_PVDDQ_KLM      A  @BASEBOARD_FAB2_LIB.BASEBOARD_FAB2(SCH_1):VR_FET_SW_P12V_STBY_PVDDQ_KLM
    2  GND                B  @BASEBOARD_FAB2_LIB.BASEBOARD_FAB2(SCH_1):GND

CAP  I36  C1B11  [CAP_0402LF-220PF,50V,10%,X7R,AA]
    2  GND                B  @BASEBOARD_FAB2_LIB.BASEBOARD_FAB2(SCH_1):GND
    1  A_TSENSE_PVDDQ_KLM      A  @BASEBOARD_FAB2_LIB.BASEBOARD_FAB2(SCH_1):A_TSENSE_PVDDQ_KLM

CAP  I39  C1B12  [CAP_0402LF-220PF,50V,10%,X7R,AA]
    2  VSENSE_PVDDQ_KLM_N      B  @BASEBOARD_FAB2_LIB.BASEBOARD_FAB2(SCH_1):VSENSE_PVDDQ_KLM_N
    1  VR_PVDDQ_KLM_AVSP      A  @BASEBOARD_FAB2_LIB.BASEBOARD_FAB2(SCH_1):VR_PVDDQ_KLM_AVSP

CAPP  I84  C1B14  [CAPP_4040LF-470UF,16V,20%,ALUMA]
    1  P12V_STBY          A  @BASEBOARD_FAB2_LIB.BASEBOARD_FAB2(SCH_1):P12V_STBY
    2  GND                B  @BASEBOARD_FAB2_LIB.BASEBOARD_FAB2(SCH_1):GND

CAP_A  I68  C1B15  [CAP_A_0402V-0.01UF,25V,10%,X7RA]
    2  GND                B  @BASEBOARD_FAB2_LIB.BASEBOARD_FAB2(SCH_1):GND
    1  FAN_TACH2          A  @BASEBOARD_FAB2_LIB.BASEBOARD_FAB2(SCH_1):FAN_TACH2

CAP_A  I30  C1B16  [CAP_A_0402V-0.1UF,16V,10%,EMPTA]
    1  VR_FET_SW_P12V_PVCCIN_CPU1_R      A  @BASEBOARD_FAB2_LIB.BASEBOARD_FAB2(SCH_1):VR_FET_SW_P12V_PVCCIN_CPU1_R
    2  GND                B  @BASEBOARD_FAB2_LIB.BASEBOARD_FAB2(SCH_1):GND

CAP_A  I128  C1B17  [CAP_A_0402V-0.01UF,25V,10%,X7RA]
    2  GND                B  @BASEBOARD_FAB2_LIB.BASEBOARD_FAB2(SCH_1):GND
    1  FAN_TACH3          A  @BASEBOARD_FAB2_LIB.BASEBOARD_FAB2(SCH_1):FAN_TACH3

CAP  I61  C1B18  [CAP_0805-10UF,16V,10%,X6S,C953A]
    1  P12V_FAN           A  @BASEBOARD_FAB2_LIB.BASEBOARD_FAB2(SCH_1):P12V_FAN
    2  GND                B  @BASEBOARD_FAB2_LIB.BASEBOARD_FAB2(SCH_1):GND

CAP_A  I64  C1B19  [CAP_A_0402V-0.1UF,16V,10%,X7R,A]
    1  P12V_FAN           A  @BASEBOARD_FAB2_LIB.BASEBOARD_FAB2(SCH_1):P12V_FAN
    2  GND                B  @BASEBOARD_FAB2_LIB.BASEBOARD_FAB2(SCH_1):GND

CAP_0402  I50  C1B20  [CAP_0402-1.0UF,16V,10%,X6S,D97A]
    1  VR_PVDDQ_KLM_PH1_VCIN      A  @BASEBOARD_FAB2_LIB.BASEBOARD_FAB2(SCH_1):VR_PVDDQ_KLM_PH1_VCIN
    2  GND                B  @BASEBOARD_FAB2_LIB.BASEBOARD_FAB2(SCH_1):GND

CAP_0402  I54  C1B21  [CAP_0402-0.22UF,16V,10%,X7R,A3A]
    1  P5V_STBY           A  @BASEBOARD_FAB2_LIB.BASEBOARD_FAB2(SCH_1):P5V_STBY
    2  GND                B  @BASEBOARD_FAB2_LIB.BASEBOARD_FAB2(SCH_1):GND

CAPP  I35  C1C1   [CAPP_2626-270UF,16V,20%,OSCON,A]
    1  VR_FET_SW_P12V_STBY_PVCCIN_CPU1      A  @BASEBOARD_FAB2_LIB.BASEBOARD_FAB2(SCH_1):VR_FET_SW_P12V_STBY_PVCCIN_CPU1
    2  GND                B  @BASEBOARD_FAB2_LIB.BASEBOARD_FAB2(SCH_1):GND

CAPP  I38  C1C2   [CAPP_2626-270UF,16V,20%,OSCON,A]
    1  VR_FET_SW_P12V_STBY_PVCCIN_CPU1      A  @BASEBOARD_FAB2_LIB.BASEBOARD_FAB2(SCH_1):VR_FET_SW_P12V_STBY_PVCCIN_CPU1
    2  GND                B  @BASEBOARD_FAB2_LIB.BASEBOARD_FAB2(SCH_1):GND

CAP_A  I23  C1C3   [CAP_A_0402V-1.0UF,6.3V,10%,X6SA]
    1  P5V_STBY           A  @BASEBOARD_FAB2_LIB.BASEBOARD_FAB2(SCH_1):P5V_STBY
    2  GND                B  @BASEBOARD_FAB2_LIB.BASEBOARD_FAB2(SCH_1):GND

CAP_0402  I22  C1C4   [CAP_0402-0.22UF,16V,10%,X7R,A3A]
    1  P5V_STBY           A  @BASEBOARD_FAB2_LIB.BASEBOARD_FAB2(SCH_1):P5V_STBY
    2  GND                B  @BASEBOARD_FAB2_LIB.BASEBOARD_FAB2(SCH_1):GND

CAP_0402  I26  C1C5   [CAP_0402-1.0UF,16V,10%,X6S,D97A]
    1  VR_PVSA_CPU1_VCIN      A  @BASEBOARD_FAB2_LIB.BASEBOARD_FAB2(SCH_1):VR_PVSA_CPU1_VCIN
    2  GND                B  @BASEBOARD_FAB2_LIB.BASEBOARD_FAB2(SCH_1):GND

CAP_A  I41  C1C7   [CAP_A_0402V-1.0UF,6.3V,10%,X6SA]
    1  VR_PVCCIN_CPU1_VDD      A  @BASEBOARD_FAB2_LIB.BASEBOARD_FAB2(SCH_1):VR_PVCCIN_CPU1_VDD
    2  GND                B  @BASEBOARD_FAB2_LIB.BASEBOARD_FAB2(SCH_1):GND

CAP  I73  C1C8   [CAP_0402LF-1000PF,50V,10%,X7R,A]
    1  VR_PVCCIN_CPU1_AVINSEN      A  @BASEBOARD_FAB2_LIB.BASEBOARD_FAB2(SCH_1):VR_PVCCIN_CPU1_AVINSEN
    2  GND                B  @BASEBOARD_FAB2_LIB.BASEBOARD_FAB2(SCH_1):GND

CAP_A  I42  C1C9   [CAP_A_0402V-0.1UF,16V,10%,X7R,A]
    1  VR_PVCCIN_CPU1_VDD      A  @BASEBOARD_FAB2_LIB.BASEBOARD_FAB2(SCH_1):VR_PVCCIN_CPU1_VDD
    2  GND                B  @BASEBOARD_FAB2_LIB.BASEBOARD_FAB2(SCH_1):GND

CAP  I69  C1C10  [CAP_0402LF-220PF,50V,10%,X7R,AA]
    2  GND                B  @BASEBOARD_FAB2_LIB.BASEBOARD_FAB2(SCH_1):GND
    1  A_TSENSE_PVCCIN_CPU1      A  @BASEBOARD_FAB2_LIB.BASEBOARD_FAB2(SCH_1):A_TSENSE_PVCCIN_CPU1

CAP  I71  C1C11  [CAP_0402LF-220PF,50V,10%,X7R,AA]
    2  GND                B  @BASEBOARD_FAB2_LIB.BASEBOARD_FAB2(SCH_1):GND
    1  A_TSENSE_PVSA_CPU1      A  @BASEBOARD_FAB2_LIB.BASEBOARD_FAB2(SCH_1):A_TSENSE_PVSA_CPU1

CAP_0402  I24  C1C12  [CAP_0402-0.220UF,16V,10%,X7R,AA]
    2  VR_PVSA_CPU1_PHASE      B  @BASEBOARD_FAB2_LIB.BASEBOARD_FAB2(SCH_1):VR_PVSA_CPU1_PHASE
    1  VR_PVSA_CPU1_BOOT      A  @BASEBOARD_FAB2_LIB.BASEBOARD_FAB2(SCH_1):VR_PVSA_CPU1_BOOT

CAP_A  I29  C1C13  [CAP_A_0402V-1.0UF,6.3V,10%,X6SA]
    1  VR_PVCCIN_CPU1_VD12      A  @BASEBOARD_FAB2_LIB.BASEBOARD_FAB2(SCH_1):VR_PVCCIN_CPU1_VD12
    2  GND                B  @BASEBOARD_FAB2_LIB.BASEBOARD_FAB2(SCH_1):GND

CAP_A  I31  C1C14  [CAP_A_0402V-0.1UF,16V,10%,X7R,A]
    1  VR_PVCCIN_CPU1_VD12      A  @BASEBOARD_FAB2_LIB.BASEBOARD_FAB2(SCH_1):VR_PVCCIN_CPU1_VD12
    2  GND                B  @BASEBOARD_FAB2_LIB.BASEBOARD_FAB2(SCH_1):GND

CAP_0402  I28  C1C15  [CAP_0402-1.0UF,16V,10%,X6S,D97A]
    1  VR_FET_SW_P12V_STBY_PVCCIN_CPU1      A  @BASEBOARD_FAB2_LIB.BASEBOARD_FAB2(SCH_1):VR_FET_SW_P12V_STBY_PVCCIN_CPU1
    2  GND                B  @BASEBOARD_FAB2_LIB.BASEBOARD_FAB2(SCH_1):GND

CAP  I68  C1C16  [CAP_0402LF-220PF,50V,10%,X7R,AA]
    2  VSENSE_PVSA_CPU1_N      B  @BASEBOARD_FAB2_LIB.BASEBOARD_FAB2(SCH_1):VSENSE_PVSA_CPU1_N
    1  VSENSE_PVSA_CPU1_BVSP      A  @BASEBOARD_FAB2_LIB.BASEBOARD_FAB2(SCH_1):VSENSE_PVSA_CPU1_BVSP

CAP_A  I27  C1C17  [CAP_A_0402V-0.1UF,16V,10%,X7R,A]
    1  VR_FET_SW_P12V_STBY_PVCCIN_CPU1      A  @BASEBOARD_FAB2_LIB.BASEBOARD_FAB2(SCH_1):VR_FET_SW_P12V_STBY_PVCCIN_CPU1
    2  GND                B  @BASEBOARD_FAB2_LIB.BASEBOARD_FAB2(SCH_1):GND

CAP_A  I21  C1C18  [CAP_A_0402V-1.0UF,6.3V,10%,X6SA]
    1  P5V_STBY           A  @BASEBOARD_FAB2_LIB.BASEBOARD_FAB2(SCH_1):P5V_STBY
    2  GND                B  @BASEBOARD_FAB2_LIB.BASEBOARD_FAB2(SCH_1):GND

CAP_A  I8   C1C19  [CAP_A_0603V-22.0UF,4V,20%,X6S,A]
    1  PVSA_CPU1          A  @BASEBOARD_FAB2_LIB.BASEBOARD_FAB2(SCH_1):PVSA_CPU1
    2  GND                B  @BASEBOARD_FAB2_LIB.BASEBOARD_FAB2(SCH_1):GND

CAP  I114  C1C23  [CAP_0402LF-1000PF,50V,10%,X7R,A]
    1  VR_VRRDY_PVCCIN_CPU1      A  @BASEBOARD_FAB2_LIB.BASEBOARD_FAB2(SCH_1):VR_VRRDY_PVCCIN_CPU1
    2  GND                B  @BASEBOARD_FAB2_LIB.BASEBOARD_FAB2(SCH_1):GND

CAP_0402  I20  C1C24  [CAP_0402-0.220UF,16V,10%,X7R,AA]
    2  VR_PVCCIN_CPU1_PH5_PHASE      B  @BASEBOARD_FAB2_LIB.BASEBOARD_FAB2(SCH_1):VR_PVCCIN_CPU1_PH5_PHASE
    1  VR_PVCCIN_CPU1_PH5_BOOT      A  @BASEBOARD_FAB2_LIB.BASEBOARD_FAB2(SCH_1):VR_PVCCIN_CPU1_PH5_BOOT

CAP_A  I17  C1C25  [CAP_A_0402V-0.1UF,16V,10%,X7R,A]
    1  VR_FET_SW_P12V_STBY_PVCCIN_CPU1      A  @BASEBOARD_FAB2_LIB.BASEBOARD_FAB2(SCH_1):VR_FET_SW_P12V_STBY_PVCCIN_CPU1
    2  GND                B  @BASEBOARD_FAB2_LIB.BASEBOARD_FAB2(SCH_1):GND

CAP_0402  I16  C1C26  [CAP_0402-1.0UF,16V,10%,X6S,D97A]
    1  VR_FET_SW_P12V_STBY_PVCCIN_CPU1      A  @BASEBOARD_FAB2_LIB.BASEBOARD_FAB2(SCH_1):VR_FET_SW_P12V_STBY_PVCCIN_CPU1
    2  GND                B  @BASEBOARD_FAB2_LIB.BASEBOARD_FAB2(SCH_1):GND

CAP  I78  C1D1   [CAP_0402LF-220PF,50V,10%,X7R,AA]
    2  VSENSE_PVCCIN_CPU1_N      B  @BASEBOARD_FAB2_LIB.BASEBOARD_FAB2(SCH_1):VSENSE_PVCCIN_CPU1_N
    1  VSENSE_PVCCIN_CPU1_AVSP      A  @BASEBOARD_FAB2_LIB.BASEBOARD_FAB2(SCH_1):VSENSE_PVCCIN_CPU1_AVSP

CAP_A  I22  C1D3   [CAP_A_0603V-22.0UF,4V,20%,X6S,A]
    1  PVCCIN_CPU1        A  @BASEBOARD_FAB2_LIB.BASEBOARD_FAB2(SCH_1):PVCCIN_CPU1
    2  GND                B  @BASEBOARD_FAB2_LIB.BASEBOARD_FAB2(SCH_1):GND

CAP_A  I47  C1D5   [CAP_A_0402V-1.0UF,6.3V,10%,X6SA]
    1  P5V_STBY           A  @BASEBOARD_FAB2_LIB.BASEBOARD_FAB2(SCH_1):P5V_STBY
    2  GND                B  @BASEBOARD_FAB2_LIB.BASEBOARD_FAB2(SCH_1):GND

CAP_0402  I46  C1D6   [CAP_0402-0.22UF,16V,10%,X7R,A3A]
    1  P5V_STBY           A  @BASEBOARD_FAB2_LIB.BASEBOARD_FAB2(SCH_1):P5V_STBY
    2  GND                B  @BASEBOARD_FAB2_LIB.BASEBOARD_FAB2(SCH_1):GND

CAP_0402  I50  C1D7   [CAP_0402-1.0UF,16V,10%,X6S,D97A]
    1  VR_PVCCIN_CPU1_PH4_VCIN      A  @BASEBOARD_FAB2_LIB.BASEBOARD_FAB2(SCH_1):VR_PVCCIN_CPU1_PH4_VCIN
    2  GND                B  @BASEBOARD_FAB2_LIB.BASEBOARD_FAB2(SCH_1):GND

CAP_A  I187  C1D9   [CAP_A_0402V-0.1UF,16V,10%,X7R,A]
    1  P12V_STBY          A  @BASEBOARD_FAB2_LIB.BASEBOARD_FAB2(SCH_1):P12V_STBY
    2  AGND_HSC           B  @BASEBOARD_FAB2_LIB.BASEBOARD_FAB2(SCH_1):AGND_HSC

CAP_0402  I48  C1D10  [CAP_0402-0.220UF,16V,10%,X7R,AA]
    2  VR_PVCCIN_CPU1_PH4_PHASE      B  @BASEBOARD_FAB2_LIB.BASEBOARD_FAB2(SCH_1):VR_PVCCIN_CPU1_PH4_PHASE
    1  VR_PVCCIN_CPU1_PH4_BOOT      A  @BASEBOARD_FAB2_LIB.BASEBOARD_FAB2(SCH_1):VR_PVCCIN_CPU1_PH4_BOOT

CAP_A  I53  C1D11  [CAP_A_0402V-0.1UF,16V,10%,X7R,A]
    1  FM_P12V_HOTSWAP0_EN      A  @BASEBOARD_FAB2_LIB.BASEBOARD_FAB2(SCH_1):FM_P12V_HOTSWAP0_EN
    2  AGND_HSC           B  @BASEBOARD_FAB2_LIB.BASEBOARD_FAB2(SCH_1):AGND_HSC

CAP_0402  I52  C1D12  [CAP_0402-1.0UF,16V,10%,X6S,D97A]
    1  VR_FET_SW_P12V_STBY_PVCCIN_CPU1      A  @BASEBOARD_FAB2_LIB.BASEBOARD_FAB2(SCH_1):VR_FET_SW_P12V_STBY_PVCCIN_CPU1
    2  GND                B  @BASEBOARD_FAB2_LIB.BASEBOARD_FAB2(SCH_1):GND

CAP_A  I51  C1D13  [CAP_A_0402V-0.1UF,16V,10%,X7R,A]
    1  VR_FET_SW_P12V_STBY_PVCCIN_CPU1      A  @BASEBOARD_FAB2_LIB.BASEBOARD_FAB2(SCH_1):VR_FET_SW_P12V_STBY_PVCCIN_CPU1
    2  GND                B  @BASEBOARD_FAB2_LIB.BASEBOARD_FAB2(SCH_1):GND

CAP_A  I9   C1D14  [CAP_A_0603V-22.0UF,4V,20%,X6S,A]
    1  PVCCIN_CPU1        A  @BASEBOARD_FAB2_LIB.BASEBOARD_FAB2(SCH_1):PVCCIN_CPU1
    2  GND                B  @BASEBOARD_FAB2_LIB.BASEBOARD_FAB2(SCH_1):GND

CAP_A  I39  C1D15  [CAP_A_0402V-1.0UF,6.3V,10%,X6SA]
    1  P5V_STBY           A  @BASEBOARD_FAB2_LIB.BASEBOARD_FAB2(SCH_1):P5V_STBY
    2  GND                B  @BASEBOARD_FAB2_LIB.BASEBOARD_FAB2(SCH_1):GND

CAP_0402  I38  C1D16  [CAP_0402-0.22UF,16V,10%,X7R,A3A]
    1  P5V_STBY           A  @BASEBOARD_FAB2_LIB.BASEBOARD_FAB2(SCH_1):P5V_STBY
    2  GND                B  @BASEBOARD_FAB2_LIB.BASEBOARD_FAB2(SCH_1):GND

CAP_0402  I43  C1D17  [CAP_0402-1.0UF,16V,10%,X6S,D97A]
    1  VR_PVCCIN_CPU1_PH3_VCIN      A  @BASEBOARD_FAB2_LIB.BASEBOARD_FAB2(SCH_1):VR_PVCCIN_CPU1_PH3_VCIN
    2  GND                B  @BASEBOARD_FAB2_LIB.BASEBOARD_FAB2(SCH_1):GND

CAP_0402  I119  C1D19  [CAP_0402-1.0UF,16V,10%,X6S,D97A]
    1  A_HSC_VCAP         A  @BASEBOARD_FAB2_LIB.BASEBOARD_FAB2(SCH_1):A_HSC_VCAP
    2  AGND_HSC           B  @BASEBOARD_FAB2_LIB.BASEBOARD_FAB2(SCH_1):AGND_HSC

CAP_0402  I40  C1D20  [CAP_0402-0.220UF,16V,10%,X7R,AA]
    2  VR_PVCCIN_CPU1_PH3_PHASE      B  @BASEBOARD_FAB2_LIB.BASEBOARD_FAB2(SCH_1):VR_PVCCIN_CPU1_PH3_PHASE
    1  VR_PVCCIN_CPU1_PH3_BOOT      A  @BASEBOARD_FAB2_LIB.BASEBOARD_FAB2(SCH_1):VR_PVCCIN_CPU1_PH3_BOOT

CAP_A  I121  C1D21  [CAP_A_0402V-0.1UF,16V,10%,X7R,A]
    1  A_HSC_PSET         A  @BASEBOARD_FAB2_LIB.BASEBOARD_FAB2(SCH_1):A_HSC_PSET
    2  AGND_HSC           B  @BASEBOARD_FAB2_LIB.BASEBOARD_FAB2(SCH_1):AGND_HSC

CAP_A  I42  C1D22  [CAP_A_0402V-0.1UF,16V,10%,EMPTA]
    2  A_HSC_MOP          B  @BASEBOARD_FAB2_LIB.BASEBOARD_FAB2(SCH_1):A_HSC_MOP
    1  A_HSC_MON          A  @BASEBOARD_FAB2_LIB.BASEBOARD_FAB2(SCH_1):A_HSC_MON

CAP_0402  I45  C1D23  [CAP_0402-1.0UF,16V,10%,X6S,D97A]
    1  VR_FET_SW_P12V_STBY_PVCCIN_CPU1      A  @BASEBOARD_FAB2_LIB.BASEBOARD_FAB2(SCH_1):VR_FET_SW_P12V_STBY_PVCCIN_CPU1
    2  GND                B  @BASEBOARD_FAB2_LIB.BASEBOARD_FAB2(SCH_1):GND

CAP_A  I42  C1D24  [CAP_A_0603V-22.0UF,4V,20%,X6S,A]
    1  PVCCIN_CPU1        A  @BASEBOARD_FAB2_LIB.BASEBOARD_FAB2(SCH_1):PVCCIN_CPU1
    2  GND                B  @BASEBOARD_FAB2_LIB.BASEBOARD_FAB2(SCH_1):GND

CAP_0402  I3   C1D25  [CAP_0402-1.0UF,16V,10%,X6S,D97A]
    1  P12V_HSC_VCC       A  @BASEBOARD_FAB2_LIB.BASEBOARD_FAB2(SCH_1):P12V_HSC_VCC
    2  AGND_HSC           B  @BASEBOARD_FAB2_LIB.BASEBOARD_FAB2(SCH_1):AGND_HSC

CAP_A  I107  C1D26  [CAP_A_0402V-0.1UF,16V,10%,X7R,A]
    1  A_HSC_UV           A  @BASEBOARD_FAB2_LIB.BASEBOARD_FAB2(SCH_1):A_HSC_UV
    2  AGND_HSC           B  @BASEBOARD_FAB2_LIB.BASEBOARD_FAB2(SCH_1):AGND_HSC

CAP_A  I7   C1D27  [CAP_A_0402V-0.1UF,16V,10%,X7R,A]
    1  A_HSC_OV           A  @BASEBOARD_FAB2_LIB.BASEBOARD_FAB2(SCH_1):A_HSC_OV
    2  AGND_HSC           B  @BASEBOARD_FAB2_LIB.BASEBOARD_FAB2(SCH_1):AGND_HSC

CAP_A  I44  C1D28  [CAP_A_0402V-0.1UF,16V,10%,X7R,A]
    1  VR_FET_SW_P12V_STBY_PVCCIN_CPU1      A  @BASEBOARD_FAB2_LIB.BASEBOARD_FAB2(SCH_1):VR_FET_SW_P12V_STBY_PVCCIN_CPU1
    2  GND                B  @BASEBOARD_FAB2_LIB.BASEBOARD_FAB2(SCH_1):GND

CAP_0402  I18  C1D32  [CAP_0402-1.0UF,16V,10%,X6S,D97A]
    1  VR_PVCCIN_CPU1_PH5_VCIN      A  @BASEBOARD_FAB2_LIB.BASEBOARD_FAB2(SCH_1):VR_PVCCIN_CPU1_PH5_VCIN
    2  GND                B  @BASEBOARD_FAB2_LIB.BASEBOARD_FAB2(SCH_1):GND

CAP_0402  I22  C1D33  [CAP_0402-0.22UF,16V,10%,X7R,A3A]
    1  P5V_STBY           A  @BASEBOARD_FAB2_LIB.BASEBOARD_FAB2(SCH_1):P5V_STBY
    2  GND                B  @BASEBOARD_FAB2_LIB.BASEBOARD_FAB2(SCH_1):GND

CAP_A  I41  C1D34  [CAP_A_0402V-0.1UF,16V,10%,X7R,A]
    1  VR_FET_SW_P12V_STBY_PVCCIN_CPU1      A  @BASEBOARD_FAB2_LIB.BASEBOARD_FAB2(SCH_1):VR_FET_SW_P12V_STBY_PVCCIN_CPU1
    2  GND                B  @BASEBOARD_FAB2_LIB.BASEBOARD_FAB2(SCH_1):GND

CAP_0402  I42  C1D35  [CAP_0402-1.0UF,16V,10%,X6S,D97A]
    1  VR_FET_SW_P12V_STBY_PVCCIN_CPU1      A  @BASEBOARD_FAB2_LIB.BASEBOARD_FAB2(SCH_1):VR_FET_SW_P12V_STBY_PVCCIN_CPU1
    2  GND                B  @BASEBOARD_FAB2_LIB.BASEBOARD_FAB2(SCH_1):GND

CAP_0402  I38  C1D36  [CAP_0402-0.220UF,16V,10%,X7R,AA]
    2  VR_PVCCIN_CPU1_PH2_PHASE      B  @BASEBOARD_FAB2_LIB.BASEBOARD_FAB2(SCH_1):VR_PVCCIN_CPU1_PH2_PHASE
    1  VR_PVCCIN_CPU1_PH2_BOOT      A  @BASEBOARD_FAB2_LIB.BASEBOARD_FAB2(SCH_1):VR_PVCCIN_CPU1_PH2_BOOT

CAP  I155  C1E2   [CAP_1206-0.068UF,50V,20%,X7R,1A]
    2  GND                B  @BASEBOARD_FAB2_LIB.BASEBOARD_FAB2(SCH_1):GND
    1  A_HSC_C            A  @BASEBOARD_FAB2_LIB.BASEBOARD_FAB2(SCH_1):A_HSC_C

CAP_A  I18  C1E3   [CAP_A_0603V-22.0UF,4V,20%,X6S,A]
    1  PVCCIN_CPU1        A  @BASEBOARD_FAB2_LIB.BASEBOARD_FAB2(SCH_1):PVCCIN_CPU1
    2  GND                B  @BASEBOARD_FAB2_LIB.BASEBOARD_FAB2(SCH_1):GND

CAP_A  I29  C1E6   [CAP_A_0402V-1.0UF,6.3V,10%,X6SA]
    1  P5V_STBY           A  @BASEBOARD_FAB2_LIB.BASEBOARD_FAB2(SCH_1):P5V_STBY
    2  GND                B  @BASEBOARD_FAB2_LIB.BASEBOARD_FAB2(SCH_1):GND

CAP_0402  I28  C1E7   [CAP_0402-0.22UF,16V,10%,X7R,A3A]
    1  P5V_STBY           A  @BASEBOARD_FAB2_LIB.BASEBOARD_FAB2(SCH_1):P5V_STBY
    2  GND                B  @BASEBOARD_FAB2_LIB.BASEBOARD_FAB2(SCH_1):GND

CAP_0402  I32  C1E8   [CAP_0402-1.0UF,16V,10%,X6S,D97A]
    1  VR_PVCCIN_CPU1_PH1_VCIN      A  @BASEBOARD_FAB2_LIB.BASEBOARD_FAB2(SCH_1):VR_PVCCIN_CPU1_PH1_VCIN
    2  GND                B  @BASEBOARD_FAB2_LIB.BASEBOARD_FAB2(SCH_1):GND

CAP_A  I58  C1E9   [CAP_A_0603V-22.0UF,4V,20%,X6S,A]
    1  PVCCIN_CPU1        A  @BASEBOARD_FAB2_LIB.BASEBOARD_FAB2(SCH_1):PVCCIN_CPU1
    2  GND                B  @BASEBOARD_FAB2_LIB.BASEBOARD_FAB2(SCH_1):GND

CAP_0402  I30  C1E11  [CAP_0402-0.220UF,16V,10%,X7R,AA]
    2  VR_PVCCIN_CPU1_PH1_PHASE      B  @BASEBOARD_FAB2_LIB.BASEBOARD_FAB2(SCH_1):VR_PVCCIN_CPU1_PH1_PHASE
    1  VR_PVCCIN_CPU1_PH1_BOOT      A  @BASEBOARD_FAB2_LIB.BASEBOARD_FAB2(SCH_1):VR_PVCCIN_CPU1_PH1_BOOT

CAP  I32  C1E12  [CAP_0805-10UF,16V,10%,X6S,C953A]
    1  P12V_PSU           A  @BASEBOARD_FAB2_LIB.BASEBOARD_FAB2(SCH_1):P12V_PSU
    2  GND                B  @BASEBOARD_FAB2_LIB.BASEBOARD_FAB2(SCH_1):GND

CAP_0402  I34  C1E13  [CAP_0402-1.0UF,16V,10%,X6S,D97A]
    1  VR_FET_SW_P12V_STBY_PVCCIN_CPU1      A  @BASEBOARD_FAB2_LIB.BASEBOARD_FAB2(SCH_1):VR_FET_SW_P12V_STBY_PVCCIN_CPU1
    2  GND                B  @BASEBOARD_FAB2_LIB.BASEBOARD_FAB2(SCH_1):GND

CAP_A  I33  C1E14  [CAP_A_0402V-0.1UF,16V,10%,X7R,A]
    1  VR_FET_SW_P12V_STBY_PVCCIN_CPU1      A  @BASEBOARD_FAB2_LIB.BASEBOARD_FAB2(SCH_1):VR_FET_SW_P12V_STBY_PVCCIN_CPU1
    2  GND                B  @BASEBOARD_FAB2_LIB.BASEBOARD_FAB2(SCH_1):GND

CAP  I35  C1E15  [CAP_0805-10UF,16V,10%,X6S,C953A]
    1  P12V_PSU           A  @BASEBOARD_FAB2_LIB.BASEBOARD_FAB2(SCH_1):P12V_PSU
    2  GND                B  @BASEBOARD_FAB2_LIB.BASEBOARD_FAB2(SCH_1):GND

CAP_A  I39  C1E16  [CAP_A_0402V-0.1UF,16V,10%,X7R,A]
    1  P12V_PSU           A  @BASEBOARD_FAB2_LIB.BASEBOARD_FAB2(SCH_1):P12V_PSU
    2  GND                B  @BASEBOARD_FAB2_LIB.BASEBOARD_FAB2(SCH_1):GND

CAP_A  I38  C1E17  [CAP_A_0402V-0.1UF,16V,10%,X7R,A]
    1  P12V_PSU           A  @BASEBOARD_FAB2_LIB.BASEBOARD_FAB2(SCH_1):P12V_PSU
    2  GND                B  @BASEBOARD_FAB2_LIB.BASEBOARD_FAB2(SCH_1):GND

CAPP  I37  C1E18  [CAPP_2626-270UF,16V,20%,OSCON,A]
    1  VR_FET_SW_P12V_STBY_PVCCIN_CPU1      A  @BASEBOARD_FAB2_LIB.BASEBOARD_FAB2(SCH_1):VR_FET_SW_P12V_STBY_PVCCIN_CPU1
    2  GND                B  @BASEBOARD_FAB2_LIB.BASEBOARD_FAB2(SCH_1):GND

CAP  I24  C1E19  [CAP_0402LF-47.0PF,50V,5%,EMPTYA]
    1  ISENSE_TMP421_2_DXP      A  @BASEBOARD_FAB2_LIB.BASEBOARD_FAB2(SCH_1):ISENSE_TMP421_2_DXP
    2  ISENSE_TMP421_2_DXN      B  @BASEBOARD_FAB2_LIB.BASEBOARD_FAB2(SCH_1):ISENSE_TMP421_2_DXN

CAP_A  I4   C1E20  [CAP_A_0402V-0.1UF,16V,10%,X7R,A]
    1  P12V_FAN           A  @BASEBOARD_FAB2_LIB.BASEBOARD_FAB2(SCH_1):P12V_FAN
    2  GND                B  @BASEBOARD_FAB2_LIB.BASEBOARD_FAB2(SCH_1):GND

CAP  I3   C1E21  [CAP_0805-10UF,16V,10%,X6S,C953A]
    1  P12V_FAN           A  @BASEBOARD_FAB2_LIB.BASEBOARD_FAB2(SCH_1):P12V_FAN
    2  GND                B  @BASEBOARD_FAB2_LIB.BASEBOARD_FAB2(SCH_1):GND

CAP_A  I113  C1E22  [CAP_A_0402V-0.1UF,16V,10%,X7R,A]
    1  P3V3_STBY          A  @BASEBOARD_FAB2_LIB.BASEBOARD_FAB2(SCH_1):P3V3_STBY
    2  GND                B  @BASEBOARD_FAB2_LIB.BASEBOARD_FAB2(SCH_1):GND

CAP_A  I37  C1E23  [CAP_A_0402V-1.0UF,6.3V,10%,X6SA]
    1  P5V_STBY           A  @BASEBOARD_FAB2_LIB.BASEBOARD_FAB2(SCH_1):P5V_STBY
    2  GND                B  @BASEBOARD_FAB2_LIB.BASEBOARD_FAB2(SCH_1):GND

CAP_0402  I40  C1E24  [CAP_0402-1.0UF,16V,10%,X6S,D97A]
    1  VR_PVCCIN_CPU1_PH2_VCIN      A  @BASEBOARD_FAB2_LIB.BASEBOARD_FAB2(SCH_1):VR_PVCCIN_CPU1_PH2_VCIN
    2  GND                B  @BASEBOARD_FAB2_LIB.BASEBOARD_FAB2(SCH_1):GND

CAP_0402  I36  C1E25  [CAP_0402-0.22UF,16V,10%,X7R,A3A]
    1  P5V_STBY           A  @BASEBOARD_FAB2_LIB.BASEBOARD_FAB2(SCH_1):P5V_STBY
    2  GND                B  @BASEBOARD_FAB2_LIB.BASEBOARD_FAB2(SCH_1):GND

CAP_0402  I162  C1F2   [CAP_0402-0.22UF,16V,10%,X7R,A3A]
    2  P3E_CPU1_PE3_MP_TXP<7>      B  @BASEBOARD_FAB2_LIB.BASEBOARD_FAB2(SCH_1):P3E_CPU1_PE3_MP_TXP<7>
    1  P3E_CPU1_PE3_MP_C_TXP<7>      A  @BASEBOARD_FAB2_LIB.BASEBOARD_FAB2(SCH_1):P3E_CPU1_PE3_MP_C_TXP<7>

CAP_0402  I167  C1F3   [CAP_0402-0.22UF,16V,10%,X7R,A3A]
    2  P3E_CPU1_PE3_MP_TXN<7>      B  @BASEBOARD_FAB2_LIB.BASEBOARD_FAB2(SCH_1):P3E_CPU1_PE3_MP_TXN<7>
    1  P3E_CPU1_PE3_MP_C_TXN<7>      A  @BASEBOARD_FAB2_LIB.BASEBOARD_FAB2(SCH_1):P3E_CPU1_PE3_MP_C_TXN<7>

CAP_0402  I160  C1F4   [CAP_0402-0.22UF,16V,10%,X7R,A3A]
    2  P3E_CPU1_PE3_MP_TXN<6>      B  @BASEBOARD_FAB2_LIB.BASEBOARD_FAB2(SCH_1):P3E_CPU1_PE3_MP_TXN<6>
    1  P3E_CPU1_PE3_MP_C_TXN<6>      A  @BASEBOARD_FAB2_LIB.BASEBOARD_FAB2(SCH_1):P3E_CPU1_PE3_MP_C_TXN<6>

CAP_0402  I161  C1F5   [CAP_0402-0.22UF,16V,10%,X7R,A3A]
    2  P3E_CPU1_PE3_MP_TXP<6>      B  @BASEBOARD_FAB2_LIB.BASEBOARD_FAB2(SCH_1):P3E_CPU1_PE3_MP_TXP<6>
    1  P3E_CPU1_PE3_MP_C_TXP<6>      A  @BASEBOARD_FAB2_LIB.BASEBOARD_FAB2(SCH_1):P3E_CPU1_PE3_MP_C_TXP<6>

CAP_0402  I165  C1F6   [CAP_0402-0.22UF,16V,10%,X7R,A3A]
    2  P3E_CPU1_PE3_MP_TXP<5>      B  @BASEBOARD_FAB2_LIB.BASEBOARD_FAB2(SCH_1):P3E_CPU1_PE3_MP_TXP<5>
    1  P3E_CPU1_PE3_MP_C_TXP<5>      A  @BASEBOARD_FAB2_LIB.BASEBOARD_FAB2(SCH_1):P3E_CPU1_PE3_MP_C_TXP<5>

CAPP  I85  C1F7   [CAPP_4040LF-470UF,16V,20%,ALUMA]
    1  P12V_STBY          A  @BASEBOARD_FAB2_LIB.BASEBOARD_FAB2(SCH_1):P12V_STBY
    2  GND                B  @BASEBOARD_FAB2_LIB.BASEBOARD_FAB2(SCH_1):GND

CAP_0402  I170  C1F8   [CAP_0402-0.22UF,16V,10%,X7R,A3A]
    2  P3E_CPU1_PE3_MP_TXN<5>      B  @BASEBOARD_FAB2_LIB.BASEBOARD_FAB2(SCH_1):P3E_CPU1_PE3_MP_TXN<5>
    1  P3E_CPU1_PE3_MP_C_TXN<5>      A  @BASEBOARD_FAB2_LIB.BASEBOARD_FAB2(SCH_1):P3E_CPU1_PE3_MP_C_TXN<5>

CAP_A  I46  C1F9   [CAP_A_0402V-0.01UF,25V,10%,X7RA]
    2  GND                B  @BASEBOARD_FAB2_LIB.BASEBOARD_FAB2(SCH_1):GND
    1  FAN_TACH0          A  @BASEBOARD_FAB2_LIB.BASEBOARD_FAB2(SCH_1):FAN_TACH0

CAP_0402  I164  C1F10  [CAP_0402-0.22UF,16V,10%,X7R,A3A]
    2  P3E_CPU1_PE3_MP_TXN<4>      B  @BASEBOARD_FAB2_LIB.BASEBOARD_FAB2(SCH_1):P3E_CPU1_PE3_MP_TXN<4>
    1  P3E_CPU1_PE3_MP_C_TXN<4>      A  @BASEBOARD_FAB2_LIB.BASEBOARD_FAB2(SCH_1):P3E_CPU1_PE3_MP_C_TXN<4>

CAP_0402  I169  C1F11  [CAP_0402-0.22UF,16V,10%,X7R,A3A]
    2  P3E_CPU1_PE3_MP_TXP<4>      B  @BASEBOARD_FAB2_LIB.BASEBOARD_FAB2(SCH_1):P3E_CPU1_PE3_MP_TXP<4>
    1  P3E_CPU1_PE3_MP_C_TXP<4>      A  @BASEBOARD_FAB2_LIB.BASEBOARD_FAB2(SCH_1):P3E_CPU1_PE3_MP_C_TXP<4>

CAP_0402  I168  C1F12  [CAP_0402-0.22UF,16V,10%,X7R,A3A]
    2  P3E_CPU1_PE3_MP_TXP<3>      B  @BASEBOARD_FAB2_LIB.BASEBOARD_FAB2(SCH_1):P3E_CPU1_PE3_MP_TXP<3>
    1  P3E_CPU1_PE3_MP_C_TXP<3>      A  @BASEBOARD_FAB2_LIB.BASEBOARD_FAB2(SCH_1):P3E_CPU1_PE3_MP_C_TXP<3>

CAP_0402  I163  C1F13  [CAP_0402-0.22UF,16V,10%,X7R,A3A]
    2  P3E_CPU1_PE3_MP_TXN<3>      B  @BASEBOARD_FAB2_LIB.BASEBOARD_FAB2(SCH_1):P3E_CPU1_PE3_MP_TXN<3>
    1  P3E_CPU1_PE3_MP_C_TXN<3>      A  @BASEBOARD_FAB2_LIB.BASEBOARD_FAB2(SCH_1):P3E_CPU1_PE3_MP_C_TXN<3>

CAP_0402  I175  C1F14  [CAP_0402-0.22UF,16V,10%,X7R,A3A]
    2  P3E_CPU1_PE3_MP_TXP<2>      B  @BASEBOARD_FAB2_LIB.BASEBOARD_FAB2(SCH_1):P3E_CPU1_PE3_MP_TXP<2>
    1  P3E_CPU1_PE3_MP_C_TXP<2>      A  @BASEBOARD_FAB2_LIB.BASEBOARD_FAB2(SCH_1):P3E_CPU1_PE3_MP_C_TXP<2>

CAP_0402  I174  C1F15  [CAP_0402-0.22UF,16V,10%,X7R,A3A]
    2  P3E_CPU1_PE3_MP_TXN<2>      B  @BASEBOARD_FAB2_LIB.BASEBOARD_FAB2(SCH_1):P3E_CPU1_PE3_MP_TXN<2>
    1  P3E_CPU1_PE3_MP_C_TXN<2>      A  @BASEBOARD_FAB2_LIB.BASEBOARD_FAB2(SCH_1):P3E_CPU1_PE3_MP_C_TXN<2>

CAP_0402  I172  C1F16  [CAP_0402-0.22UF,16V,10%,X7R,A3A]
    2  P3E_CPU1_PE3_MP_TXN<1>      B  @BASEBOARD_FAB2_LIB.BASEBOARD_FAB2(SCH_1):P3E_CPU1_PE3_MP_TXN<1>
    1  P3E_CPU1_PE3_MP_C_TXN<1>      A  @BASEBOARD_FAB2_LIB.BASEBOARD_FAB2(SCH_1):P3E_CPU1_PE3_MP_C_TXN<1>

CAP_0402  I173  C1F17  [CAP_0402-0.22UF,16V,10%,X7R,A3A]
    2  P3E_CPU1_PE3_MP_TXP<1>      B  @BASEBOARD_FAB2_LIB.BASEBOARD_FAB2(SCH_1):P3E_CPU1_PE3_MP_TXP<1>
    1  P3E_CPU1_PE3_MP_C_TXP<1>      A  @BASEBOARD_FAB2_LIB.BASEBOARD_FAB2(SCH_1):P3E_CPU1_PE3_MP_C_TXP<1>

CAP_0402  I171  C1F18  [CAP_0402-0.22UF,16V,10%,X7R,A3A]
    2  P3E_CPU1_PE3_MP_TXP<0>      B  @BASEBOARD_FAB2_LIB.BASEBOARD_FAB2(SCH_1):P3E_CPU1_PE3_MP_TXP<0>
    1  P3E_CPU1_PE3_MP_C_TXP<0>      A  @BASEBOARD_FAB2_LIB.BASEBOARD_FAB2(SCH_1):P3E_CPU1_PE3_MP_C_TXP<0>

CAP_A  I8   C1F19  [CAP_A_0402V-0.01UF,25V,10%,X7RA]
    1  M_G_CPU_VREF       A  @BASEBOARD_FAB2_LIB.BASEBOARD_FAB2(SCH_1):M_G_CPU_VREF
    2  GND                B  @BASEBOARD_FAB2_LIB.BASEBOARD_FAB2(SCH_1):GND

CAP_0402  I166  C1F20  [CAP_0402-0.22UF,16V,10%,X7R,A3A]
    2  P3E_CPU1_PE3_MP_TXN<0>      B  @BASEBOARD_FAB2_LIB.BASEBOARD_FAB2(SCH_1):P3E_CPU1_PE3_MP_TXN<0>
    1  P3E_CPU1_PE3_MP_C_TXN<0>      A  @BASEBOARD_FAB2_LIB.BASEBOARD_FAB2(SCH_1):P3E_CPU1_PE3_MP_C_TXN<0>

CAP_A  I73  C1F21  [CAP_A_0402V-1.0UF,6.3V,10%,X6SA]
    1  P5V_STBY           A  @BASEBOARD_FAB2_LIB.BASEBOARD_FAB2(SCH_1):P5V_STBY
    2  GND                B  @BASEBOARD_FAB2_LIB.BASEBOARD_FAB2(SCH_1):GND

CAP_A  I181  C1F22  [CAP_A_0402V-0.01UF,25V,10%,X7RA]
    1  M_G_VREF           A  @BASEBOARD_FAB2_LIB.BASEBOARD_FAB2(SCH_1):M_G_VREF
    2  GND                B  @BASEBOARD_FAB2_LIB.BASEBOARD_FAB2(SCH_1):GND

CAP_0402  I75  C1F26  [CAP_0402-0.220UF,16V,10%,X7R,AA]
    2  VR_PVDDQ_GHJ_PH2_PHASE      B  @BASEBOARD_FAB2_LIB.BASEBOARD_FAB2(SCH_1):VR_PVDDQ_GHJ_PH2_PHASE
    1  VR_PVDDQ_GHJ_PH2_BOOT      A  @BASEBOARD_FAB2_LIB.BASEBOARD_FAB2(SCH_1):VR_PVDDQ_GHJ_PH2_BOOT

CAP_0402  I48  C1F27  [CAP_0402-1.0UF,16V,10%,X6S,D97A]
    1  VR_FET_SW_P12V_STBY_PVDDQ_GHJ      A  @BASEBOARD_FAB2_LIB.BASEBOARD_FAB2(SCH_1):VR_FET_SW_P12V_STBY_PVDDQ_GHJ
    2  GND                B  @BASEBOARD_FAB2_LIB.BASEBOARD_FAB2(SCH_1):GND

CAP_A  I78  C1F28  [CAP_A_0402V-0.1UF,16V,10%,X7R,A]
    1  VR_FET_SW_P12V_STBY_PVDDQ_GHJ      A  @BASEBOARD_FAB2_LIB.BASEBOARD_FAB2(SCH_1):VR_FET_SW_P12V_STBY_PVDDQ_GHJ
    2  GND                B  @BASEBOARD_FAB2_LIB.BASEBOARD_FAB2(SCH_1):GND

CAP  I194  C1G2   [CAP_1210-47UF,16V,20%,X6S,D384A]
    1  VR_FET_SW_P12V_STBY_PVDDQ_GHJ      A  @BASEBOARD_FAB2_LIB.BASEBOARD_FAB2(SCH_1):VR_FET_SW_P12V_STBY_PVDDQ_GHJ
    2  GND                B  @BASEBOARD_FAB2_LIB.BASEBOARD_FAB2(SCH_1):GND

CAP_A  I53  C1G4   [CAP_A_0402V-1.0UF,6.3V,10%,X6SA]
    1  P5V_STBY           A  @BASEBOARD_FAB2_LIB.BASEBOARD_FAB2(SCH_1):P5V_STBY
    2  GND                B  @BASEBOARD_FAB2_LIB.BASEBOARD_FAB2(SCH_1):GND

CAP_0402  I54  C1G5   [CAP_0402-0.22UF,16V,10%,X7R,A3A]
    1  P5V_STBY           A  @BASEBOARD_FAB2_LIB.BASEBOARD_FAB2(SCH_1):P5V_STBY
    2  GND                B  @BASEBOARD_FAB2_LIB.BASEBOARD_FAB2(SCH_1):GND

CAP_0402  I50  C1G6   [CAP_0402-1.0UF,16V,10%,X6S,D97A]
    1  VR_PVDDQ_GHJ_PH1_VCIN      A  @BASEBOARD_FAB2_LIB.BASEBOARD_FAB2(SCH_1):VR_PVDDQ_GHJ_PH1_VCIN
    2  GND                B  @BASEBOARD_FAB2_LIB.BASEBOARD_FAB2(SCH_1):GND

CAP  I195  C1G7   [CAP_1210-47UF,16V,20%,X6S,D384A]
    1  VR_FET_SW_P12V_STBY_PVDDQ_GHJ      A  @BASEBOARD_FAB2_LIB.BASEBOARD_FAB2(SCH_1):VR_FET_SW_P12V_STBY_PVDDQ_GHJ
    2  GND                B  @BASEBOARD_FAB2_LIB.BASEBOARD_FAB2(SCH_1):GND

CAP_A  I26  C1G8   [CAP_A_0402V-0.01UF,25V,10%,X7RA]
    1  M_H_CPU_VREF       A  @BASEBOARD_FAB2_LIB.BASEBOARD_FAB2(SCH_1):M_H_CPU_VREF
    2  GND                B  @BASEBOARD_FAB2_LIB.BASEBOARD_FAB2(SCH_1):GND

CAP_A  I3   C1G10  [CAP_A_0402V-0.01UF,25V,10%,X7RA]
    1  M_H_VREF           A  @BASEBOARD_FAB2_LIB.BASEBOARD_FAB2(SCH_1):M_H_VREF
    2  GND                B  @BASEBOARD_FAB2_LIB.BASEBOARD_FAB2(SCH_1):GND

CAP_0402  I44  C1G11  [CAP_0402-0.220UF,16V,10%,X7R,AA]
    2  VR_PVDDQ_GHJ_PH1_PHASE      B  @BASEBOARD_FAB2_LIB.BASEBOARD_FAB2(SCH_1):VR_PVDDQ_GHJ_PH1_PHASE
    1  VR_PVDDQ_GHJ_PH1_BOOT      A  @BASEBOARD_FAB2_LIB.BASEBOARD_FAB2(SCH_1):VR_PVDDQ_GHJ_PH1_BOOT

CAP  I193  C1G12  [CAP_1210-47UF,16V,20%,X6S,D384A]
    1  VR_FET_SW_P12V_STBY_PVDDQ_GHJ      A  @BASEBOARD_FAB2_LIB.BASEBOARD_FAB2(SCH_1):VR_FET_SW_P12V_STBY_PVDDQ_GHJ
    2  GND                B  @BASEBOARD_FAB2_LIB.BASEBOARD_FAB2(SCH_1):GND

CAP_0402  I79  C1G13  [CAP_0402-1.0UF,16V,10%,X6S,D97A]
    1  VR_FET_SW_P12V_STBY_PVDDQ_GHJ      A  @BASEBOARD_FAB2_LIB.BASEBOARD_FAB2(SCH_1):VR_FET_SW_P12V_STBY_PVDDQ_GHJ
    2  GND                B  @BASEBOARD_FAB2_LIB.BASEBOARD_FAB2(SCH_1):GND

CAP_A  I51  C1G14  [CAP_A_0402V-0.1UF,16V,10%,X7R,A]
    1  VR_FET_SW_P12V_STBY_PVDDQ_GHJ      A  @BASEBOARD_FAB2_LIB.BASEBOARD_FAB2(SCH_1):VR_FET_SW_P12V_STBY_PVDDQ_GHJ
    2  GND                B  @BASEBOARD_FAB2_LIB.BASEBOARD_FAB2(SCH_1):GND

CAP  I192  C1G15  [CAP_1210-47UF,16V,20%,X6S,D384A]
    1  VR_FET_SW_P12V_STBY_PVDDQ_GHJ      A  @BASEBOARD_FAB2_LIB.BASEBOARD_FAB2(SCH_1):VR_FET_SW_P12V_STBY_PVDDQ_GHJ
    2  GND                B  @BASEBOARD_FAB2_LIB.BASEBOARD_FAB2(SCH_1):GND

CAP  I39  C1G16  [CAP_0402LF-220PF,50V,10%,X7R,AA]
    2  VSENSE_PVDDQ_GHJ_N      B  @BASEBOARD_FAB2_LIB.BASEBOARD_FAB2(SCH_1):VSENSE_PVDDQ_GHJ_N
    1  VR_PVDDQ_GHJ_AVSP      A  @BASEBOARD_FAB2_LIB.BASEBOARD_FAB2(SCH_1):VR_PVDDQ_GHJ_AVSP

CAP  I6   C1G17  [CAP_0805LF-22UF,4V,20%,X6S,C95A]
    1  PVDDQ_GHJ          A  @BASEBOARD_FAB2_LIB.BASEBOARD_FAB2(SCH_1):PVDDQ_GHJ
    2  GND                B  @BASEBOARD_FAB2_LIB.BASEBOARD_FAB2(SCH_1):GND

CAP_A  I42  C1G18  [CAP_A_0402V-0.01UF,25V,10%,X7RA]
    1  M_J_CPU_VREF       A  @BASEBOARD_FAB2_LIB.BASEBOARD_FAB2(SCH_1):M_J_CPU_VREF
    2  GND                B  @BASEBOARD_FAB2_LIB.BASEBOARD_FAB2(SCH_1):GND

CAP_A  I180  C1G19  [CAP_A_0402V-0.01UF,25V,10%,X7RA]
    1  M_J_VREF           A  @BASEBOARD_FAB2_LIB.BASEBOARD_FAB2(SCH_1):M_J_VREF
    2  GND                B  @BASEBOARD_FAB2_LIB.BASEBOARD_FAB2(SCH_1):GND

CAP  I68  C1G20  [CAP_0805LF-22UF,4V,20%,X6S,C95A]
    1  PVDDQ_GHJ          A  @BASEBOARD_FAB2_LIB.BASEBOARD_FAB2(SCH_1):PVDDQ_GHJ
    2  GND                B  @BASEBOARD_FAB2_LIB.BASEBOARD_FAB2(SCH_1):GND

CAP  I80  C1G21  [CAP_0402LF-1000PF,50V,10%,X7R,A]
    1  PWRGD_PVDDQ_GHJ_R      A  @BASEBOARD_FAB2_LIB.BASEBOARD_FAB2(SCH_1):PWRGD_PVDDQ_GHJ_R
    2  GND                B  @BASEBOARD_FAB2_LIB.BASEBOARD_FAB2(SCH_1):GND

CAP_A  I44  C1G22  [CAP_A_0402V-0.1UF,16V,10%,X7R,A]
    1  VR_PVDDQ_GHJ_VD12      A  @BASEBOARD_FAB2_LIB.BASEBOARD_FAB2(SCH_1):VR_PVDDQ_GHJ_VD12
    2  GND                B  @BASEBOARD_FAB2_LIB.BASEBOARD_FAB2(SCH_1):GND

CAP_A  I41  C1G23  [CAP_A_0402V-1.0UF,6.3V,10%,X6SA]
    1  VR_PVDDQ_GHJ_VD12      A  @BASEBOARD_FAB2_LIB.BASEBOARD_FAB2(SCH_1):VR_PVDDQ_GHJ_VD12
    2  GND                B  @BASEBOARD_FAB2_LIB.BASEBOARD_FAB2(SCH_1):GND

CAP  I36  C1G24  [CAP_0402LF-220PF,50V,10%,X7R,AA]
    2  GND                B  @BASEBOARD_FAB2_LIB.BASEBOARD_FAB2(SCH_1):GND
    1  A_TSENSE_PVDDQ_GHJ      A  @BASEBOARD_FAB2_LIB.BASEBOARD_FAB2(SCH_1):A_TSENSE_PVDDQ_GHJ

CAP_A  I27  C1G25  [CAP_A_0402V-0.1UF,16V,10%,X7R,A]
    1  VR_PVDDQ_GHJ_VDD      A  @BASEBOARD_FAB2_LIB.BASEBOARD_FAB2(SCH_1):VR_PVDDQ_GHJ_VDD
    2  GND                B  @BASEBOARD_FAB2_LIB.BASEBOARD_FAB2(SCH_1):GND

CAP  I59  C1G26  [CAP_0402LF-1000PF,50V,10%,X7R,A]
    1  VR_PVDDQ_GHJ_VINSEN      A  @BASEBOARD_FAB2_LIB.BASEBOARD_FAB2(SCH_1):VR_PVDDQ_GHJ_VINSEN
    2  GND                B  @BASEBOARD_FAB2_LIB.BASEBOARD_FAB2(SCH_1):GND

CAP_A  I25  C1G27  [CAP_A_0402V-1.0UF,6.3V,10%,X6SA]
    1  VR_PVDDQ_GHJ_VDD      A  @BASEBOARD_FAB2_LIB.BASEBOARD_FAB2(SCH_1):VR_PVDDQ_GHJ_VDD
    2  GND                B  @BASEBOARD_FAB2_LIB.BASEBOARD_FAB2(SCH_1):GND

CAP_0402  I77  C1G28  [CAP_0402-1.0UF,16V,10%,X6S,D97A]
    1  VR_PVDDQ_GHJ_PH2_VCIN      A  @BASEBOARD_FAB2_LIB.BASEBOARD_FAB2(SCH_1):VR_PVDDQ_GHJ_PH2_VCIN
    2  GND                B  @BASEBOARD_FAB2_LIB.BASEBOARD_FAB2(SCH_1):GND

CAP_0402  I72  C1G29  [CAP_0402-0.22UF,16V,10%,X7R,A3A]
    1  P5V_STBY           A  @BASEBOARD_FAB2_LIB.BASEBOARD_FAB2(SCH_1):P5V_STBY
    2  GND                B  @BASEBOARD_FAB2_LIB.BASEBOARD_FAB2(SCH_1):GND

CAP_0402  I136  C1L1   [CAP_0402-1.0UF,16V,10%,X6S,D97A]
    1  P3V3_STBY          A  @BASEBOARD_FAB2_LIB.BASEBOARD_FAB2(SCH_1):P3V3_STBY
    2  GND                B  @BASEBOARD_FAB2_LIB.BASEBOARD_FAB2(SCH_1):GND

CAP_A  I9   C1L2   [CAP_A_0402V-0.01UF,25V,10%,X7RA]
    2  SATA6G_TX_DP<0>      B  @BASEBOARD_FAB2_LIB.BASEBOARD_FAB2(SCH_1):SATA6G_TX_DP<0>
    1  SATA6G_P8_TX_C_DP      A  @BASEBOARD_FAB2_LIB.BASEBOARD_FAB2(SCH_1):SATA6G_P8_TX_C_DP

CAP_A  I8   C1L3   [CAP_A_0402V-0.01UF,25V,10%,X7RA]
    2  SATA6G_TX_DN<0>      B  @BASEBOARD_FAB2_LIB.BASEBOARD_FAB2(SCH_1):SATA6G_TX_DN<0>
    1  SATA6G_P8_TX_C_DN      A  @BASEBOARD_FAB2_LIB.BASEBOARD_FAB2(SCH_1):SATA6G_P8_TX_C_DN

CAP_A  I64  C1L4   [CAP_A_0402V-0.1UF,16V,10%,X7R,A]
    1  P5V_STBY           A  @BASEBOARD_FAB2_LIB.BASEBOARD_FAB2(SCH_1):P5V_STBY
    2  GND                B  @BASEBOARD_FAB2_LIB.BASEBOARD_FAB2(SCH_1):GND

CAP_A  I30  C1L5   [CAP_A_0402V-1.0UF,6.3V,10%,X6SA]
    1  P1V05_PCH_STBY      A  @BASEBOARD_FAB2_LIB.BASEBOARD_FAB2(SCH_1):P1V05_PCH_STBY
    2  GND                B  @BASEBOARD_FAB2_LIB.BASEBOARD_FAB2(SCH_1):GND

CAP_A  I13  C1L6   [CAP_A_0402V-0.01UF,25V,10%,X7RA]
    2  SATA6G_TX_DP<1>      B  @BASEBOARD_FAB2_LIB.BASEBOARD_FAB2(SCH_1):SATA6G_TX_DP<1>
    1  SATA6G_P9_TX_C_DP      A  @BASEBOARD_FAB2_LIB.BASEBOARD_FAB2(SCH_1):SATA6G_P9_TX_C_DP

CAP_A  I12  C1L7   [CAP_A_0402V-0.01UF,25V,10%,X7RA]
    2  SATA6G_TX_DN<1>      B  @BASEBOARD_FAB2_LIB.BASEBOARD_FAB2(SCH_1):SATA6G_TX_DN<1>
    1  SATA6G_P9_TX_C_DN      A  @BASEBOARD_FAB2_LIB.BASEBOARD_FAB2(SCH_1):SATA6G_P9_TX_C_DN

CAP_A  I14  C1L8   [CAP_A_0402V-0.1UF,16V,10%,X7R,A]
    1  XDP_PWRGD_RST_N      A  @BASEBOARD_FAB2_LIB.BASEBOARD_FAB2(SCH_1):XDP_PWRGD_RST_N
    2  GND                B  @BASEBOARD_FAB2_LIB.BASEBOARD_FAB2(SCH_1):GND

CAP_A  I38  C1L9   [CAP_A_0402V-0.1UF,16V,10%,X7R,A]
    1  P3V3_STBY          A  @BASEBOARD_FAB2_LIB.BASEBOARD_FAB2(SCH_1):P3V3_STBY
    2  GND                B  @BASEBOARD_FAB2_LIB.BASEBOARD_FAB2(SCH_1):GND

CAP_A  I19  C1L10  [CAP_A_0402V-1.0UF,6.3V,10%,X6SA]
    2  GND                B  @BASEBOARD_FAB2_LIB.BASEBOARD_FAB2(SCH_1):GND
    1  FP_RST_BTN_R_N      A  @BASEBOARD_FAB2_LIB.BASEBOARD_FAB2(SCH_1):FP_RST_BTN_R_N

CAP_A  I87  C1L11  [CAP_A_0402V-0.1UF,16V,10%,X7R,A]
    1  P3V3_STBY          A  @BASEBOARD_FAB2_LIB.BASEBOARD_FAB2(SCH_1):P3V3_STBY
    2  GND                B  @BASEBOARD_FAB2_LIB.BASEBOARD_FAB2(SCH_1):GND

CAP_A  I19  C1L12  [CAP_A_0402V-0.01UF,25V,10%,X7RA]
    2  SATA6G_TX_DP<2>      B  @BASEBOARD_FAB2_LIB.BASEBOARD_FAB2(SCH_1):SATA6G_TX_DP<2>
    1  SATA6G_P10_TX_C_DP      A  @BASEBOARD_FAB2_LIB.BASEBOARD_FAB2(SCH_1):SATA6G_P10_TX_C_DP

CAP_A  I14  C1L13  [CAP_A_0402V-0.01UF,25V,10%,X7RA]
    2  SATA6G_TX_DN<2>      B  @BASEBOARD_FAB2_LIB.BASEBOARD_FAB2(SCH_1):SATA6G_TX_DN<2>
    1  SATA6G_P10_TX_C_DN      A  @BASEBOARD_FAB2_LIB.BASEBOARD_FAB2(SCH_1):SATA6G_P10_TX_C_DN

CAP_A  I20  C1L14  [CAP_A_0402V-0.01UF,25V,10%,X7RA]
    2  SATA6G_TX_DP<3>      B  @BASEBOARD_FAB2_LIB.BASEBOARD_FAB2(SCH_1):SATA6G_TX_DP<3>
    1  SATA6G_P11_TX_C_DP      A  @BASEBOARD_FAB2_LIB.BASEBOARD_FAB2(SCH_1):SATA6G_P11_TX_C_DP

CAP_A  I18  C1L15  [CAP_A_0402V-0.01UF,25V,10%,X7RA]
    2  SATA6G_TX_DN<3>      B  @BASEBOARD_FAB2_LIB.BASEBOARD_FAB2(SCH_1):SATA6G_TX_DN<3>
    1  SATA6G_P11_TX_C_DN      A  @BASEBOARD_FAB2_LIB.BASEBOARD_FAB2(SCH_1):SATA6G_P11_TX_C_DN

CAP_A  I81  C1L16  [CAP_A_0402V-0.1UF,16V,10%,X7R,A]
    1  P3V3               A  @BASEBOARD_FAB2_LIB.BASEBOARD_FAB2(SCH_1):P3V3
    2  GND                B  @BASEBOARD_FAB2_LIB.BASEBOARD_FAB2(SCH_1):GND

CAP_A  I37  C1L17  [CAP_A_0402V-0.1UF,16V,10%,X7R,A]
    1  P3V3_STBY          A  @BASEBOARD_FAB2_LIB.BASEBOARD_FAB2(SCH_1):P3V3_STBY
    2  GND                B  @BASEBOARD_FAB2_LIB.BASEBOARD_FAB2(SCH_1):GND

CAP_A  I11  C1L18  [CAP_A_0402V-1.0UF,6.3V,10%,X6SA]
    2  GND                B  @BASEBOARD_FAB2_LIB.BASEBOARD_FAB2(SCH_1):GND
    1  FP_PWR_BTN_R1_N      A  @BASEBOARD_FAB2_LIB.BASEBOARD_FAB2(SCH_1):FP_PWR_BTN_R1_N

CAP_0402  I140  C1L19  [CAP_0402-1.0UF,16V,10%,X6S,D97A]
    1  P3V3_STBY          A  @BASEBOARD_FAB2_LIB.BASEBOARD_FAB2(SCH_1):P3V3_STBY
    2  GND                B  @BASEBOARD_FAB2_LIB.BASEBOARD_FAB2(SCH_1):GND

CAP_A  I267  C1L20  [CAP_A_0402V-0.01UF,25V,10%,X7RA]
    1  P3V3_STBY          A  @BASEBOARD_FAB2_LIB.BASEBOARD_FAB2(SCH_1):P3V3_STBY
    2  GND                B  @BASEBOARD_FAB2_LIB.BASEBOARD_FAB2(SCH_1):GND

CAP_A  I64  C1M1   [CAP_A_0402V-0.1UF,16V,10%,X7R,A]
    1  USB3_P01_TXP       A  @BASEBOARD_FAB2_LIB.BASEBOARD_FAB2(SCH_1):USB3_P01_TXP
    2  USB3_P01_C_TXP      B  @BASEBOARD_FAB2_LIB.BASEBOARD_FAB2(SCH_1):USB3_P01_C_TXP

CAP_A  I63  C1M2   [CAP_A_0402V-0.1UF,16V,10%,X7R,A]
    1  USB3_P01_TXN       A  @BASEBOARD_FAB2_LIB.BASEBOARD_FAB2(SCH_1):USB3_P01_TXN
    2  USB3_P01_C_TXN      B  @BASEBOARD_FAB2_LIB.BASEBOARD_FAB2(SCH_1):USB3_P01_C_TXN

CAP_A  I20  C1M3   [CAP_A_0402V-1.0UF,6.3V,10%,X6SA]
    1  P3V3               A  @BASEBOARD_FAB2_LIB.BASEBOARD_FAB2(SCH_1):P3V3
    2  GND                B  @BASEBOARD_FAB2_LIB.BASEBOARD_FAB2(SCH_1):GND

CAP  I7   C1M4   [CAP_0402LF-47.0PF,50V,5%,EMPTYA]
    1  ISENSE_TMP421_1_DXP      A  @BASEBOARD_FAB2_LIB.BASEBOARD_FAB2(SCH_1):ISENSE_TMP421_1_DXP
    2  ISENSE_TMP421_1_DXN      B  @BASEBOARD_FAB2_LIB.BASEBOARD_FAB2(SCH_1):ISENSE_TMP421_1_DXN

CAPP  I103  C1M5   [CAPP_3018-68UF,16V,20%,TANT,72A]
    1  P12V_STBY          A  @BASEBOARD_FAB2_LIB.BASEBOARD_FAB2(SCH_1):P12V_STBY
    2  GND                B  @BASEBOARD_FAB2_LIB.BASEBOARD_FAB2(SCH_1):GND

CAP_0402  I109  C1M6   [CAP_0402-0.22UF,16V,10%,X7R,A3A]
    2  P3E_OCP_CPU0_PE3_C_TXP<15>      B  @BASEBOARD_FAB2_LIB.BASEBOARD_FAB2(SCH_1):P3E_OCP_CPU0_PE3_C_TXP<15>
    1  P3E_CPU0_PE3_OCP_TXP<15>      A  @BASEBOARD_FAB2_LIB.BASEBOARD_FAB2(SCH_1):P3E_CPU0_PE3_OCP_TXP<15>

CAP_0402  I122  C1M7   [CAP_0402-0.22UF,16V,10%,X7R,A3A]
    2  P3E_OCP_CPU0_PE3_C_TXN<15>      B  @BASEBOARD_FAB2_LIB.BASEBOARD_FAB2(SCH_1):P3E_OCP_CPU0_PE3_C_TXN<15>
    1  P3E_CPU0_PE3_OCP_TXN<15>      A  @BASEBOARD_FAB2_LIB.BASEBOARD_FAB2(SCH_1):P3E_CPU0_PE3_OCP_TXN<15>

CAP_0402  I105  C1M8   [CAP_0402-0.22UF,16V,10%,X7R,A3A]
    2  P3E_OCP_CPU0_PE3_C_TXP<14>      B  @BASEBOARD_FAB2_LIB.BASEBOARD_FAB2(SCH_1):P3E_OCP_CPU0_PE3_C_TXP<14>
    1  P3E_CPU0_PE3_OCP_TXP<14>      A  @BASEBOARD_FAB2_LIB.BASEBOARD_FAB2(SCH_1):P3E_CPU0_PE3_OCP_TXP<14>

CAP_0402  I114  C1M9   [CAP_0402-0.22UF,16V,10%,X7R,A3A]
    2  P3E_OCP_CPU0_PE3_C_TXN<14>      B  @BASEBOARD_FAB2_LIB.BASEBOARD_FAB2(SCH_1):P3E_OCP_CPU0_PE3_C_TXN<14>
    1  P3E_CPU0_PE3_OCP_TXN<14>      A  @BASEBOARD_FAB2_LIB.BASEBOARD_FAB2(SCH_1):P3E_CPU0_PE3_OCP_TXN<14>

CAP_0402  I102  C1M10  [CAP_0402-0.22UF,16V,10%,X7R,A3A]
    2  P3E_OCP_CPU0_PE3_C_TXP<13>      B  @BASEBOARD_FAB2_LIB.BASEBOARD_FAB2(SCH_1):P3E_OCP_CPU0_PE3_C_TXP<13>
    1  P3E_CPU0_PE3_OCP_TXP<13>      A  @BASEBOARD_FAB2_LIB.BASEBOARD_FAB2(SCH_1):P3E_CPU0_PE3_OCP_TXP<13>

CAP_0402  I117  C1M11  [CAP_0402-0.22UF,16V,10%,X7R,A3A]
    2  P3E_OCP_CPU0_PE3_C_TXN<13>      B  @BASEBOARD_FAB2_LIB.BASEBOARD_FAB2(SCH_1):P3E_OCP_CPU0_PE3_C_TXN<13>
    1  P3E_CPU0_PE3_OCP_TXN<13>      A  @BASEBOARD_FAB2_LIB.BASEBOARD_FAB2(SCH_1):P3E_CPU0_PE3_OCP_TXN<13>

CAP_0402  I100  C1M12  [CAP_0402-0.22UF,16V,10%,X7R,A3A]
    2  P3E_OCP_CPU0_PE3_C_TXP<12>      B  @BASEBOARD_FAB2_LIB.BASEBOARD_FAB2(SCH_1):P3E_OCP_CPU0_PE3_C_TXP<12>
    1  P3E_CPU0_PE3_OCP_TXP<12>      A  @BASEBOARD_FAB2_LIB.BASEBOARD_FAB2(SCH_1):P3E_CPU0_PE3_OCP_TXP<12>

CAP_0402  I111  C1M13  [CAP_0402-0.22UF,16V,10%,X7R,A3A]
    2  P3E_OCP_CPU0_PE3_C_TXN<12>      B  @BASEBOARD_FAB2_LIB.BASEBOARD_FAB2(SCH_1):P3E_OCP_CPU0_PE3_C_TXN<12>
    1  P3E_CPU0_PE3_OCP_TXN<12>      A  @BASEBOARD_FAB2_LIB.BASEBOARD_FAB2(SCH_1):P3E_CPU0_PE3_OCP_TXN<12>

CAP_0402  I85  C1M14  [CAP_0402-0.22UF,16V,10%,X7R,A3A]
    2  P3E_OCP_CPU0_PE3_C_TXP<11>      B  @BASEBOARD_FAB2_LIB.BASEBOARD_FAB2(SCH_1):P3E_OCP_CPU0_PE3_C_TXP<11>
    1  P3E_CPU0_PE3_OCP_TXP<11>      A  @BASEBOARD_FAB2_LIB.BASEBOARD_FAB2(SCH_1):P3E_CPU0_PE3_OCP_TXP<11>

CAP_0402  I95  C1M15  [CAP_0402-0.22UF,16V,10%,X7R,A3A]
    2  P3E_OCP_CPU0_PE3_C_TXN<11>      B  @BASEBOARD_FAB2_LIB.BASEBOARD_FAB2(SCH_1):P3E_OCP_CPU0_PE3_C_TXN<11>
    1  P3E_CPU0_PE3_OCP_TXN<11>      A  @BASEBOARD_FAB2_LIB.BASEBOARD_FAB2(SCH_1):P3E_CPU0_PE3_OCP_TXN<11>

CAP_0402  I82  C1M16  [CAP_0402-0.22UF,16V,10%,X7R,A3A]
    2  P3E_OCP_CPU0_PE3_C_TXP<10>      B  @BASEBOARD_FAB2_LIB.BASEBOARD_FAB2(SCH_1):P3E_OCP_CPU0_PE3_C_TXP<10>
    1  P3E_CPU0_PE3_OCP_TXP<10>      A  @BASEBOARD_FAB2_LIB.BASEBOARD_FAB2(SCH_1):P3E_CPU0_PE3_OCP_TXP<10>

CAP_0402  I92  C1M17  [CAP_0402-0.22UF,16V,10%,X7R,A3A]
    2  P3E_OCP_CPU0_PE3_C_TXN<10>      B  @BASEBOARD_FAB2_LIB.BASEBOARD_FAB2(SCH_1):P3E_OCP_CPU0_PE3_C_TXN<10>
    1  P3E_CPU0_PE3_OCP_TXN<10>      A  @BASEBOARD_FAB2_LIB.BASEBOARD_FAB2(SCH_1):P3E_CPU0_PE3_OCP_TXN<10>

CAP_0402  I78  C1M18  [CAP_0402-0.22UF,16V,10%,X7R,A3A]
    2  P3E_OCP_CPU0_PE3_C_TXP<9>      B  @BASEBOARD_FAB2_LIB.BASEBOARD_FAB2(SCH_1):P3E_OCP_CPU0_PE3_C_TXP<9>
    1  P3E_CPU0_PE3_OCP_TXP<9>      A  @BASEBOARD_FAB2_LIB.BASEBOARD_FAB2(SCH_1):P3E_CPU0_PE3_OCP_TXP<9>

CAP_0402  I90  C1M19  [CAP_0402-0.22UF,16V,10%,X7R,A3A]
    2  P3E_OCP_CPU0_PE3_C_TXN<9>      B  @BASEBOARD_FAB2_LIB.BASEBOARD_FAB2(SCH_1):P3E_OCP_CPU0_PE3_C_TXN<9>
    1  P3E_CPU0_PE3_OCP_TXN<9>      A  @BASEBOARD_FAB2_LIB.BASEBOARD_FAB2(SCH_1):P3E_CPU0_PE3_OCP_TXN<9>

CAP_A  I270  C1M20  [CAP_A_0402V-0.1UF,16V,10%,X7R,A]
    1  P3V3_STBY          A  @BASEBOARD_FAB2_LIB.BASEBOARD_FAB2(SCH_1):P3V3_STBY
    2  GND                B  @BASEBOARD_FAB2_LIB.BASEBOARD_FAB2(SCH_1):GND

CAP_A  I334  C1M21  [CAP_A_0402V-1.0UF,6.3V,10%,X6SA]
    1  P3V3               A  @BASEBOARD_FAB2_LIB.BASEBOARD_FAB2(SCH_1):P3V3
    2  GND                B  @BASEBOARD_FAB2_LIB.BASEBOARD_FAB2(SCH_1):GND

CAP_A  I8   C1M22  [CAP_A_0402V-0.1UF,16V,10%,X7R,A]
    1  P12V_STBY          A  @BASEBOARD_FAB2_LIB.BASEBOARD_FAB2(SCH_1):P12V_STBY
    2  GND                B  @BASEBOARD_FAB2_LIB.BASEBOARD_FAB2(SCH_1):GND

CAP_A  I7   C1M23  [CAP_A_0402V-0.1UF,16V,10%,X7R,A]
    1  P12V_STBY          A  @BASEBOARD_FAB2_LIB.BASEBOARD_FAB2(SCH_1):P12V_STBY
    2  GND                B  @BASEBOARD_FAB2_LIB.BASEBOARD_FAB2(SCH_1):GND

CAP_A  I10  C1M24  [CAP_A_0402V-0.1UF,16V,10%,X7R,A]
    1  P3V3               A  @BASEBOARD_FAB2_LIB.BASEBOARD_FAB2(SCH_1):P3V3
    2  GND                B  @BASEBOARD_FAB2_LIB.BASEBOARD_FAB2(SCH_1):GND

CAP_A  I335  C1M25  [CAP_A_0402V-1.0UF,6.3V,10%,X6SA]
    1  P3V3_STBY          A  @BASEBOARD_FAB2_LIB.BASEBOARD_FAB2(SCH_1):P3V3_STBY
    2  GND                B  @BASEBOARD_FAB2_LIB.BASEBOARD_FAB2(SCH_1):GND

CAP  I6   C1M26  [CAP_0805-10UF,16V,10%,X6S,C953A]
    1  P12V_STBY          A  @BASEBOARD_FAB2_LIB.BASEBOARD_FAB2(SCH_1):P12V_STBY
    2  GND                B  @BASEBOARD_FAB2_LIB.BASEBOARD_FAB2(SCH_1):GND

CAP  I3   C1M27  [CAP_0805-10UF,16V,10%,X6S,C953A]
    1  P12V_STBY          A  @BASEBOARD_FAB2_LIB.BASEBOARD_FAB2(SCH_1):P12V_STBY
    2  GND                B  @BASEBOARD_FAB2_LIB.BASEBOARD_FAB2(SCH_1):GND

CAP_A  I119  C1M28  [CAP_A_0402V-0.01UF,25V,10%,X7RA]
    1  P3V3_STBY          A  @BASEBOARD_FAB2_LIB.BASEBOARD_FAB2(SCH_1):P3V3_STBY
    2  GND                B  @BASEBOARD_FAB2_LIB.BASEBOARD_FAB2(SCH_1):GND

CAP_A  I147  C1M29  [CAP_A_0402V-0.1UF,16V,10%,X7R,A]
    1  P1V8_MCP_CPU0      A  @BASEBOARD_FAB2_LIB.BASEBOARD_FAB2(SCH_1):P1V8_MCP_CPU0
    2  GND                B  @BASEBOARD_FAB2_LIB.BASEBOARD_FAB2(SCH_1):GND

CAP_A  I131  C1M30  [CAP_A_0402V-0.01UF,25V,10%,X7RA]
    1  P3V3_STBY          A  @BASEBOARD_FAB2_LIB.BASEBOARD_FAB2(SCH_1):P3V3_STBY
    2  GND                B  @BASEBOARD_FAB2_LIB.BASEBOARD_FAB2(SCH_1):GND

CAP_A  I116  C1M31  [CAP_A_0402V-0.01UF,25V,10%,X7RA]
    1  P3V3_STBY          A  @BASEBOARD_FAB2_LIB.BASEBOARD_FAB2(SCH_1):P3V3_STBY
    2  GND                B  @BASEBOARD_FAB2_LIB.BASEBOARD_FAB2(SCH_1):GND

CAP_A  I117  C1M32  [CAP_A_0402V-1.0UF,6.3V,10%,X6SA]
    1  P3V3_STBY          A  @BASEBOARD_FAB2_LIB.BASEBOARD_FAB2(SCH_1):P3V3_STBY
    2  GND                B  @BASEBOARD_FAB2_LIB.BASEBOARD_FAB2(SCH_1):GND

CAP_A  I248  C1M33  [CAP_A_0402V-0.1UF,16V,10%,X7R,A]
    1  JTAG_MCP_TMS_R1      A  @BASEBOARD_FAB2_LIB.BASEBOARD_FAB2(SCH_1):JTAG_MCP_TMS_R1
    2  GND                B  @BASEBOARD_FAB2_LIB.BASEBOARD_FAB2(SCH_1):GND

CAP_A  I265  C1M34  [CAP_A_0402V-0.01UF,25V,10%,X7RA]
    1  P3V3_STBY          A  @BASEBOARD_FAB2_LIB.BASEBOARD_FAB2(SCH_1):P3V3_STBY
    2  GND                B  @BASEBOARD_FAB2_LIB.BASEBOARD_FAB2(SCH_1):GND

CAP_A  I266  C1M35  [CAP_A_0402V-0.01UF,25V,10%,X7RA]
    1  P3V3_STBY          A  @BASEBOARD_FAB2_LIB.BASEBOARD_FAB2(SCH_1):P3V3_STBY
    2  GND                B  @BASEBOARD_FAB2_LIB.BASEBOARD_FAB2(SCH_1):GND

CAP_A  I42  C1M36  [CAP_A_0402V-0.01UF,25V,10%,X7RA]
    1  P3V3_STBY          A  @BASEBOARD_FAB2_LIB.BASEBOARD_FAB2(SCH_1):P3V3_STBY
    2  GND                B  @BASEBOARD_FAB2_LIB.BASEBOARD_FAB2(SCH_1):GND

CAP_A  I47  C1M37  [CAP_A_0402V-1.0UF,6.3V,10%,X6SA]
    1  P3V3_STBY          A  @BASEBOARD_FAB2_LIB.BASEBOARD_FAB2(SCH_1):P3V3_STBY
    2  GND                B  @BASEBOARD_FAB2_LIB.BASEBOARD_FAB2(SCH_1):GND

CAP_A  I108  C1M38  [CAP_A_0402V-0.1UF,16V,10%,X7R,A]
    1  P5V                A  @BASEBOARD_FAB2_LIB.BASEBOARD_FAB2(SCH_1):P5V
    2  GND                B  @BASEBOARD_FAB2_LIB.BASEBOARD_FAB2(SCH_1):GND

CAP_0402  I29  C1R1   [CAP_0402-0.22UF,16V,10%,X7R,A3A]
    2  P3E_OCP_CPU0_PE3_C_TXN<0>      B  @BASEBOARD_FAB2_LIB.BASEBOARD_FAB2(SCH_1):P3E_OCP_CPU0_PE3_C_TXN<0>
    1  P3E_CPU0_PE3_OCP_TXN<0>      A  @BASEBOARD_FAB2_LIB.BASEBOARD_FAB2(SCH_1):P3E_CPU0_PE3_OCP_TXN<0>

CAP_0402  I10  C1R2   [CAP_0402-0.22UF,16V,10%,X7R,A3A]
    2  P3E_OCP_CPU0_PE3_C_TXP<0>      B  @BASEBOARD_FAB2_LIB.BASEBOARD_FAB2(SCH_1):P3E_OCP_CPU0_PE3_C_TXP<0>
    1  P3E_CPU0_PE3_OCP_TXP<0>      A  @BASEBOARD_FAB2_LIB.BASEBOARD_FAB2(SCH_1):P3E_CPU0_PE3_OCP_TXP<0>

CAP_0402  I37  C1R3   [CAP_0402-0.22UF,16V,10%,X7R,A3A]
    2  P3E_OCP_CPU0_PE3_C_TXN<1>      B  @BASEBOARD_FAB2_LIB.BASEBOARD_FAB2(SCH_1):P3E_OCP_CPU0_PE3_C_TXN<1>
    1  P3E_CPU0_PE3_OCP_TXN<1>      A  @BASEBOARD_FAB2_LIB.BASEBOARD_FAB2(SCH_1):P3E_CPU0_PE3_OCP_TXN<1>

CAP_0402  I26  C1R4   [CAP_0402-0.22UF,16V,10%,X7R,A3A]
    2  P3E_OCP_CPU0_PE3_C_TXP<1>      B  @BASEBOARD_FAB2_LIB.BASEBOARD_FAB2(SCH_1):P3E_OCP_CPU0_PE3_C_TXP<1>
    1  P3E_CPU0_PE3_OCP_TXP<1>      A  @BASEBOARD_FAB2_LIB.BASEBOARD_FAB2(SCH_1):P3E_CPU0_PE3_OCP_TXP<1>

CAP_0402  I59  C1R5   [CAP_0402-0.22UF,16V,10%,X7R,A3A]
    2  P3E_OCP_CPU0_PE3_C_TXN<2>      B  @BASEBOARD_FAB2_LIB.BASEBOARD_FAB2(SCH_1):P3E_OCP_CPU0_PE3_C_TXN<2>
    1  P3E_CPU0_PE3_OCP_TXN<2>      A  @BASEBOARD_FAB2_LIB.BASEBOARD_FAB2(SCH_1):P3E_CPU0_PE3_OCP_TXN<2>

CAP_0402  I40  C1R6   [CAP_0402-0.22UF,16V,10%,X7R,A3A]
    2  P3E_OCP_CPU0_PE3_C_TXP<2>      B  @BASEBOARD_FAB2_LIB.BASEBOARD_FAB2(SCH_1):P3E_OCP_CPU0_PE3_C_TXP<2>
    1  P3E_CPU0_PE3_OCP_TXP<2>      A  @BASEBOARD_FAB2_LIB.BASEBOARD_FAB2(SCH_1):P3E_CPU0_PE3_OCP_TXP<2>

CAP_0402  I70  C1R7   [CAP_0402-0.22UF,16V,10%,X7R,A3A]
    2  P3E_OCP_CPU0_PE3_C_TXN<3>      B  @BASEBOARD_FAB2_LIB.BASEBOARD_FAB2(SCH_1):P3E_OCP_CPU0_PE3_C_TXN<3>
    1  P3E_CPU0_PE3_OCP_TXN<3>      A  @BASEBOARD_FAB2_LIB.BASEBOARD_FAB2(SCH_1):P3E_CPU0_PE3_OCP_TXN<3>

CAP_0402  I55  C1R8   [CAP_0402-0.22UF,16V,10%,X7R,A3A]
    2  P3E_OCP_CPU0_PE3_C_TXP<3>      B  @BASEBOARD_FAB2_LIB.BASEBOARD_FAB2(SCH_1):P3E_OCP_CPU0_PE3_C_TXP<3>
    1  P3E_CPU0_PE3_OCP_TXP<3>      A  @BASEBOARD_FAB2_LIB.BASEBOARD_FAB2(SCH_1):P3E_CPU0_PE3_OCP_TXP<3>

CAP_0402  I134  C1R9   [CAP_0402-0.22UF,16V,10%,X7R,A3A]
    2  P3E_OCP_CPU0_PE3_C_TXN<4>      B  @BASEBOARD_FAB2_LIB.BASEBOARD_FAB2(SCH_1):P3E_OCP_CPU0_PE3_C_TXN<4>
    1  P3E_CPU0_PE3_OCP_TXN<4>      A  @BASEBOARD_FAB2_LIB.BASEBOARD_FAB2(SCH_1):P3E_CPU0_PE3_OCP_TXN<4>

CAP_0402  I128  C1R10  [CAP_0402-0.22UF,16V,10%,X7R,A3A]
    2  P3E_OCP_CPU0_PE3_C_TXP<4>      B  @BASEBOARD_FAB2_LIB.BASEBOARD_FAB2(SCH_1):P3E_OCP_CPU0_PE3_C_TXP<4>
    1  P3E_CPU0_PE3_OCP_TXP<4>      A  @BASEBOARD_FAB2_LIB.BASEBOARD_FAB2(SCH_1):P3E_CPU0_PE3_OCP_TXP<4>

CAP  I142  C1R13  [CAP_0603-10UF,6.3V,20%,X6S,E15A]
    1  P3V3_STBY          A  @BASEBOARD_FAB2_LIB.BASEBOARD_FAB2(SCH_1):P3V3_STBY
    2  GND                B  @BASEBOARD_FAB2_LIB.BASEBOARD_FAB2(SCH_1):GND

CAP_A  I145  C1R14  [CAP_A_0402V-0.1UF,16V,10%,X7R,A]
    1  P3V3_STBY          A  @BASEBOARD_FAB2_LIB.BASEBOARD_FAB2(SCH_1):P3V3_STBY
    2  GND                B  @BASEBOARD_FAB2_LIB.BASEBOARD_FAB2(SCH_1):GND

CAP_A  I160  C1R15  [CAP_A_0402V-0.1UF,16V,10%,X7R,A]
    1  P0V9_LAN           A  @BASEBOARD_FAB2_LIB.BASEBOARD_FAB2(SCH_1):P0V9_LAN
    2  GND                B  @BASEBOARD_FAB2_LIB.BASEBOARD_FAB2(SCH_1):GND

CAP  I161  C1R16  [CAP_0603-10UF,6.3V,20%,X6S,E15A]
    1  P0V9_LAN           A  @BASEBOARD_FAB2_LIB.BASEBOARD_FAB2(SCH_1):P0V9_LAN
    2  GND                B  @BASEBOARD_FAB2_LIB.BASEBOARD_FAB2(SCH_1):GND

CAP  I153  C1R17  [CAP_0603-10UF,6.3V,20%,X6S,E15A]
    1  P1V5_LAN           A  @BASEBOARD_FAB2_LIB.BASEBOARD_FAB2(SCH_1):P1V5_LAN
    2  GND                B  @BASEBOARD_FAB2_LIB.BASEBOARD_FAB2(SCH_1):GND

CAP_A  I157  C1R18  [CAP_A_0402V-0.1UF,16V,10%,X7R,A]
    1  P0V9_LAN           A  @BASEBOARD_FAB2_LIB.BASEBOARD_FAB2(SCH_1):P0V9_LAN
    2  GND                B  @BASEBOARD_FAB2_LIB.BASEBOARD_FAB2(SCH_1):GND

CAP_A  I151  C1R19  [CAP_A_0402V-0.1UF,16V,10%,X7R,A]
    1  P1V5_LAN           A  @BASEBOARD_FAB2_LIB.BASEBOARD_FAB2(SCH_1):P1V5_LAN
    2  GND                B  @BASEBOARD_FAB2_LIB.BASEBOARD_FAB2(SCH_1):GND

CAP_A  I143  C1R20  [CAP_A_0402V-0.1UF,16V,10%,X7R,A]
    1  P3V3_STBY          A  @BASEBOARD_FAB2_LIB.BASEBOARD_FAB2(SCH_1):P3V3_STBY
    2  GND                B  @BASEBOARD_FAB2_LIB.BASEBOARD_FAB2(SCH_1):GND

CAP_A  I146  C1R21  [CAP_A_0402V-0.1UF,16V,10%,X7R,A]
    1  P3V3_STBY          A  @BASEBOARD_FAB2_LIB.BASEBOARD_FAB2(SCH_1):P3V3_STBY
    2  GND                B  @BASEBOARD_FAB2_LIB.BASEBOARD_FAB2(SCH_1):GND

CAP  I136  C1R22  [CAP_0603-10UF,6.3V,20%,X6S,E15A]
    1  P3V3_STBY          A  @BASEBOARD_FAB2_LIB.BASEBOARD_FAB2(SCH_1):P3V3_STBY
    2  GND                B  @BASEBOARD_FAB2_LIB.BASEBOARD_FAB2(SCH_1):GND

CAPP  I101  C1R23  [CAPP_3018-68UF,16V,20%,TANT,72A]
    1  P12V_STBY          A  @BASEBOARD_FAB2_LIB.BASEBOARD_FAB2(SCH_1):P12V_STBY
    2  GND                B  @BASEBOARD_FAB2_LIB.BASEBOARD_FAB2(SCH_1):GND

CAP_A  I159  C1R24  [CAP_A_0402V-0.1UF,16V,10%,X7R,A]
    1  P0V9_LAN           A  @BASEBOARD_FAB2_LIB.BASEBOARD_FAB2(SCH_1):P0V9_LAN
    2  GND                B  @BASEBOARD_FAB2_LIB.BASEBOARD_FAB2(SCH_1):GND

CAP_A  I3   C1R25  [CAP_A_0402V-0.1UF,16V,10%,X7R,A]
    1  P3V3_STBY          A  @BASEBOARD_FAB2_LIB.BASEBOARD_FAB2(SCH_1):P3V3_STBY
    2  GND                B  @BASEBOARD_FAB2_LIB.BASEBOARD_FAB2(SCH_1):GND

CAP_A  I149  C1R26  [CAP_A_0402V-0.1UF,16V,10%,X7R,A]
    1  P1V5_LAN           A  @BASEBOARD_FAB2_LIB.BASEBOARD_FAB2(SCH_1):P1V5_LAN
    2  GND                B  @BASEBOARD_FAB2_LIB.BASEBOARD_FAB2(SCH_1):GND

CAP_A  I30  C1R27  [CAP_A_0402V-0.1UF,16V,10%,X7R,A]
    1  P3V3_STBY          A  @BASEBOARD_FAB2_LIB.BASEBOARD_FAB2(SCH_1):P3V3_STBY
    2  GND                B  @BASEBOARD_FAB2_LIB.BASEBOARD_FAB2(SCH_1):GND

CAP_A  I49  C1R28  [CAP_A_0402V-0.1UF,16V,10%,X7R,A]
    1  P3V3_STBY          A  @BASEBOARD_FAB2_LIB.BASEBOARD_FAB2(SCH_1):P3V3_STBY
    2  GND                B  @BASEBOARD_FAB2_LIB.BASEBOARD_FAB2(SCH_1):GND

CAP_A  I150  C1R29  [CAP_A_0402V-0.1UF,16V,10%,X7R,A]
    1  P1V5_LAN           A  @BASEBOARD_FAB2_LIB.BASEBOARD_FAB2(SCH_1):P1V5_LAN
    2  GND                B  @BASEBOARD_FAB2_LIB.BASEBOARD_FAB2(SCH_1):GND

CAP  I135  C1R30  [CAP_0603-10UF,6.3V,20%,X6S,E15A]
    1  P1V5_LAN           A  @BASEBOARD_FAB2_LIB.BASEBOARD_FAB2(SCH_1):P1V5_LAN
    2  GND                B  @BASEBOARD_FAB2_LIB.BASEBOARD_FAB2(SCH_1):GND

CAP_A  I152  C1R31  [CAP_A_0402V-0.1UF,16V,10%,X7R,A]
    1  P1V5_LAN           A  @BASEBOARD_FAB2_LIB.BASEBOARD_FAB2(SCH_1):P1V5_LAN
    2  GND                B  @BASEBOARD_FAB2_LIB.BASEBOARD_FAB2(SCH_1):GND

CAP_A  I144  C1T3   [CAP_A_0402V-0.1UF,16V,10%,X7R,A]
    1  P3V3_STBY          A  @BASEBOARD_FAB2_LIB.BASEBOARD_FAB2(SCH_1):P3V3_STBY
    2  GND                B  @BASEBOARD_FAB2_LIB.BASEBOARD_FAB2(SCH_1):GND

CAP  I134  C1T4   [CAP_0603-10UF,6.3V,20%,X6S,E15A]
    1  P0V9_LAN           A  @BASEBOARD_FAB2_LIB.BASEBOARD_FAB2(SCH_1):P0V9_LAN
    2  GND                B  @BASEBOARD_FAB2_LIB.BASEBOARD_FAB2(SCH_1):GND

CAP_A  I158  C1T5   [CAP_A_0402V-0.1UF,16V,10%,X7R,A]
    1  P0V9_LAN           A  @BASEBOARD_FAB2_LIB.BASEBOARD_FAB2(SCH_1):P0V9_LAN
    2  GND                B  @BASEBOARD_FAB2_LIB.BASEBOARD_FAB2(SCH_1):GND

CAP  I22  C1T7   [CAP_0603-10UF,6.3V,20%,X6S,E15A]
    1  P3V3_STBY          A  @BASEBOARD_FAB2_LIB.BASEBOARD_FAB2(SCH_1):P3V3_STBY
    2  GND                B  @BASEBOARD_FAB2_LIB.BASEBOARD_FAB2(SCH_1):GND

CAP_A  I44  C1T8   [CAP_A_0402V-0.1UF,16V,10%,X7R,A]
    1  P3V3_STBY          A  @BASEBOARD_FAB2_LIB.BASEBOARD_FAB2(SCH_1):P3V3_STBY
    2  GND                B  @BASEBOARD_FAB2_LIB.BASEBOARD_FAB2(SCH_1):GND

CAP  I75  C1T9   [CAP_0805-22UF,6.3V,20%,X6S,C95A]
    1  P3V3_STBY          A  @BASEBOARD_FAB2_LIB.BASEBOARD_FAB2(SCH_1):P3V3_STBY
    2  GND                B  @BASEBOARD_FAB2_LIB.BASEBOARD_FAB2(SCH_1):GND

CAP_A  I70  C1T10  [CAP_A_0402V-0.1UF,16V,10%,X7R,A]
    1  P3V3_STBY          A  @BASEBOARD_FAB2_LIB.BASEBOARD_FAB2(SCH_1):P3V3_STBY
    2  GND                B  @BASEBOARD_FAB2_LIB.BASEBOARD_FAB2(SCH_1):GND

CAP_A  I97  C1T11  [CAP_A_0402V-0.1UF,16V,10%,X7R,A]
    1  P3V3_STBY          A  @BASEBOARD_FAB2_LIB.BASEBOARD_FAB2(SCH_1):P3V3_STBY
    2  GND                B  @BASEBOARD_FAB2_LIB.BASEBOARD_FAB2(SCH_1):GND

CAP_A  I8   C1T12  [CAP_A_0402V-1.0UF,6.3V,10%,X6SA]
    1  P3V3_STBY          A  @BASEBOARD_FAB2_LIB.BASEBOARD_FAB2(SCH_1):P3V3_STBY
    2  GND                B  @BASEBOARD_FAB2_LIB.BASEBOARD_FAB2(SCH_1):GND

CAP  I74  C1T13  [CAP_0805-22UF,6.3V,20%,X6S,C95A]
    1  P3V3_STBY          A  @BASEBOARD_FAB2_LIB.BASEBOARD_FAB2(SCH_1):P3V3_STBY
    2  GND                B  @BASEBOARD_FAB2_LIB.BASEBOARD_FAB2(SCH_1):GND

CAP_A  I49  C1T14  [CAP_A_0402V-0.1UF,16V,10%,X7R,A]
    1  P3V3_STBY          A  @BASEBOARD_FAB2_LIB.BASEBOARD_FAB2(SCH_1):P3V3_STBY
    2  GND                B  @BASEBOARD_FAB2_LIB.BASEBOARD_FAB2(SCH_1):GND

CAP  I12  C1T15  [CAP_0603-10UF,6.3V,20%,X6S,E15A]
    1  P1V538_BMC_STBY      A  @BASEBOARD_FAB2_LIB.BASEBOARD_FAB2(SCH_1):P1V538_BMC_STBY
    2  GND                B  @BASEBOARD_FAB2_LIB.BASEBOARD_FAB2(SCH_1):GND

CAP  I150  C1T16  [CAP_0603-10UF,6.3V,20%,EMPTY,EA]
    1  P1V8_BMC_STBY_PCIE      A  @BASEBOARD_FAB2_LIB.BASEBOARD_FAB2(SCH_1):P1V8_BMC_STBY_PCIE
    2  GND                B  @BASEBOARD_FAB2_LIB.BASEBOARD_FAB2(SCH_1):GND

CAP_A  I151  C1T17  [CAP_A_0402V-0.1UF,16V,10%,EMPTA]
    1  P1V8_BMC_STBY_PCIE      A  @BASEBOARD_FAB2_LIB.BASEBOARD_FAB2(SCH_1):P1V8_BMC_STBY_PCIE
    2  GND                B  @BASEBOARD_FAB2_LIB.BASEBOARD_FAB2(SCH_1):GND

CAP_A  I152  C1T18  [CAP_A_0402V-1.0UF,6.3V,10%,EMPA]
    1  P1V8_BMC_STBY_PCIE      A  @BASEBOARD_FAB2_LIB.BASEBOARD_FAB2(SCH_1):P1V8_BMC_STBY_PCIE
    2  GND                B  @BASEBOARD_FAB2_LIB.BASEBOARD_FAB2(SCH_1):GND

CAP_A  I121  C1T19  [CAP_A_0402V-1.0UF,6.3V,10%,X6SA]
    1  P3V3_STBY_BMC_HPLLAV33      A  @BASEBOARD_FAB2_LIB.BASEBOARD_FAB2(SCH_1):P3V3_STBY_BMC_HPLLAV33
    2  GND                B  @BASEBOARD_FAB2_LIB.BASEBOARD_FAB2(SCH_1):GND

CAP  I119  C1T20  [CAP_0402LF-100.0PF,50V,5%,COG,A]
    1  P3V3_STBY_BMC_HPLLAV33      A  @BASEBOARD_FAB2_LIB.BASEBOARD_FAB2(SCH_1):P3V3_STBY_BMC_HPLLAV33
    2  GND                B  @BASEBOARD_FAB2_LIB.BASEBOARD_FAB2(SCH_1):GND

CAP_A  I28  C1T21  [CAP_A_0402V-1.0UF,6.3V,10%,X6SA]
    1  PVCCIO_CPU0        A  @BASEBOARD_FAB2_LIB.BASEBOARD_FAB2(SCH_1):PVCCIO_CPU0
    2  GND                B  @BASEBOARD_FAB2_LIB.BASEBOARD_FAB2(SCH_1):GND

CAP_A  I43  C1T22  [CAP_A_0402V-0.1UF,16V,10%,X7R,A]
    1  P3V3_STBY          A  @BASEBOARD_FAB2_LIB.BASEBOARD_FAB2(SCH_1):P3V3_STBY
    2  GND                B  @BASEBOARD_FAB2_LIB.BASEBOARD_FAB2(SCH_1):GND

CAP_A  I147  C1T23  [CAP_A_0402V-0.1UF,16V,10%,X7R,A]
    1  P3V3_STBY_BMC_HPLLAV33      A  @BASEBOARD_FAB2_LIB.BASEBOARD_FAB2(SCH_1):P3V3_STBY_BMC_HPLLAV33
    2  GND                B  @BASEBOARD_FAB2_LIB.BASEBOARD_FAB2(SCH_1):GND

CAP_A  I81  C1T24  [CAP_A_0402V-0.01UF,25V,10%,X7RA]
    1  P1V26_BMC_STBY      A  @BASEBOARD_FAB2_LIB.BASEBOARD_FAB2(SCH_1):P1V26_BMC_STBY
    2  GND                B  @BASEBOARD_FAB2_LIB.BASEBOARD_FAB2(SCH_1):GND

CAP_A  I42  C1T25  [CAP_A_0402V-0.1UF,16V,10%,X7R,A]
    1  P3V3_STBY          A  @BASEBOARD_FAB2_LIB.BASEBOARD_FAB2(SCH_1):P3V3_STBY
    2  GND                B  @BASEBOARD_FAB2_LIB.BASEBOARD_FAB2(SCH_1):GND

CAP_A  I46  C1T26  [CAP_A_0402V-0.1UF,16V,10%,X7R,A]
    1  P3V3_STBY          A  @BASEBOARD_FAB2_LIB.BASEBOARD_FAB2(SCH_1):P3V3_STBY
    2  GND                B  @BASEBOARD_FAB2_LIB.BASEBOARD_FAB2(SCH_1):GND

CAP_A  I82  C1T27  [CAP_A_0402V-0.01UF,25V,10%,X7RA]
    1  P1V26_BMC_STBY      A  @BASEBOARD_FAB2_LIB.BASEBOARD_FAB2(SCH_1):P1V26_BMC_STBY
    2  GND                B  @BASEBOARD_FAB2_LIB.BASEBOARD_FAB2(SCH_1):GND

CAP_A  I77  C1T28  [CAP_A_0402V-1.0UF,6.3V,10%,X6SA]
    1  P1V26_BMC_STBY      A  @BASEBOARD_FAB2_LIB.BASEBOARD_FAB2(SCH_1):P1V26_BMC_STBY
    2  GND                B  @BASEBOARD_FAB2_LIB.BASEBOARD_FAB2(SCH_1):GND

CAP_A  I5   C1T29  [CAP_A_0402V-0.1UF,16V,10%,X7R,A]
    1  P3V3_STBY          A  @BASEBOARD_FAB2_LIB.BASEBOARD_FAB2(SCH_1):P3V3_STBY
    2  GND                B  @BASEBOARD_FAB2_LIB.BASEBOARD_FAB2(SCH_1):GND

CAP_A  I6   C1T30  [CAP_A_0402V-0.1UF,16V,10%,X7R,A]
    1  P3V3_STBY          A  @BASEBOARD_FAB2_LIB.BASEBOARD_FAB2(SCH_1):P3V3_STBY
    2  GND                B  @BASEBOARD_FAB2_LIB.BASEBOARD_FAB2(SCH_1):GND

CAP_A  I92  C1T31  [CAP_A_0402V-1.0UF,6.3V,10%,X6SA]
    1  P1V538_BMC_STBY      A  @BASEBOARD_FAB2_LIB.BASEBOARD_FAB2(SCH_1):P1V538_BMC_STBY
    2  GND                B  @BASEBOARD_FAB2_LIB.BASEBOARD_FAB2(SCH_1):GND

CAP_A  I89  C1T32  [CAP_A_0402V-1.0UF,6.3V,10%,X6SA]
    1  P1V538_BMC_STBY      A  @BASEBOARD_FAB2_LIB.BASEBOARD_FAB2(SCH_1):P1V538_BMC_STBY
    2  GND                B  @BASEBOARD_FAB2_LIB.BASEBOARD_FAB2(SCH_1):GND

CAP_A  I80  C1T33  [CAP_A_0402V-0.1UF,16V,10%,X7R,A]
    1  P1V538_BMC_STBY      A  @BASEBOARD_FAB2_LIB.BASEBOARD_FAB2(SCH_1):P1V538_BMC_STBY
    2  GND                B  @BASEBOARD_FAB2_LIB.BASEBOARD_FAB2(SCH_1):GND

CAP_A  I80  C1T34  [CAP_A_0402V-0.01UF,25V,10%,X7RA]
    1  P1V26_BMC_STBY      A  @BASEBOARD_FAB2_LIB.BASEBOARD_FAB2(SCH_1):P1V26_BMC_STBY
    2  GND                B  @BASEBOARD_FAB2_LIB.BASEBOARD_FAB2(SCH_1):GND

CAP_A  I93  C1T35  [CAP_A_0402V-1.0UF,6.3V,10%,X6SA]
    1  P1V538_BMC_STBY      A  @BASEBOARD_FAB2_LIB.BASEBOARD_FAB2(SCH_1):P1V538_BMC_STBY
    2  GND                B  @BASEBOARD_FAB2_LIB.BASEBOARD_FAB2(SCH_1):GND

CAP_A  I83  C1T36  [CAP_A_0402V-0.01UF,25V,10%,X7RA]
    1  P1V26_BMC_STBY      A  @BASEBOARD_FAB2_LIB.BASEBOARD_FAB2(SCH_1):P1V26_BMC_STBY
    2  GND                B  @BASEBOARD_FAB2_LIB.BASEBOARD_FAB2(SCH_1):GND

CAP_A  I336  C1T37  [CAP_A_0402V-0.1UF,16V,10%,X7R,A]
    1  M_BMC_DDR3_MVREF      A  @BASEBOARD_FAB2_LIB.BASEBOARD_FAB2(SCH_1):M_BMC_DDR3_MVREF
    2  GND                B  @BASEBOARD_FAB2_LIB.BASEBOARD_FAB2(SCH_1):GND

CAP_A  I22  C1T38  [CAP_A_0402V-0.1UF,16V,10%,X7R,A]
    1  P3V3_STBY          A  @BASEBOARD_FAB2_LIB.BASEBOARD_FAB2(SCH_1):P3V3_STBY
    2  GND                B  @BASEBOARD_FAB2_LIB.BASEBOARD_FAB2(SCH_1):GND

CAP_A  I64  C1T39  [CAP_A_0402V-0.01UF,25V,10%,X7RA]
    1  P1V538_BMC_STBY      A  @BASEBOARD_FAB2_LIB.BASEBOARD_FAB2(SCH_1):P1V538_BMC_STBY
    2  M_BMC_DDR3_MVREF      B  @BASEBOARD_FAB2_LIB.BASEBOARD_FAB2(SCH_1):M_BMC_DDR3_MVREF

CAP_A  I76  C1T40  [CAP_A_0402V-0.1UF,16V,10%,X7R,A]
    1  P1V538_BMC_STBY      A  @BASEBOARD_FAB2_LIB.BASEBOARD_FAB2(SCH_1):P1V538_BMC_STBY
    2  GND                B  @BASEBOARD_FAB2_LIB.BASEBOARD_FAB2(SCH_1):GND

CAP_A  I63  C1T41  [CAP_A_0402V-0.01UF,25V,10%,X7RA]
    1  M_BMC_DDR3_MVREF      A  @BASEBOARD_FAB2_LIB.BASEBOARD_FAB2(SCH_1):M_BMC_DDR3_MVREF
    2  GND                B  @BASEBOARD_FAB2_LIB.BASEBOARD_FAB2(SCH_1):GND

CAP  I85  C1T42  [CAP_0603-0.47UF,16V,10%,X7R,20A]
    1  P1V26_BMC_STBY      A  @BASEBOARD_FAB2_LIB.BASEBOARD_FAB2(SCH_1):P1V26_BMC_STBY
    2  GND                B  @BASEBOARD_FAB2_LIB.BASEBOARD_FAB2(SCH_1):GND

CAP_A  I20  C1T43  [CAP_A_0402V-0.1UF,16V,10%,X7R,A]
    1  P3V3_STBY          A  @BASEBOARD_FAB2_LIB.BASEBOARD_FAB2(SCH_1):P3V3_STBY
    2  GND                B  @BASEBOARD_FAB2_LIB.BASEBOARD_FAB2(SCH_1):GND

CAP  I25  C1T44  [CAP_0603-4.7UF,6.3V,10%,X6S,E1A]
    1  P3V3_STBY          A  @BASEBOARD_FAB2_LIB.BASEBOARD_FAB2(SCH_1):P3V3_STBY
    2  GND                B  @BASEBOARD_FAB2_LIB.BASEBOARD_FAB2(SCH_1):GND

CAP_A  I21  C1T45  [CAP_A_0402V-0.1UF,16V,10%,X7R,A]
    1  P3V3_STBY          A  @BASEBOARD_FAB2_LIB.BASEBOARD_FAB2(SCH_1):P3V3_STBY
    2  GND                B  @BASEBOARD_FAB2_LIB.BASEBOARD_FAB2(SCH_1):GND

CAP_A  I91  C1T46  [CAP_A_0402V-1.0UF,6.3V,10%,X6SA]
    1  P1V538_BMC_STBY      A  @BASEBOARD_FAB2_LIB.BASEBOARD_FAB2(SCH_1):P1V538_BMC_STBY
    2  GND                B  @BASEBOARD_FAB2_LIB.BASEBOARD_FAB2(SCH_1):GND

CAP_A  I24  C1T47  [CAP_A_0402V-0.1UF,16V,10%,X7R,A]
    1  P3V3_STBY          A  @BASEBOARD_FAB2_LIB.BASEBOARD_FAB2(SCH_1):P3V3_STBY
    2  GND                B  @BASEBOARD_FAB2_LIB.BASEBOARD_FAB2(SCH_1):GND

CAP_A  I58  C1T48  [CAP_A_0402V-0.1UF,16V,10%,X7R,A]
    1  M_BMC_DDR3_MVREF      A  @BASEBOARD_FAB2_LIB.BASEBOARD_FAB2(SCH_1):M_BMC_DDR3_MVREF
    2  GND                B  @BASEBOARD_FAB2_LIB.BASEBOARD_FAB2(SCH_1):GND

CAP_A  I94  C1T49  [CAP_A_0402V-1.0UF,6.3V,10%,X6SA]
    1  P1V538_BMC_STBY      A  @BASEBOARD_FAB2_LIB.BASEBOARD_FAB2(SCH_1):P1V538_BMC_STBY
    2  GND                B  @BASEBOARD_FAB2_LIB.BASEBOARD_FAB2(SCH_1):GND

CAP_A  I41  C1T50  [CAP_A_0402V-0.1UF,16V,10%,X7R,A]
    1  P3V3_STBY          A  @BASEBOARD_FAB2_LIB.BASEBOARD_FAB2(SCH_1):P3V3_STBY
    2  GND                B  @BASEBOARD_FAB2_LIB.BASEBOARD_FAB2(SCH_1):GND

CAP_A  I62  C1T51  [CAP_A_0402V-1.0UF,6.3V,10%,X6SA]
    1  M_BMC_DDR3_MVREF      A  @BASEBOARD_FAB2_LIB.BASEBOARD_FAB2(SCH_1):M_BMC_DDR3_MVREF
    2  GND                B  @BASEBOARD_FAB2_LIB.BASEBOARD_FAB2(SCH_1):GND

CAP_A  I1   C1T52  [CAP_A_0402V-0.1UF,16V,10%,X7R,A]
    1  P3V3_STBY          A  @BASEBOARD_FAB2_LIB.BASEBOARD_FAB2(SCH_1):P3V3_STBY
    2  GND                B  @BASEBOARD_FAB2_LIB.BASEBOARD_FAB2(SCH_1):GND

CAP_A  I82  C1T53  [CAP_A_0402V-0.1UF,16V,10%,X7R,A]
    1  P1V538_BMC_STBY      A  @BASEBOARD_FAB2_LIB.BASEBOARD_FAB2(SCH_1):P1V538_BMC_STBY
    2  GND                B  @BASEBOARD_FAB2_LIB.BASEBOARD_FAB2(SCH_1):GND

CAP_A  I83  C1T54  [CAP_A_0402V-0.1UF,16V,10%,X7R,A]
    1  P1V538_BMC_STBY      A  @BASEBOARD_FAB2_LIB.BASEBOARD_FAB2(SCH_1):P1V538_BMC_STBY
    2  GND                B  @BASEBOARD_FAB2_LIB.BASEBOARD_FAB2(SCH_1):GND

CAP_A  I90  C1T55  [CAP_A_0402V-1.0UF,6.3V,10%,X6SA]
    1  P1V538_BMC_STBY      A  @BASEBOARD_FAB2_LIB.BASEBOARD_FAB2(SCH_1):P1V538_BMC_STBY
    2  GND                B  @BASEBOARD_FAB2_LIB.BASEBOARD_FAB2(SCH_1):GND

CAP_A  I184  C1T56  [CAP_A_0402V-0.1UF,16V,10%,X7R,A]
    1  P3V3_STBY          A  @BASEBOARD_FAB2_LIB.BASEBOARD_FAB2(SCH_1):P3V3_STBY
    2  GND                B  @BASEBOARD_FAB2_LIB.BASEBOARD_FAB2(SCH_1):GND

CAP  I84  C1U1   [CAP_0805-10UF,16V,10%,X6S,C953A]
    1  P1V26_BMC_STBY      A  @BASEBOARD_FAB2_LIB.BASEBOARD_FAB2(SCH_1):P1V26_BMC_STBY
    2  GND                B  @BASEBOARD_FAB2_LIB.BASEBOARD_FAB2(SCH_1):GND

CAP  I26  C1U2   [CAP_0402LF-100.0PF,50V,5%,COG,A]
    1  P3V3_STBY          A  @BASEBOARD_FAB2_LIB.BASEBOARD_FAB2(SCH_1):P3V3_STBY
    2  GND                B  @BASEBOARD_FAB2_LIB.BASEBOARD_FAB2(SCH_1):GND

CAP_A  I4   C1U3   [CAP_A_0402V-0.1UF,16V,10%,X7R,A]
    1  P3V3_STBY          A  @BASEBOARD_FAB2_LIB.BASEBOARD_FAB2(SCH_1):P3V3_STBY
    2  GND                B  @BASEBOARD_FAB2_LIB.BASEBOARD_FAB2(SCH_1):GND

CAP_A  I18  C1U4   [CAP_A_0402V-0.1UF,16V,10%,X7R,A]
    1  P3V3_STBY          A  @BASEBOARD_FAB2_LIB.BASEBOARD_FAB2(SCH_1):P3V3_STBY
    2  GND                B  @BASEBOARD_FAB2_LIB.BASEBOARD_FAB2(SCH_1):GND

CAP_A  I17  C1U5   [CAP_A_0402V-0.1UF,16V,10%,X7R,A]
    1  P3V3_STBY          A  @BASEBOARD_FAB2_LIB.BASEBOARD_FAB2(SCH_1):P3V3_STBY
    2  GND                B  @BASEBOARD_FAB2_LIB.BASEBOARD_FAB2(SCH_1):GND

CAP_A  I78  C1U6   [CAP_A_0402V-1.0UF,6.3V,10%,X6SA]
    1  P1V26_BMC_STBY      A  @BASEBOARD_FAB2_LIB.BASEBOARD_FAB2(SCH_1):P1V26_BMC_STBY
    2  GND                B  @BASEBOARD_FAB2_LIB.BASEBOARD_FAB2(SCH_1):GND

CAP_A  I79  C1U7   [CAP_A_0402V-1.0UF,6.3V,10%,X6SA]
    1  P1V26_BMC_STBY      A  @BASEBOARD_FAB2_LIB.BASEBOARD_FAB2(SCH_1):P1V26_BMC_STBY
    2  GND                B  @BASEBOARD_FAB2_LIB.BASEBOARD_FAB2(SCH_1):GND

CAP_A  I19  C1U8   [CAP_A_0402V-1.0UF,6.3V,10%,X6SA]
    1  P3V3_STBY          A  @BASEBOARD_FAB2_LIB.BASEBOARD_FAB2(SCH_1):P3V3_STBY
    2  GND                B  @BASEBOARD_FAB2_LIB.BASEBOARD_FAB2(SCH_1):GND

CAP_A  I23  C1U9   [CAP_A_0402V-0.1UF,16V,10%,X7R,A]
    1  P3V3_STBY          A  @BASEBOARD_FAB2_LIB.BASEBOARD_FAB2(SCH_1):P3V3_STBY
    2  GND                B  @BASEBOARD_FAB2_LIB.BASEBOARD_FAB2(SCH_1):GND

CAP_A  I86  C1U10  [CAP_A_0402V-0.1UF,16V,10%,X7R,A]
    1  P1V538_BMC_STBY      A  @BASEBOARD_FAB2_LIB.BASEBOARD_FAB2(SCH_1):P1V538_BMC_STBY
    2  GND                B  @BASEBOARD_FAB2_LIB.BASEBOARD_FAB2(SCH_1):GND

CAP_A  I25  C1U11  [CAP_A_0402V-0.1UF,16V,10%,X7R,A]
    1  P3V3_STBY          A  @BASEBOARD_FAB2_LIB.BASEBOARD_FAB2(SCH_1):P3V3_STBY
    2  GND                B  @BASEBOARD_FAB2_LIB.BASEBOARD_FAB2(SCH_1):GND

CAP  I88  C1U12  [CAP_0805-10UF,16V,10%,X6S,C953A]
    1  P1V538_BMC_STBY      A  @BASEBOARD_FAB2_LIB.BASEBOARD_FAB2(SCH_1):P1V538_BMC_STBY
    2  GND                B  @BASEBOARD_FAB2_LIB.BASEBOARD_FAB2(SCH_1):GND

CAP_A  I79  C1U13  [CAP_A_0402V-0.1UF,16V,10%,X7R,A]
    1  P1V538_BMC_STBY      A  @BASEBOARD_FAB2_LIB.BASEBOARD_FAB2(SCH_1):P1V538_BMC_STBY
    2  GND                B  @BASEBOARD_FAB2_LIB.BASEBOARD_FAB2(SCH_1):GND

CAP_A  I84  C1U14  [CAP_A_0402V-0.1UF,16V,10%,X7R,A]
    1  P1V538_BMC_STBY      A  @BASEBOARD_FAB2_LIB.BASEBOARD_FAB2(SCH_1):P1V538_BMC_STBY
    2  GND                B  @BASEBOARD_FAB2_LIB.BASEBOARD_FAB2(SCH_1):GND

CAP_A  I78  C1U15  [CAP_A_0402V-0.1UF,16V,10%,X7R,A]
    1  P1V538_BMC_STBY      A  @BASEBOARD_FAB2_LIB.BASEBOARD_FAB2(SCH_1):P1V538_BMC_STBY
    2  GND                B  @BASEBOARD_FAB2_LIB.BASEBOARD_FAB2(SCH_1):GND

CAP_A  I81  C1U16  [CAP_A_0402V-0.1UF,16V,10%,X7R,A]
    1  P1V538_BMC_STBY      A  @BASEBOARD_FAB2_LIB.BASEBOARD_FAB2(SCH_1):P1V538_BMC_STBY
    2  GND                B  @BASEBOARD_FAB2_LIB.BASEBOARD_FAB2(SCH_1):GND

CAP  I142  C1U17  [CAP_0402LF-100.0PF,50V,5%,COG,A]
    1  P3V3_STBY_BMC_ADCAV33      A  @BASEBOARD_FAB2_LIB.BASEBOARD_FAB2(SCH_1):P3V3_STBY_BMC_ADCAV33
    2  GND                B  @BASEBOARD_FAB2_LIB.BASEBOARD_FAB2(SCH_1):GND

CAP_A  I141  C1U18  [CAP_A_0402V-1.0UF,6.3V,10%,X6SA]
    1  P3V3_STBY_BMC_ADCAV33      A  @BASEBOARD_FAB2_LIB.BASEBOARD_FAB2(SCH_1):P3V3_STBY_BMC_ADCAV33
    2  GND                B  @BASEBOARD_FAB2_LIB.BASEBOARD_FAB2(SCH_1):GND

CAP_0402  I18  C1U19  [CAP_0402-1.0UF,16V,10%,X6S,D97A]
    1  P3V3               A  @BASEBOARD_FAB2_LIB.BASEBOARD_FAB2(SCH_1):P3V3
    2  GND                B  @BASEBOARD_FAB2_LIB.BASEBOARD_FAB2(SCH_1):GND

CAP  I67  C1U20  [CAP_0805-10UF,16V,10%,X7R,G106A]
    1  P3V3_FB_ADC128_VCC      A  @BASEBOARD_FAB2_LIB.BASEBOARD_FAB2(SCH_1):P3V3_FB_ADC128_VCC
    2  GND                B  @BASEBOARD_FAB2_LIB.BASEBOARD_FAB2(SCH_1):GND

CAP  I56  C1U21  [CAP_0402LF-47.0PF,50V,5%,COG,AA]
    2  GND                B  @BASEBOARD_FAB2_LIB.BASEBOARD_FAB2(SCH_1):GND
    1  A_P1V05_STBY_PCH_SENSOR      A  @BASEBOARD_FAB2_LIB.BASEBOARD_FAB2(SCH_1):A_P1V05_STBY_PCH_SENSOR

CAP_A  I27  C1U22  [CAP_A_0402V-0.1UF,16V,10%,X7R,A]
    1  P0V7_GTL2014_2      A  @BASEBOARD_FAB2_LIB.BASEBOARD_FAB2(SCH_1):P0V7_GTL2014_2
    2  GND                B  @BASEBOARD_FAB2_LIB.BASEBOARD_FAB2(SCH_1):GND

CAP_A  I210  C2A1   [CAP_A_0603V-22.0UF,4V,20%,X6S,A]
    1  PVDDQ_KLM          A  @BASEBOARD_FAB2_LIB.BASEBOARD_FAB2(SCH_1):PVDDQ_KLM
    2  GND                B  @BASEBOARD_FAB2_LIB.BASEBOARD_FAB2(SCH_1):GND

CAP_A  I209  C2A2   [CAP_A_0603V-22.0UF,4V,20%,X6S,A]
    1  PVDDQ_KLM          A  @BASEBOARD_FAB2_LIB.BASEBOARD_FAB2(SCH_1):PVDDQ_KLM
    2  GND                B  @BASEBOARD_FAB2_LIB.BASEBOARD_FAB2(SCH_1):GND

CAP_A  I230  C2A3   [CAP_A_0603V-22.0UF,4V,20%,X6S,A]
    1  PVDDQ_KLM          A  @BASEBOARD_FAB2_LIB.BASEBOARD_FAB2(SCH_1):PVDDQ_KLM
    2  GND                B  @BASEBOARD_FAB2_LIB.BASEBOARD_FAB2(SCH_1):GND

CAP_A  I234  C2A4   [CAP_A_0603V-22.0UF,4V,20%,X6S,A]
    1  PVDDQ_KLM          A  @BASEBOARD_FAB2_LIB.BASEBOARD_FAB2(SCH_1):PVDDQ_KLM
    2  GND                B  @BASEBOARD_FAB2_LIB.BASEBOARD_FAB2(SCH_1):GND

CAP_A  I199  C2A5   [CAP_A_0603V-47UF,4V,20%,X5R,60A]
    1  PVDDQ_KLM          A  @BASEBOARD_FAB2_LIB.BASEBOARD_FAB2(SCH_1):PVDDQ_KLM
    2  GND                B  @BASEBOARD_FAB2_LIB.BASEBOARD_FAB2(SCH_1):GND

CAP_A  I219  C2A6   [CAP_A_0603V-22.0UF,4V,20%,X6S,A]
    1  PVDDQ_KLM          A  @BASEBOARD_FAB2_LIB.BASEBOARD_FAB2(SCH_1):PVDDQ_KLM
    2  GND                B  @BASEBOARD_FAB2_LIB.BASEBOARD_FAB2(SCH_1):GND

CAP_A  I218  C2A7   [CAP_A_0603V-22.0UF,4V,20%,X6S,A]
    1  PVDDQ_KLM          A  @BASEBOARD_FAB2_LIB.BASEBOARD_FAB2(SCH_1):PVDDQ_KLM
    2  GND                B  @BASEBOARD_FAB2_LIB.BASEBOARD_FAB2(SCH_1):GND

CAP  I82  C2A8   [CAP_0805-100UF,4V,20%,X5R,6024A]
    1  PVDDQ_KLM          A  @BASEBOARD_FAB2_LIB.BASEBOARD_FAB2(SCH_1):PVDDQ_KLM
    2  GND                B  @BASEBOARD_FAB2_LIB.BASEBOARD_FAB2(SCH_1):GND

CAP_A  I215  C2A9   [CAP_A_0603V-22.0UF,4V,20%,X6S,A]
    1  PVDDQ_KLM          A  @BASEBOARD_FAB2_LIB.BASEBOARD_FAB2(SCH_1):PVDDQ_KLM
    2  GND                B  @BASEBOARD_FAB2_LIB.BASEBOARD_FAB2(SCH_1):GND

CAP_A  I214  C2A10  [CAP_A_0603V-22.0UF,4V,20%,X6S,A]
    1  PVDDQ_KLM          A  @BASEBOARD_FAB2_LIB.BASEBOARD_FAB2(SCH_1):PVDDQ_KLM
    2  GND                B  @BASEBOARD_FAB2_LIB.BASEBOARD_FAB2(SCH_1):GND

CAP_A  I213  C2A11  [CAP_A_0603V-22.0UF,4V,20%,X6S,A]
    1  PVDDQ_KLM          A  @BASEBOARD_FAB2_LIB.BASEBOARD_FAB2(SCH_1):PVDDQ_KLM
    2  GND                B  @BASEBOARD_FAB2_LIB.BASEBOARD_FAB2(SCH_1):GND

CAP_A  I211  C2A12  [CAP_A_0603V-22.0UF,4V,20%,X6S,A]
    1  PVDDQ_KLM          A  @BASEBOARD_FAB2_LIB.BASEBOARD_FAB2(SCH_1):PVDDQ_KLM
    2  GND                B  @BASEBOARD_FAB2_LIB.BASEBOARD_FAB2(SCH_1):GND

CAP_A  I212  C2A13  [CAP_A_0603V-22.0UF,4V,20%,X6S,A]
    1  PVDDQ_KLM          A  @BASEBOARD_FAB2_LIB.BASEBOARD_FAB2(SCH_1):PVDDQ_KLM
    2  GND                B  @BASEBOARD_FAB2_LIB.BASEBOARD_FAB2(SCH_1):GND

CAP_A  I220  C2A14  [CAP_A_0603V-22.0UF,4V,20%,X6S,A]
    1  PVDDQ_KLM          A  @BASEBOARD_FAB2_LIB.BASEBOARD_FAB2(SCH_1):PVDDQ_KLM
    2  GND                B  @BASEBOARD_FAB2_LIB.BASEBOARD_FAB2(SCH_1):GND

CAP_A  I221  C2A15  [CAP_A_0603V-22.0UF,4V,20%,X6S,A]
    1  PVDDQ_KLM          A  @BASEBOARD_FAB2_LIB.BASEBOARD_FAB2(SCH_1):PVDDQ_KLM
    2  GND                B  @BASEBOARD_FAB2_LIB.BASEBOARD_FAB2(SCH_1):GND

CAP  I89  C2A16  [CAP_0805-100UF,4V,20%,X5R,6024A]
    1  PVDDQ_KLM          A  @BASEBOARD_FAB2_LIB.BASEBOARD_FAB2(SCH_1):PVDDQ_KLM
    2  GND                B  @BASEBOARD_FAB2_LIB.BASEBOARD_FAB2(SCH_1):GND

CAP_A  I200  C2B1   [CAP_A_0603V-47UF,4V,20%,X5R,60A]
    1  PVDDQ_KLM          A  @BASEBOARD_FAB2_LIB.BASEBOARD_FAB2(SCH_1):PVDDQ_KLM
    2  GND                B  @BASEBOARD_FAB2_LIB.BASEBOARD_FAB2(SCH_1):GND

CAP_A  I204  C2B2   [CAP_A_0603V-47UF,4V,20%,X5R,60A]
    1  PVDDQ_KLM          A  @BASEBOARD_FAB2_LIB.BASEBOARD_FAB2(SCH_1):PVDDQ_KLM
    2  GND                B  @BASEBOARD_FAB2_LIB.BASEBOARD_FAB2(SCH_1):GND

CAP_A  I116  C2D1   [CAP_A_0603V-22.0UF,4V,20%,X6S,A]
    1  PVCCIN_CPU1        A  @BASEBOARD_FAB2_LIB.BASEBOARD_FAB2(SCH_1):PVCCIN_CPU1
    2  GND                B  @BASEBOARD_FAB2_LIB.BASEBOARD_FAB2(SCH_1):GND

CAP_A  I201  C2D2   [CAP_A_0603V-22.0UF,4V,20%,X6S,A]
    1  PVCCIN_CPU1        A  @BASEBOARD_FAB2_LIB.BASEBOARD_FAB2(SCH_1):PVCCIN_CPU1
    2  GND                B  @BASEBOARD_FAB2_LIB.BASEBOARD_FAB2(SCH_1):GND

CAP_A  I202  C2D3   [CAP_A_0603V-22.0UF,4V,20%,X6S,A]
    1  PVCCIN_CPU1        A  @BASEBOARD_FAB2_LIB.BASEBOARD_FAB2(SCH_1):PVCCIN_CPU1
    2  GND                B  @BASEBOARD_FAB2_LIB.BASEBOARD_FAB2(SCH_1):GND

CAP  I187  C2D4   [CAP_0603LF-10UF,4V,20%,X6S,E15A]
    1  PVDDQ_KLM          A  @BASEBOARD_FAB2_LIB.BASEBOARD_FAB2(SCH_1):PVDDQ_KLM
    2  GND                B  @BASEBOARD_FAB2_LIB.BASEBOARD_FAB2(SCH_1):GND

CAP  I188  C2D5   [CAP_0603LF-10UF,4V,20%,X6S,E15A]
    1  PVDDQ_KLM          A  @BASEBOARD_FAB2_LIB.BASEBOARD_FAB2(SCH_1):PVDDQ_KLM
    2  GND                B  @BASEBOARD_FAB2_LIB.BASEBOARD_FAB2(SCH_1):GND

CAP  I190  C2D6   [CAP_0603LF-10UF,4V,20%,X6S,E15A]
    1  PVDDQ_KLM          A  @BASEBOARD_FAB2_LIB.BASEBOARD_FAB2(SCH_1):PVDDQ_KLM
    2  GND                B  @BASEBOARD_FAB2_LIB.BASEBOARD_FAB2(SCH_1):GND

CAP  I186  C2D7   [CAP_0603LF-10UF,4V,20%,X6S,E15A]
    1  PVDDQ_KLM          A  @BASEBOARD_FAB2_LIB.BASEBOARD_FAB2(SCH_1):PVDDQ_KLM
    2  GND                B  @BASEBOARD_FAB2_LIB.BASEBOARD_FAB2(SCH_1):GND

CAP  I33  C2D8   [CAP_0603LF-10UF,4V,20%,X6S,E15A]
    1  PVSA_CPU1          A  @BASEBOARD_FAB2_LIB.BASEBOARD_FAB2(SCH_1):PVSA_CPU1
    2  GND                B  @BASEBOARD_FAB2_LIB.BASEBOARD_FAB2(SCH_1):GND

CAP  I43  C2D9   [CAP_0603LF-10UF,4V,20%,X6S,E15A]
    1  PVSA_CPU1          A  @BASEBOARD_FAB2_LIB.BASEBOARD_FAB2(SCH_1):PVSA_CPU1
    2  GND                B  @BASEBOARD_FAB2_LIB.BASEBOARD_FAB2(SCH_1):GND

CAP  I37  C2D10  [CAP_0603LF-10UF,4V,20%,X6S,E15A]
    1  PVSA_CPU1          A  @BASEBOARD_FAB2_LIB.BASEBOARD_FAB2(SCH_1):PVSA_CPU1
    2  GND                B  @BASEBOARD_FAB2_LIB.BASEBOARD_FAB2(SCH_1):GND

CAP  I42  C2D11  [CAP_0603LF-10UF,4V,20%,X6S,E15A]
    1  PVSA_CPU1          A  @BASEBOARD_FAB2_LIB.BASEBOARD_FAB2(SCH_1):PVSA_CPU1
    2  GND                B  @BASEBOARD_FAB2_LIB.BASEBOARD_FAB2(SCH_1):GND

CAP_A  I59  C2D12  [CAP_A_0603V-22.0UF,4V,20%,X6S,A]
    1  PVCCIN_CPU1        A  @BASEBOARD_FAB2_LIB.BASEBOARD_FAB2(SCH_1):PVCCIN_CPU1
    2  GND                B  @BASEBOARD_FAB2_LIB.BASEBOARD_FAB2(SCH_1):GND

CAP_A  I73  C2D13  [CAP_A_0603V-22.0UF,4V,20%,X6S,A]
    1  PVCCIN_CPU1        A  @BASEBOARD_FAB2_LIB.BASEBOARD_FAB2(SCH_1):PVCCIN_CPU1
    2  GND                B  @BASEBOARD_FAB2_LIB.BASEBOARD_FAB2(SCH_1):GND

CAP_A  I76  C2D14  [CAP_A_0603V-22.0UF,4V,20%,X6S,A]
    1  PVCCIN_CPU1        A  @BASEBOARD_FAB2_LIB.BASEBOARD_FAB2(SCH_1):PVCCIN_CPU1
    2  GND                B  @BASEBOARD_FAB2_LIB.BASEBOARD_FAB2(SCH_1):GND

CAP_A  I159  C2D15  [CAP_A_0603V-22.0UF,4V,20%,X6S,A]
    1  PVCCIN_CPU1        A  @BASEBOARD_FAB2_LIB.BASEBOARD_FAB2(SCH_1):PVCCIN_CPU1
    2  GND                B  @BASEBOARD_FAB2_LIB.BASEBOARD_FAB2(SCH_1):GND

CAP_A  I124  C2D16  [CAP_A_0603V-22.0UF,4V,20%,X6S,A]
    1  PVCCIN_CPU1        A  @BASEBOARD_FAB2_LIB.BASEBOARD_FAB2(SCH_1):PVCCIN_CPU1
    2  GND                B  @BASEBOARD_FAB2_LIB.BASEBOARD_FAB2(SCH_1):GND

CAP_A  I114  C2D17  [CAP_A_0603V-22.0UF,4V,20%,X6S,A]
    1  PVCCIN_CPU1        A  @BASEBOARD_FAB2_LIB.BASEBOARD_FAB2(SCH_1):PVCCIN_CPU1
    2  GND                B  @BASEBOARD_FAB2_LIB.BASEBOARD_FAB2(SCH_1):GND

CAP_A  I197  C2D18  [CAP_A_0603V-22.0UF,4V,20%,X6S,A]
    1  PVCCMCP_CPU1       A  @BASEBOARD_FAB2_LIB.BASEBOARD_FAB2(SCH_1):PVCCMCP_CPU1
    2  GND                B  @BASEBOARD_FAB2_LIB.BASEBOARD_FAB2(SCH_1):GND

CAP_A  I75  C2D19  [CAP_A_0603V-22.0UF,4V,20%,X6S,A]
    1  PVCCIN_CPU1        A  @BASEBOARD_FAB2_LIB.BASEBOARD_FAB2(SCH_1):PVCCIN_CPU1
    2  GND                B  @BASEBOARD_FAB2_LIB.BASEBOARD_FAB2(SCH_1):GND

CAP_A  I79  C2D20  [CAP_A_0603V-22.0UF,4V,20%,X6S,A]
    1  PVCCIN_CPU1        A  @BASEBOARD_FAB2_LIB.BASEBOARD_FAB2(SCH_1):PVCCIN_CPU1
    2  GND                B  @BASEBOARD_FAB2_LIB.BASEBOARD_FAB2(SCH_1):GND

CAP_A  I65  C2D21  [CAP_A_0603V-22.0UF,4V,20%,X6S,A]
    1  PVCCIN_CPU1        A  @BASEBOARD_FAB2_LIB.BASEBOARD_FAB2(SCH_1):PVCCIN_CPU1
    2  GND                B  @BASEBOARD_FAB2_LIB.BASEBOARD_FAB2(SCH_1):GND

CAP_A  I61  C2D22  [CAP_A_0603V-22.0UF,4V,20%,X6S,A]
    1  PVCCIN_CPU1        A  @BASEBOARD_FAB2_LIB.BASEBOARD_FAB2(SCH_1):PVCCIN_CPU1
    2  GND                B  @BASEBOARD_FAB2_LIB.BASEBOARD_FAB2(SCH_1):GND

CAP_A  I112  C2D23  [CAP_A_0603V-22.0UF,4V,20%,X6S,A]
    1  PVCCIN_CPU1        A  @BASEBOARD_FAB2_LIB.BASEBOARD_FAB2(SCH_1):PVCCIN_CPU1
    2  GND                B  @BASEBOARD_FAB2_LIB.BASEBOARD_FAB2(SCH_1):GND

CAP_A  I80  C2D24  [CAP_A_0603V-22.0UF,4V,20%,X6S,A]
    1  PVCCIN_CPU1        A  @BASEBOARD_FAB2_LIB.BASEBOARD_FAB2(SCH_1):PVCCIN_CPU1
    2  GND                B  @BASEBOARD_FAB2_LIB.BASEBOARD_FAB2(SCH_1):GND

CAP_A  I82  C2D25  [CAP_A_0603V-22.0UF,4V,20%,X6S,A]
    1  PVCCIN_CPU1        A  @BASEBOARD_FAB2_LIB.BASEBOARD_FAB2(SCH_1):PVCCIN_CPU1
    2  GND                B  @BASEBOARD_FAB2_LIB.BASEBOARD_FAB2(SCH_1):GND

CAP_A  I108  C2D26  [CAP_A_0603V-22.0UF,4V,20%,X6S,A]
    1  PVCCIN_CPU1        A  @BASEBOARD_FAB2_LIB.BASEBOARD_FAB2(SCH_1):PVCCIN_CPU1
    2  GND                B  @BASEBOARD_FAB2_LIB.BASEBOARD_FAB2(SCH_1):GND

CAP_A  I66  C2D27  [CAP_A_0603V-22.0UF,4V,20%,X6S,A]
    1  PVCCIN_CPU1        A  @BASEBOARD_FAB2_LIB.BASEBOARD_FAB2(SCH_1):PVCCIN_CPU1
    2  GND                B  @BASEBOARD_FAB2_LIB.BASEBOARD_FAB2(SCH_1):GND

CAP_A  I198  C2D28  [CAP_A_0603V-22.0UF,4V,20%,X6S,A]
    1  PVCCMCP_CPU1       A  @BASEBOARD_FAB2_LIB.BASEBOARD_FAB2(SCH_1):PVCCMCP_CPU1
    2  GND                B  @BASEBOARD_FAB2_LIB.BASEBOARD_FAB2(SCH_1):GND

CAP_A  I199  C2D29  [CAP_A_0603V-22.0UF,4V,20%,X6S,A]
    1  PVCCMCP_CPU1       A  @BASEBOARD_FAB2_LIB.BASEBOARD_FAB2(SCH_1):PVCCMCP_CPU1
    2  GND                B  @BASEBOARD_FAB2_LIB.BASEBOARD_FAB2(SCH_1):GND

CAP_A  I83  C2D30  [CAP_A_0603V-22.0UF,4V,20%,X6S,A]
    1  PVCCIN_CPU1        A  @BASEBOARD_FAB2_LIB.BASEBOARD_FAB2(SCH_1):PVCCIN_CPU1
    2  GND                B  @BASEBOARD_FAB2_LIB.BASEBOARD_FAB2(SCH_1):GND

CAP_A  I63  C2D31  [CAP_A_0603V-22.0UF,4V,20%,X6S,A]
    1  PVCCIN_CPU1        A  @BASEBOARD_FAB2_LIB.BASEBOARD_FAB2(SCH_1):PVCCIN_CPU1
    2  GND                B  @BASEBOARD_FAB2_LIB.BASEBOARD_FAB2(SCH_1):GND

CAP_A  I90  C2D32  [CAP_A_0603V-22.0UF,4V,20%,X6S,A]
    1  PVCCIN_CPU1        A  @BASEBOARD_FAB2_LIB.BASEBOARD_FAB2(SCH_1):PVCCIN_CPU1
    2  GND                B  @BASEBOARD_FAB2_LIB.BASEBOARD_FAB2(SCH_1):GND

CAP_A  I85  C2D33  [CAP_A_0603V-22.0UF,4V,20%,X6S,A]
    1  PVCCIN_CPU1        A  @BASEBOARD_FAB2_LIB.BASEBOARD_FAB2(SCH_1):PVCCIN_CPU1
    2  GND                B  @BASEBOARD_FAB2_LIB.BASEBOARD_FAB2(SCH_1):GND

CAP_A  I122  C2D34  [CAP_A_0603V-22.0UF,4V,20%,X6S,A]
    1  PVCCIN_CPU1        A  @BASEBOARD_FAB2_LIB.BASEBOARD_FAB2(SCH_1):PVCCIN_CPU1
    2  GND                B  @BASEBOARD_FAB2_LIB.BASEBOARD_FAB2(SCH_1):GND

CAP_A  I161  C2D35  [CAP_A_0603V-22.0UF,4V,20%,X6S,A]
    1  PVCCIN_CPU1        A  @BASEBOARD_FAB2_LIB.BASEBOARD_FAB2(SCH_1):PVCCIN_CPU1
    2  GND                B  @BASEBOARD_FAB2_LIB.BASEBOARD_FAB2(SCH_1):GND

CAP_A  I70  C2D36  [CAP_A_0603V-22.0UF,4V,20%,X6S,A]
    1  PVCCIN_CPU1        A  @BASEBOARD_FAB2_LIB.BASEBOARD_FAB2(SCH_1):PVCCIN_CPU1
    2  GND                B  @BASEBOARD_FAB2_LIB.BASEBOARD_FAB2(SCH_1):GND

CAP_A  I119  C2D37  [CAP_A_0603V-22.0UF,4V,20%,X6S,A]
    1  PVCCIN_CPU1        A  @BASEBOARD_FAB2_LIB.BASEBOARD_FAB2(SCH_1):PVCCIN_CPU1
    2  GND                B  @BASEBOARD_FAB2_LIB.BASEBOARD_FAB2(SCH_1):GND

CAP_A  I160  C2D38  [CAP_A_0603V-22.0UF,4V,20%,X6S,A]
    1  PVCCIN_CPU1        A  @BASEBOARD_FAB2_LIB.BASEBOARD_FAB2(SCH_1):PVCCIN_CPU1
    2  GND                B  @BASEBOARD_FAB2_LIB.BASEBOARD_FAB2(SCH_1):GND

CAP_A  I165  C2D39  [CAP_A_0603V-22.0UF,4V,20%,X6S,A]
    1  PVCCMCP_CPU1       A  @BASEBOARD_FAB2_LIB.BASEBOARD_FAB2(SCH_1):PVCCMCP_CPU1
    2  GND                B  @BASEBOARD_FAB2_LIB.BASEBOARD_FAB2(SCH_1):GND

CAP_A  I10  C2D40  [CAP_A_0603V-22.0UF,4V,20%,X6S,A]
    1  PVCCMCP_CPU1       A  @BASEBOARD_FAB2_LIB.BASEBOARD_FAB2(SCH_1):PVCCMCP_CPU1
    2  GND                B  @BASEBOARD_FAB2_LIB.BASEBOARD_FAB2(SCH_1):GND

CAP  I180  C2D41  [CAP_0603LF-10UF,4V,20%,X6S,E15A]
    1  PVDDQ_GHJ          A  @BASEBOARD_FAB2_LIB.BASEBOARD_FAB2(SCH_1):PVDDQ_GHJ
    2  GND                B  @BASEBOARD_FAB2_LIB.BASEBOARD_FAB2(SCH_1):GND

CAP  I183  C2D42  [CAP_0603LF-10UF,4V,20%,X6S,E15A]
    1  PVDDQ_GHJ          A  @BASEBOARD_FAB2_LIB.BASEBOARD_FAB2(SCH_1):PVDDQ_GHJ
    2  GND                B  @BASEBOARD_FAB2_LIB.BASEBOARD_FAB2(SCH_1):GND

CAP  I179  C2D43  [CAP_0603LF-10UF,4V,20%,X6S,E15A]
    1  PVDDQ_GHJ          A  @BASEBOARD_FAB2_LIB.BASEBOARD_FAB2(SCH_1):PVDDQ_GHJ
    2  GND                B  @BASEBOARD_FAB2_LIB.BASEBOARD_FAB2(SCH_1):GND

CAP  I181  C2D44  [CAP_0603LF-10UF,4V,20%,X6S,E15A]
    1  PVDDQ_GHJ          A  @BASEBOARD_FAB2_LIB.BASEBOARD_FAB2(SCH_1):PVDDQ_GHJ
    2  GND                B  @BASEBOARD_FAB2_LIB.BASEBOARD_FAB2(SCH_1):GND

CAP_A  I123  C2D45  [CAP_A_0603V-22.0UF,4V,20%,X6S,A]
    1  PVCCIN_CPU1        A  @BASEBOARD_FAB2_LIB.BASEBOARD_FAB2(SCH_1):PVCCIN_CPU1
    2  GND                B  @BASEBOARD_FAB2_LIB.BASEBOARD_FAB2(SCH_1):GND

CAP_A  I204  C2D46  [CAP_A_0603V-22.0UF,4V,20%,X6S,A]
    1  PVCCIN_CPU1        A  @BASEBOARD_FAB2_LIB.BASEBOARD_FAB2(SCH_1):PVCCIN_CPU1
    2  GND                B  @BASEBOARD_FAB2_LIB.BASEBOARD_FAB2(SCH_1):GND

CAP_A  I203  C2D47  [CAP_A_0603V-22.0UF,4V,20%,X6S,A]
    1  PVCCIN_CPU1        A  @BASEBOARD_FAB2_LIB.BASEBOARD_FAB2(SCH_1):PVCCIN_CPU1
    2  GND                B  @BASEBOARD_FAB2_LIB.BASEBOARD_FAB2(SCH_1):GND

CAP_A  I201  C2F1   [CAP_A_0603V-47UF,4V,20%,X5R,60A]
    1  PVDDQ_GHJ          A  @BASEBOARD_FAB2_LIB.BASEBOARD_FAB2(SCH_1):PVDDQ_GHJ
    2  GND                B  @BASEBOARD_FAB2_LIB.BASEBOARD_FAB2(SCH_1):GND

CAP_A  I47  C2F2   [CAP_A_0603V-47UF,4V,20%,X5R,60A]
    1  PVTT_GHJ           A  @BASEBOARD_FAB2_LIB.BASEBOARD_FAB2(SCH_1):PVTT_GHJ
    2  GND                B  @BASEBOARD_FAB2_LIB.BASEBOARD_FAB2(SCH_1):GND

CAP_A  I219  C2G1   [CAP_A_0603V-22.0UF,4V,20%,X6S,A]
    1  PVDDQ_GHJ          A  @BASEBOARD_FAB2_LIB.BASEBOARD_FAB2(SCH_1):PVDDQ_GHJ
    2  GND                B  @BASEBOARD_FAB2_LIB.BASEBOARD_FAB2(SCH_1):GND

CAP_A  I217  C2G2   [CAP_A_0603V-22.0UF,4V,20%,X6S,A]
    1  PVDDQ_GHJ          A  @BASEBOARD_FAB2_LIB.BASEBOARD_FAB2(SCH_1):PVDDQ_GHJ
    2  GND                B  @BASEBOARD_FAB2_LIB.BASEBOARD_FAB2(SCH_1):GND

CAP_A  I216  C2G3   [CAP_A_0603V-22.0UF,4V,20%,X6S,A]
    1  PVDDQ_GHJ          A  @BASEBOARD_FAB2_LIB.BASEBOARD_FAB2(SCH_1):PVDDQ_GHJ
    2  GND                B  @BASEBOARD_FAB2_LIB.BASEBOARD_FAB2(SCH_1):GND

CAP_A  I215  C2G4   [CAP_A_0603V-22.0UF,4V,20%,X6S,A]
    1  PVDDQ_GHJ          A  @BASEBOARD_FAB2_LIB.BASEBOARD_FAB2(SCH_1):PVDDQ_GHJ
    2  GND                B  @BASEBOARD_FAB2_LIB.BASEBOARD_FAB2(SCH_1):GND

CAP_A  I214  C2G5   [CAP_A_0603V-22.0UF,4V,20%,X6S,A]
    1  PVDDQ_GHJ          A  @BASEBOARD_FAB2_LIB.BASEBOARD_FAB2(SCH_1):PVDDQ_GHJ
    2  GND                B  @BASEBOARD_FAB2_LIB.BASEBOARD_FAB2(SCH_1):GND

CAP_A  I213  C2G6   [CAP_A_0603V-22.0UF,4V,20%,X6S,A]
    1  PVDDQ_GHJ          A  @BASEBOARD_FAB2_LIB.BASEBOARD_FAB2(SCH_1):PVDDQ_GHJ
    2  GND                B  @BASEBOARD_FAB2_LIB.BASEBOARD_FAB2(SCH_1):GND

CAP  I92  C2G7   [CAP_0805-100UF,4V,20%,X5R,6024A]
    1  PVDDQ_GHJ          A  @BASEBOARD_FAB2_LIB.BASEBOARD_FAB2(SCH_1):PVDDQ_GHJ
    2  GND                B  @BASEBOARD_FAB2_LIB.BASEBOARD_FAB2(SCH_1):GND

CAP_A  I197  C2G8   [CAP_A_0603V-47UF,4V,20%,X5R,60A]
    1  PVDDQ_GHJ          A  @BASEBOARD_FAB2_LIB.BASEBOARD_FAB2(SCH_1):PVDDQ_GHJ
    2  GND                B  @BASEBOARD_FAB2_LIB.BASEBOARD_FAB2(SCH_1):GND

CAP_A  I218  C2G9   [CAP_A_0603V-22.0UF,4V,20%,X6S,A]
    1  PVDDQ_GHJ          A  @BASEBOARD_FAB2_LIB.BASEBOARD_FAB2(SCH_1):PVDDQ_GHJ
    2  GND                B  @BASEBOARD_FAB2_LIB.BASEBOARD_FAB2(SCH_1):GND

CAP_A  I223  C2G10  [CAP_A_0603V-22.0UF,4V,20%,X6S,A]
    1  PVDDQ_GHJ          A  @BASEBOARD_FAB2_LIB.BASEBOARD_FAB2(SCH_1):PVDDQ_GHJ
    2  GND                B  @BASEBOARD_FAB2_LIB.BASEBOARD_FAB2(SCH_1):GND

CAP_A  I221  C2G11  [CAP_A_0603V-22.0UF,4V,20%,X6S,A]
    1  PVDDQ_GHJ          A  @BASEBOARD_FAB2_LIB.BASEBOARD_FAB2(SCH_1):PVDDQ_GHJ
    2  GND                B  @BASEBOARD_FAB2_LIB.BASEBOARD_FAB2(SCH_1):GND

CAP_A  I220  C2G12  [CAP_A_0603V-22.0UF,4V,20%,X6S,A]
    1  PVDDQ_GHJ          A  @BASEBOARD_FAB2_LIB.BASEBOARD_FAB2(SCH_1):PVDDQ_GHJ
    2  GND                B  @BASEBOARD_FAB2_LIB.BASEBOARD_FAB2(SCH_1):GND

CAP_A  I210  C2G13  [CAP_A_0603V-22.0UF,4V,20%,X6S,A]
    1  PVDDQ_GHJ          A  @BASEBOARD_FAB2_LIB.BASEBOARD_FAB2(SCH_1):PVDDQ_GHJ
    2  GND                B  @BASEBOARD_FAB2_LIB.BASEBOARD_FAB2(SCH_1):GND

CAP_A  I209  C2G14  [CAP_A_0603V-22.0UF,4V,20%,X6S,A]
    1  PVDDQ_GHJ          A  @BASEBOARD_FAB2_LIB.BASEBOARD_FAB2(SCH_1):PVDDQ_GHJ
    2  GND                B  @BASEBOARD_FAB2_LIB.BASEBOARD_FAB2(SCH_1):GND

CAP_A  I200  C2G15  [CAP_A_0603V-47UF,4V,20%,X5R,60A]
    1  PVDDQ_GHJ          A  @BASEBOARD_FAB2_LIB.BASEBOARD_FAB2(SCH_1):PVDDQ_GHJ
    2  GND                B  @BASEBOARD_FAB2_LIB.BASEBOARD_FAB2(SCH_1):GND

CAP  I110  C2G16  [CAP_0805-100UF,4V,20%,X5R,6024A]
    1  PVDDQ_GHJ          A  @BASEBOARD_FAB2_LIB.BASEBOARD_FAB2(SCH_1):PVDDQ_GHJ
    2  GND                B  @BASEBOARD_FAB2_LIB.BASEBOARD_FAB2(SCH_1):GND

CAP  I153  C2L2   [CAP_0402LF-220PF,50V,10%,X7R,AA]
    2  VSENSE_P1V05_PCH_STBY_AVSN      B  @BASEBOARD_FAB2_LIB.BASEBOARD_FAB2(SCH_1):VSENSE_P1V05_PCH_STBY_AVSN
    1  VR_P1V05_PCH_STBY_AVSP      A  @BASEBOARD_FAB2_LIB.BASEBOARD_FAB2(SCH_1):VR_P1V05_PCH_STBY_AVSP

CAP_A  I194  C2L3   [CAP_A_0402V-0.01UF,25V,10%,X7RA]
    1  SATA6G_PCH_PCIE_UP_SATA_RXN<3>      A  @BASEBOARD_FAB2_LIB.BASEBOARD_FAB2(SCH_1):SATA6G_PCH_PCIE_UP_SATA_RXN<3>
    2  SATA6G_P3_RX_C_DN      B  @BASEBOARD_FAB2_LIB.BASEBOARD_FAB2(SCH_1):SATA6G_P3_RX_C_DN

CAP_A  I192  C2L4   [CAP_A_0402V-0.01UF,25V,10%,X7RA]
    1  SATA6G_PCH_PCIE_UP_SATA_RXP<3>      A  @BASEBOARD_FAB2_LIB.BASEBOARD_FAB2(SCH_1):SATA6G_PCH_PCIE_UP_SATA_RXP<3>
    2  SATA6G_P3_RX_C_DP      B  @BASEBOARD_FAB2_LIB.BASEBOARD_FAB2(SCH_1):SATA6G_P3_RX_C_DP

CAP_A  I209  C2L5   [CAP_A_0402V-0.01UF,25V,10%,X7RA]
    1  SATA6G_PCH_PCIE_UP_SATA_RXN<7>      A  @BASEBOARD_FAB2_LIB.BASEBOARD_FAB2(SCH_1):SATA6G_PCH_PCIE_UP_SATA_RXN<7>
    2  SATA6G_P7_RX_C_DN      B  @BASEBOARD_FAB2_LIB.BASEBOARD_FAB2(SCH_1):SATA6G_P7_RX_C_DN

CAP_A  I166  C2L6   [CAP_A_0402V-0.01UF,25V,10%,X7RA]
    1  SATA6G_PCH_PCIE_UP_SATA_RXN<1>      A  @BASEBOARD_FAB2_LIB.BASEBOARD_FAB2(SCH_1):SATA6G_PCH_PCIE_UP_SATA_RXN<1>
    2  SATA6G_P1_RX_C_DN      B  @BASEBOARD_FAB2_LIB.BASEBOARD_FAB2(SCH_1):SATA6G_P1_RX_C_DN

CAP_A  I206  C2L7   [CAP_A_0402V-0.01UF,25V,10%,X7RA]
    1  SATA6G_PCH_PCIE_UP_SATA_RXP<7>      A  @BASEBOARD_FAB2_LIB.BASEBOARD_FAB2(SCH_1):SATA6G_PCH_PCIE_UP_SATA_RXP<7>
    2  SATA6G_P7_RX_C_DP      B  @BASEBOARD_FAB2_LIB.BASEBOARD_FAB2(SCH_1):SATA6G_P7_RX_C_DP

CAP_A  I151  C2L8   [CAP_A_0402V-1.0UF,6.3V,10%,X6SA]
    1  VR_PVNN_PCH_VDD      A  @BASEBOARD_FAB2_LIB.BASEBOARD_FAB2(SCH_1):VR_PVNN_PCH_VDD
    2  GND                B  @BASEBOARD_FAB2_LIB.BASEBOARD_FAB2(SCH_1):GND

CAP_A  I207  C2L9   [CAP_A_0402V-0.01UF,25V,10%,X7RA]
    1  SATA6G_PCH_PCIE_UP_SATA_RXN<5>      A  @BASEBOARD_FAB2_LIB.BASEBOARD_FAB2(SCH_1):SATA6G_PCH_PCIE_UP_SATA_RXN<5>
    2  SATA6G_P5_RX_C_DN      B  @BASEBOARD_FAB2_LIB.BASEBOARD_FAB2(SCH_1):SATA6G_P5_RX_C_DN

CAP_A  I173  C2L10  [CAP_A_0402V-0.01UF,25V,10%,X7RA]
    1  SATA6G_PCH_PCIE_UP_SATA_RXP<1>      A  @BASEBOARD_FAB2_LIB.BASEBOARD_FAB2(SCH_1):SATA6G_PCH_PCIE_UP_SATA_RXP<1>
    2  SATA6G_P1_RX_C_DP      B  @BASEBOARD_FAB2_LIB.BASEBOARD_FAB2(SCH_1):SATA6G_P1_RX_C_DP

CAP_A  I169  C2L11  [CAP_A_0402V-0.1UF,16V,10%,X7R,A]
    1  VR_PVNN_PCH_VDD      A  @BASEBOARD_FAB2_LIB.BASEBOARD_FAB2(SCH_1):VR_PVNN_PCH_VDD
    2  GND                B  @BASEBOARD_FAB2_LIB.BASEBOARD_FAB2(SCH_1):GND

CAP_A  I196  C2L12  [CAP_A_0402V-0.01UF,25V,10%,X7RA]
    1  SATA6G_PCH_PCIE_UP_SATA_RXP<5>      A  @BASEBOARD_FAB2_LIB.BASEBOARD_FAB2(SCH_1):SATA6G_PCH_PCIE_UP_SATA_RXP<5>
    2  SATA6G_P5_RX_C_DP      B  @BASEBOARD_FAB2_LIB.BASEBOARD_FAB2(SCH_1):SATA6G_P5_RX_C_DP

CAP_A  I165  C2L13  [CAP_A_0402V-0.01UF,25V,10%,X7RA]
    1  SATA6G_PCH_PCIE_UP_SATA_RXN<2>      A  @BASEBOARD_FAB2_LIB.BASEBOARD_FAB2(SCH_1):SATA6G_PCH_PCIE_UP_SATA_RXN<2>
    2  SATA6G_P2_RX_C_DN      B  @BASEBOARD_FAB2_LIB.BASEBOARD_FAB2(SCH_1):SATA6G_P2_RX_C_DN

CAP_A  I208  C2L14  [CAP_A_0402V-0.01UF,25V,10%,X7RA]
    1  SATA6G_PCH_PCIE_UP_SATA_RXN<6>      A  @BASEBOARD_FAB2_LIB.BASEBOARD_FAB2(SCH_1):SATA6G_PCH_PCIE_UP_SATA_RXN<6>
    2  SATA6G_P6_RX_C_DN      B  @BASEBOARD_FAB2_LIB.BASEBOARD_FAB2(SCH_1):SATA6G_P6_RX_C_DN

CAP_A  I191  C2L15  [CAP_A_0402V-0.01UF,25V,10%,X7RA]
    1  SATA6G_PCH_PCIE_UP_SATA_RXP<2>      A  @BASEBOARD_FAB2_LIB.BASEBOARD_FAB2(SCH_1):SATA6G_PCH_PCIE_UP_SATA_RXP<2>
    2  SATA6G_P2_RX_C_DP      B  @BASEBOARD_FAB2_LIB.BASEBOARD_FAB2(SCH_1):SATA6G_P2_RX_C_DP

CAP_A  I205  C2L16  [CAP_A_0402V-0.01UF,25V,10%,X7RA]
    1  SATA6G_PCH_PCIE_UP_SATA_RXP<6>      A  @BASEBOARD_FAB2_LIB.BASEBOARD_FAB2(SCH_1):SATA6G_PCH_PCIE_UP_SATA_RXP<6>
    2  SATA6G_P6_RX_C_DP      B  @BASEBOARD_FAB2_LIB.BASEBOARD_FAB2(SCH_1):SATA6G_P6_RX_C_DP

CAP_A  I174  C2L17  [CAP_A_0402V-0.01UF,25V,10%,X7RA]
    1  SATA6G_PCH_PCIE_UP_SATA_RXN<0>      A  @BASEBOARD_FAB2_LIB.BASEBOARD_FAB2(SCH_1):SATA6G_PCH_PCIE_UP_SATA_RXN<0>
    2  SATA6G_P0_RX_C_DN      B  @BASEBOARD_FAB2_LIB.BASEBOARD_FAB2(SCH_1):SATA6G_P0_RX_C_DN

CAP_A  I197  C2L18  [CAP_A_0402V-0.01UF,25V,10%,X7RA]
    1  SATA6G_PCH_PCIE_UP_SATA_RXN<4>      A  @BASEBOARD_FAB2_LIB.BASEBOARD_FAB2(SCH_1):SATA6G_PCH_PCIE_UP_SATA_RXN<4>
    2  SATA6G_P4_RX_C_DN      B  @BASEBOARD_FAB2_LIB.BASEBOARD_FAB2(SCH_1):SATA6G_P4_RX_C_DN

CAP_A  I172  C2L19  [CAP_A_0402V-0.01UF,25V,10%,X7RA]
    1  SATA6G_PCH_PCIE_UP_SATA_RXP<0>      A  @BASEBOARD_FAB2_LIB.BASEBOARD_FAB2(SCH_1):SATA6G_PCH_PCIE_UP_SATA_RXP<0>
    2  SATA6G_P0_RX_C_DP      B  @BASEBOARD_FAB2_LIB.BASEBOARD_FAB2(SCH_1):SATA6G_P0_RX_C_DP

CAP_A  I195  C2L20  [CAP_A_0402V-0.01UF,25V,10%,X7RA]
    1  SATA6G_PCH_PCIE_UP_SATA_RXP<4>      A  @BASEBOARD_FAB2_LIB.BASEBOARD_FAB2(SCH_1):SATA6G_PCH_PCIE_UP_SATA_RXP<4>
    2  SATA6G_P4_RX_C_DP      B  @BASEBOARD_FAB2_LIB.BASEBOARD_FAB2(SCH_1):SATA6G_P4_RX_C_DP

CAP_A  I259  C2L21  [CAP_A_0402V-0.01UF,25V,10%,X7RA]
    2  SATA6G_PCH_PCIE_UP_SATA_TXN<7>      B  @BASEBOARD_FAB2_LIB.BASEBOARD_FAB2(SCH_1):SATA6G_PCH_PCIE_UP_SATA_TXN<7>
    1  SATA6G_P7_TX_C_DN      A  @BASEBOARD_FAB2_LIB.BASEBOARD_FAB2(SCH_1):SATA6G_P7_TX_C_DN

CAP_A  I234  C2L22  [CAP_A_0402V-0.01UF,25V,10%,X7RA]
    2  SATA6G_PCH_PCIE_UP_SATA_TXN<3>      B  @BASEBOARD_FAB2_LIB.BASEBOARD_FAB2(SCH_1):SATA6G_PCH_PCIE_UP_SATA_TXN<3>
    1  SATA6G_P3_TX_C_DN      A  @BASEBOARD_FAB2_LIB.BASEBOARD_FAB2(SCH_1):SATA6G_P3_TX_C_DN

CAP_A  I241  C2L23  [CAP_A_0402V-0.01UF,25V,10%,X7RA]
    2  SATA6G_PCH_PCIE_UP_SATA_TXP<3>      B  @BASEBOARD_FAB2_LIB.BASEBOARD_FAB2(SCH_1):SATA6G_PCH_PCIE_UP_SATA_TXP<3>
    1  SATA6G_P3_TX_C_DP      A  @BASEBOARD_FAB2_LIB.BASEBOARD_FAB2(SCH_1):SATA6G_P3_TX_C_DP

CAP_A  I258  C2L24  [CAP_A_0402V-0.01UF,25V,10%,X7RA]
    2  SATA6G_PCH_PCIE_UP_SATA_TXP<7>      B  @BASEBOARD_FAB2_LIB.BASEBOARD_FAB2(SCH_1):SATA6G_PCH_PCIE_UP_SATA_TXP<7>
    1  SATA6G_P7_TX_C_DP      A  @BASEBOARD_FAB2_LIB.BASEBOARD_FAB2(SCH_1):SATA6G_P7_TX_C_DP

CAPP  I79  C2L25  [CAPP_SM-470UF,2V,20%,ALUM,6990A]
    1  P1V05_PCH_STBY      A  @BASEBOARD_FAB2_LIB.BASEBOARD_FAB2(SCH_1):P1V05_PCH_STBY
    2  GND                B  @BASEBOARD_FAB2_LIB.BASEBOARD_FAB2(SCH_1):GND

CAP_A  I255  C2L26  [CAP_A_0402V-0.01UF,25V,10%,X7RA]
    2  SATA6G_PCH_PCIE_UP_SATA_TXN<5>      B  @BASEBOARD_FAB2_LIB.BASEBOARD_FAB2(SCH_1):SATA6G_PCH_PCIE_UP_SATA_TXN<5>
    1  SATA6G_P5_TX_C_DN      A  @BASEBOARD_FAB2_LIB.BASEBOARD_FAB2(SCH_1):SATA6G_P5_TX_C_DN

CAP_A  I240  C2L27  [CAP_A_0402V-0.01UF,25V,10%,X7RA]
    2  SATA6G_PCH_PCIE_UP_SATA_TXP<5>      B  @BASEBOARD_FAB2_LIB.BASEBOARD_FAB2(SCH_1):SATA6G_PCH_PCIE_UP_SATA_TXP<5>
    1  SATA6G_P5_TX_C_DP      A  @BASEBOARD_FAB2_LIB.BASEBOARD_FAB2(SCH_1):SATA6G_P5_TX_C_DP

CAP_A  I30  C2L28  [CAP_A_0402V-0.01UF,25V,10%,X7RA]
    1  SATA6G_RX_DP<1>      A  @BASEBOARD_FAB2_LIB.BASEBOARD_FAB2(SCH_1):SATA6G_RX_DP<1>
    2  SATA6G_P9_RX_C_DP      B  @BASEBOARD_FAB2_LIB.BASEBOARD_FAB2(SCH_1):SATA6G_P9_RX_C_DP

CAP_A  I32  C2L29  [CAP_A_0402V-0.01UF,25V,10%,X7RA]
    1  SATA6G_RX_DN<1>      A  @BASEBOARD_FAB2_LIB.BASEBOARD_FAB2(SCH_1):SATA6G_RX_DN<1>
    2  SATA6G_P9_RX_C_DN      B  @BASEBOARD_FAB2_LIB.BASEBOARD_FAB2(SCH_1):SATA6G_P9_RX_C_DN

CAP_A  I28  C2L30  [CAP_A_0402V-0.01UF,25V,10%,X7RA]
    1  SATA6G_RX_DP<0>      A  @BASEBOARD_FAB2_LIB.BASEBOARD_FAB2(SCH_1):SATA6G_RX_DP<0>
    2  SATA6G_P8_RX_C_DP      B  @BASEBOARD_FAB2_LIB.BASEBOARD_FAB2(SCH_1):SATA6G_P8_RX_C_DP

CAP_A  I29  C2L31  [CAP_A_0402V-0.01UF,25V,10%,X7RA]
    1  SATA6G_RX_DN<0>      A  @BASEBOARD_FAB2_LIB.BASEBOARD_FAB2(SCH_1):SATA6G_RX_DN<0>
    2  SATA6G_P8_RX_C_DN      B  @BASEBOARD_FAB2_LIB.BASEBOARD_FAB2(SCH_1):SATA6G_P8_RX_C_DN

CAP  I79  C2L32  [CAP_0805-47UF,4V,20%,X6S,C9533A]
    1  P1V8_PCH_STBY      A  @BASEBOARD_FAB2_LIB.BASEBOARD_FAB2(SCH_1):P1V8_PCH_STBY
    2  GND                B  @BASEBOARD_FAB2_LIB.BASEBOARD_FAB2(SCH_1):GND

CAP_A  I40  C2L33  [CAP_A_0402V-0.01UF,25V,10%,X7RA]
    1  SATA6G_RX_DP<3>      A  @BASEBOARD_FAB2_LIB.BASEBOARD_FAB2(SCH_1):SATA6G_RX_DP<3>
    2  SATA6G_P11_RX_C_DP      B  @BASEBOARD_FAB2_LIB.BASEBOARD_FAB2(SCH_1):SATA6G_P11_RX_C_DP

CAP_A  I41  C2L34  [CAP_A_0402V-0.01UF,25V,10%,X7RA]
    1  SATA6G_RX_DN<3>      A  @BASEBOARD_FAB2_LIB.BASEBOARD_FAB2(SCH_1):SATA6G_RX_DN<3>
    2  SATA6G_P11_RX_C_DN      B  @BASEBOARD_FAB2_LIB.BASEBOARD_FAB2(SCH_1):SATA6G_P11_RX_C_DN

CAP_A  I31  C2L35  [CAP_A_0402V-0.01UF,25V,10%,X7RA]
    1  SATA6G_RX_DP<2>      A  @BASEBOARD_FAB2_LIB.BASEBOARD_FAB2(SCH_1):SATA6G_RX_DP<2>
    2  SATA6G_P10_RX_C_DP      B  @BASEBOARD_FAB2_LIB.BASEBOARD_FAB2(SCH_1):SATA6G_P10_RX_C_DP

CAP_A  I39  C2L36  [CAP_A_0402V-0.01UF,25V,10%,X7RA]
    1  SATA6G_RX_DN<2>      A  @BASEBOARD_FAB2_LIB.BASEBOARD_FAB2(SCH_1):SATA6G_RX_DN<2>
    2  SATA6G_P10_RX_C_DN      B  @BASEBOARD_FAB2_LIB.BASEBOARD_FAB2(SCH_1):SATA6G_P10_RX_C_DN

CAP_A  I238  C2L37  [CAP_A_0402V-0.01UF,25V,10%,X7RA]
    2  SATA6G_PCH_PCIE_UP_SATA_TXN<4>      B  @BASEBOARD_FAB2_LIB.BASEBOARD_FAB2(SCH_1):SATA6G_PCH_PCIE_UP_SATA_TXN<4>
    1  SATA6G_P4_TX_C_DN      A  @BASEBOARD_FAB2_LIB.BASEBOARD_FAB2(SCH_1):SATA6G_P4_TX_C_DN

CAP_A  I256  C2L38  [CAP_A_0402V-0.01UF,25V,10%,X7RA]
    2  SATA6G_PCH_PCIE_UP_SATA_TXN<6>      B  @BASEBOARD_FAB2_LIB.BASEBOARD_FAB2(SCH_1):SATA6G_PCH_PCIE_UP_SATA_TXN<6>
    1  SATA6G_P6_TX_C_DN      A  @BASEBOARD_FAB2_LIB.BASEBOARD_FAB2(SCH_1):SATA6G_P6_TX_C_DN

CAP_A  I221  C2L39  [CAP_A_0402V-0.01UF,25V,10%,X7RA]
    2  SATA6G_PCH_PCIE_UP_SATA_TXP<0>      B  @BASEBOARD_FAB2_LIB.BASEBOARD_FAB2(SCH_1):SATA6G_PCH_PCIE_UP_SATA_TXP<0>
    1  SATA6G_P0_TX_C_DP      A  @BASEBOARD_FAB2_LIB.BASEBOARD_FAB2(SCH_1):SATA6G_P0_TX_C_DP

CAP_A  I220  C2L40  [CAP_A_0402V-0.01UF,25V,10%,X7RA]
    2  SATA6G_PCH_PCIE_UP_SATA_TXN<0>      B  @BASEBOARD_FAB2_LIB.BASEBOARD_FAB2(SCH_1):SATA6G_PCH_PCIE_UP_SATA_TXN<0>
    1  SATA6G_P0_TX_C_DN      A  @BASEBOARD_FAB2_LIB.BASEBOARD_FAB2(SCH_1):SATA6G_P0_TX_C_DN

CAP_A  I242  C2L41  [CAP_A_0402V-0.01UF,25V,10%,X7RA]
    2  SATA6G_PCH_PCIE_UP_SATA_TXP<2>      B  @BASEBOARD_FAB2_LIB.BASEBOARD_FAB2(SCH_1):SATA6G_PCH_PCIE_UP_SATA_TXP<2>
    1  SATA6G_P2_TX_C_DP      A  @BASEBOARD_FAB2_LIB.BASEBOARD_FAB2(SCH_1):SATA6G_P2_TX_C_DP

CAP_A  I233  C2L42  [CAP_A_0402V-0.01UF,25V,10%,X7RA]
    2  SATA6G_PCH_PCIE_UP_SATA_TXN<2>      B  @BASEBOARD_FAB2_LIB.BASEBOARD_FAB2(SCH_1):SATA6G_PCH_PCIE_UP_SATA_TXN<2>
    1  SATA6G_P2_TX_C_DN      A  @BASEBOARD_FAB2_LIB.BASEBOARD_FAB2(SCH_1):SATA6G_P2_TX_C_DN

CAP_A  I222  C2L43  [CAP_A_0402V-0.01UF,25V,10%,X7RA]
    2  SATA6G_PCH_PCIE_UP_SATA_TXP<1>      B  @BASEBOARD_FAB2_LIB.BASEBOARD_FAB2(SCH_1):SATA6G_PCH_PCIE_UP_SATA_TXP<1>
    1  SATA6G_P1_TX_C_DP      A  @BASEBOARD_FAB2_LIB.BASEBOARD_FAB2(SCH_1):SATA6G_P1_TX_C_DP

CAP_A  I228  C2L44  [CAP_A_0402V-0.01UF,25V,10%,X7RA]
    2  SATA6G_PCH_PCIE_UP_SATA_TXN<1>      B  @BASEBOARD_FAB2_LIB.BASEBOARD_FAB2(SCH_1):SATA6G_PCH_PCIE_UP_SATA_TXN<1>
    1  SATA6G_P1_TX_C_DN      A  @BASEBOARD_FAB2_LIB.BASEBOARD_FAB2(SCH_1):SATA6G_P1_TX_C_DN

CAP  I12  C2L45  [CAP_0805-22UF,6.3V,20%,X6S,C95A]
    1  P1V8_PCH_STBY      A  @BASEBOARD_FAB2_LIB.BASEBOARD_FAB2(SCH_1):P1V8_PCH_STBY
    2  GND                B  @BASEBOARD_FAB2_LIB.BASEBOARD_FAB2(SCH_1):GND

CAPP  I77  C2L46  [CAPP_SM-470UF,2V,20%,ALUM,6990A]
    1  P1V05_PCH_STBY      A  @BASEBOARD_FAB2_LIB.BASEBOARD_FAB2(SCH_1):P1V05_PCH_STBY
    2  GND                B  @BASEBOARD_FAB2_LIB.BASEBOARD_FAB2(SCH_1):GND

CAP_A  I239  C2L47  [CAP_A_0402V-0.01UF,25V,10%,X7RA]
    2  SATA6G_PCH_PCIE_UP_SATA_TXP<4>      B  @BASEBOARD_FAB2_LIB.BASEBOARD_FAB2(SCH_1):SATA6G_PCH_PCIE_UP_SATA_TXP<4>
    1  SATA6G_P4_TX_C_DP      A  @BASEBOARD_FAB2_LIB.BASEBOARD_FAB2(SCH_1):SATA6G_P4_TX_C_DP

CAP_A  I257  C2L48  [CAP_A_0402V-0.01UF,25V,10%,X7RA]
    2  SATA6G_PCH_PCIE_UP_SATA_TXP<6>      B  @BASEBOARD_FAB2_LIB.BASEBOARD_FAB2(SCH_1):SATA6G_PCH_PCIE_UP_SATA_TXP<6>
    1  SATA6G_P6_TX_C_DP      A  @BASEBOARD_FAB2_LIB.BASEBOARD_FAB2(SCH_1):SATA6G_P6_TX_C_DP

CAP_A  I5   C2L49  [CAP_A_0402V-0.01UF,25V,10%,X7RA]
    2  SATA6G_S1_RX_DP      B  @BASEBOARD_FAB2_LIB.BASEBOARD_FAB2(SCH_1):SATA6G_S1_RX_DP
    1  SATA6G_S1_RX_C_DP      A  @BASEBOARD_FAB2_LIB.BASEBOARD_FAB2(SCH_1):SATA6G_S1_RX_C_DP

CAP_A  I7   C2L50  [CAP_A_0402V-0.01UF,25V,10%,X7RA]
    2  SATA6G_S1_RX_DN      B  @BASEBOARD_FAB2_LIB.BASEBOARD_FAB2(SCH_1):SATA6G_S1_RX_DN
    1  SATA6G_S1_RX_C_DN      A  @BASEBOARD_FAB2_LIB.BASEBOARD_FAB2(SCH_1):SATA6G_S1_RX_C_DN

CAP_A  I8   C2L51  [CAP_A_0402V-0.01UF,25V,10%,X7RA]
    2  SATA6G_S1_TX_DN      B  @BASEBOARD_FAB2_LIB.BASEBOARD_FAB2(SCH_1):SATA6G_S1_TX_DN
    1  SATA6G_S1_TX_C_DN      A  @BASEBOARD_FAB2_LIB.BASEBOARD_FAB2(SCH_1):SATA6G_S1_TX_C_DN

CAP_A  I6   C2L52  [CAP_A_0402V-0.01UF,25V,10%,X7RA]
    2  SATA6G_S1_TX_DP      B  @BASEBOARD_FAB2_LIB.BASEBOARD_FAB2(SCH_1):SATA6G_S1_TX_DP
    1  SATA6G_S1_TX_C_DP      A  @BASEBOARD_FAB2_LIB.BASEBOARD_FAB2(SCH_1):SATA6G_S1_TX_C_DP

CAP_A  I43  C2M1   [CAP_A_0603V-22.0UF,4V,20%,X6S,A]
    1  P1V8_PCH_STBY      A  @BASEBOARD_FAB2_LIB.BASEBOARD_FAB2(SCH_1):P1V8_PCH_STBY
    2  GND                B  @BASEBOARD_FAB2_LIB.BASEBOARD_FAB2(SCH_1):GND

CAP_A  I45  C2M2   [CAP_A_0603V-22.0UF,4V,20%,X6S,A]
    1  P1V8_PCH_STBY      A  @BASEBOARD_FAB2_LIB.BASEBOARD_FAB2(SCH_1):P1V8_PCH_STBY
    2  GND                B  @BASEBOARD_FAB2_LIB.BASEBOARD_FAB2(SCH_1):GND

CAP_A  I183  C2M3   [CAP_A_0402V-0.1UF,16V,10%,EMPTA]
    1  P2E_SSB_BMC_TX_DN      A  @BASEBOARD_FAB2_LIB.BASEBOARD_FAB2(SCH_1):P2E_SSB_BMC_TX_DN
    2  P2E_SSB_BMC_TX_C_DN      B  @BASEBOARD_FAB2_LIB.BASEBOARD_FAB2(SCH_1):P2E_SSB_BMC_TX_C_DN

CAP_A  I182  C2M4   [CAP_A_0402V-0.1UF,16V,10%,EMPTA]
    1  P2E_SSB_BMC_TX_DP      A  @BASEBOARD_FAB2_LIB.BASEBOARD_FAB2(SCH_1):P2E_SSB_BMC_TX_DP
    2  P2E_SSB_BMC_TX_C_DP      B  @BASEBOARD_FAB2_LIB.BASEBOARD_FAB2(SCH_1):P2E_SSB_BMC_TX_C_DP

CAP  I43  C2M5   [CAP_0603LF-10UF,4V,20%,X6S,E15A]
    1  P1V05_PCH_STBY_WM20_PLL      A  @BASEBOARD_FAB2_LIB.BASEBOARD_FAB2(SCH_1):P1V05_PCH_STBY_WM20_PLL
    2  GND                B  @BASEBOARD_FAB2_LIB.BASEBOARD_FAB2(SCH_1):GND

CAP_A  I76  C2M6   [CAP_A_0402V-1.0UF,6.3V,10%,X6SA]
    1  P1V05_PCH_STBY      A  @BASEBOARD_FAB2_LIB.BASEBOARD_FAB2(SCH_1):P1V05_PCH_STBY
    2  GND                B  @BASEBOARD_FAB2_LIB.BASEBOARD_FAB2(SCH_1):GND

CAP_A  I44  C2M7   [CAP_A_0402V-1.0UF,6.3V,10%,X6SA]
    1  P1V05_PCH_STBY_WM20_PLL      A  @BASEBOARD_FAB2_LIB.BASEBOARD_FAB2(SCH_1):P1V05_PCH_STBY_WM20_PLL
    2  GND                B  @BASEBOARD_FAB2_LIB.BASEBOARD_FAB2(SCH_1):GND

CAP_A  I74  C2M8   [CAP_A_0402V-1.0UF,6.3V,10%,X6SA]
    1  P1V05_PCH_STBY      A  @BASEBOARD_FAB2_LIB.BASEBOARD_FAB2(SCH_1):P1V05_PCH_STBY
    2  GND                B  @BASEBOARD_FAB2_LIB.BASEBOARD_FAB2(SCH_1):GND

CAP_A  I50  C2M9   [CAP_A_0402V-1.0UF,6.3V,10%,X6SA]
    1  P1V05_PCH_STBY_WM26_PLL      A  @BASEBOARD_FAB2_LIB.BASEBOARD_FAB2(SCH_1):P1V05_PCH_STBY_WM26_PLL
    2  GND                B  @BASEBOARD_FAB2_LIB.BASEBOARD_FAB2(SCH_1):GND

CAP  I49  C2M10  [CAP_0603LF-10UF,4V,20%,X6S,E15A]
    1  P1V05_PCH_STBY_WM26_PLL      A  @BASEBOARD_FAB2_LIB.BASEBOARD_FAB2(SCH_1):P1V05_PCH_STBY_WM26_PLL
    2  GND                B  @BASEBOARD_FAB2_LIB.BASEBOARD_FAB2(SCH_1):GND

CAP  I35  C2M11  [CAP_0805-47UF,4V,20%,X6S,C9533A]
    1  P1V05_PCH_STBY      A  @BASEBOARD_FAB2_LIB.BASEBOARD_FAB2(SCH_1):P1V05_PCH_STBY
    2  GND                B  @BASEBOARD_FAB2_LIB.BASEBOARD_FAB2(SCH_1):GND

CAP_A  I52  C2M12  [CAP_A_0603V-22.0UF,4V,20%,X6S,A]
    1  P1V05_PCH_STBY      A  @BASEBOARD_FAB2_LIB.BASEBOARD_FAB2(SCH_1):P1V05_PCH_STBY
    2  GND                B  @BASEBOARD_FAB2_LIB.BASEBOARD_FAB2(SCH_1):GND

CAP_A  I48  C2M13  [CAP_A_0603V-22.0UF,4V,20%,X6S,A]
    1  P1V05_PCH_STBY      A  @BASEBOARD_FAB2_LIB.BASEBOARD_FAB2(SCH_1):P1V05_PCH_STBY
    2  GND                B  @BASEBOARD_FAB2_LIB.BASEBOARD_FAB2(SCH_1):GND

CAP_0402  I76  C2M14  [CAP_0402-0.22UF,16V,10%,X7R,A3A]
    2  P3E_OCP_CPU0_PE3_C_TXP<8>      B  @BASEBOARD_FAB2_LIB.BASEBOARD_FAB2(SCH_1):P3E_OCP_CPU0_PE3_C_TXP<8>
    1  P3E_CPU0_PE3_OCP_TXP<8>      A  @BASEBOARD_FAB2_LIB.BASEBOARD_FAB2(SCH_1):P3E_CPU0_PE3_OCP_TXP<8>

CAP_0402  I86  C2M15  [CAP_0402-0.22UF,16V,10%,X7R,A3A]
    2  P3E_OCP_CPU0_PE3_C_TXN<8>      B  @BASEBOARD_FAB2_LIB.BASEBOARD_FAB2(SCH_1):P3E_OCP_CPU0_PE3_C_TXN<8>
    1  P3E_CPU0_PE3_OCP_TXN<8>      A  @BASEBOARD_FAB2_LIB.BASEBOARD_FAB2(SCH_1):P3E_CPU0_PE3_OCP_TXN<8>

CAP_A  I37  C2M16  [CAP_A_0402V-1.0UF,6.3V,10%,X6SA]
    1  P3V3_STBY          A  @BASEBOARD_FAB2_LIB.BASEBOARD_FAB2(SCH_1):P3V3_STBY
    2  GND                B  @BASEBOARD_FAB2_LIB.BASEBOARD_FAB2(SCH_1):GND

CAP  I34  C2M17  [CAP_0805-47UF,4V,20%,X6S,C9533A]
    1  P1V05_PCH_STBY      A  @BASEBOARD_FAB2_LIB.BASEBOARD_FAB2(SCH_1):P1V05_PCH_STBY
    2  GND                B  @BASEBOARD_FAB2_LIB.BASEBOARD_FAB2(SCH_1):GND

CAP_A  I29  C2M18  [CAP_A_0402V-1.0UF,6.3V,10%,X6SA]
    1  P1V05_PCH_STBY      A  @BASEBOARD_FAB2_LIB.BASEBOARD_FAB2(SCH_1):P1V05_PCH_STBY
    2  GND                B  @BASEBOARD_FAB2_LIB.BASEBOARD_FAB2(SCH_1):GND

CAP_A  I31  C2M19  [CAP_A_0402V-1.0UF,6.3V,10%,X6SA]
    1  P1V05_PCH_STBY      A  @BASEBOARD_FAB2_LIB.BASEBOARD_FAB2(SCH_1):P1V05_PCH_STBY
    2  GND                B  @BASEBOARD_FAB2_LIB.BASEBOARD_FAB2(SCH_1):GND

CAP_A  I39  C2M20  [CAP_A_0402V-1.0UF,6.3V,10%,X6SA]
    1  P1V05_PCH_STBY      A  @BASEBOARD_FAB2_LIB.BASEBOARD_FAB2(SCH_1):P1V05_PCH_STBY
    2  GND                B  @BASEBOARD_FAB2_LIB.BASEBOARD_FAB2(SCH_1):GND

CAP_A  I28  C2M21  [CAP_A_0402V-1.0UF,6.3V,10%,X6SA]
    1  P1V05_PCH_STBY      A  @BASEBOARD_FAB2_LIB.BASEBOARD_FAB2(SCH_1):P1V05_PCH_STBY
    2  GND                B  @BASEBOARD_FAB2_LIB.BASEBOARD_FAB2(SCH_1):GND

CAP_A  I27  C2M22  [CAP_A_0402V-1.0UF,6.3V,10%,X6SA]
    1  P1V05_PCH_STBY      A  @BASEBOARD_FAB2_LIB.BASEBOARD_FAB2(SCH_1):P1V05_PCH_STBY
    2  GND                B  @BASEBOARD_FAB2_LIB.BASEBOARD_FAB2(SCH_1):GND

CAP_A  I89  C2M23  [CAP_A_0402V-0.1UF,16V,10%,X7R,A]
    1  PE_PCH_SPRV_TX_DP      A  @BASEBOARD_FAB2_LIB.BASEBOARD_FAB2(SCH_1):PE_PCH_SPRV_TX_DP
    2  PE_PCH_SPRV_TX_C_DP      B  @BASEBOARD_FAB2_LIB.BASEBOARD_FAB2(SCH_1):PE_PCH_SPRV_TX_C_DP

CAP_A  I90  C2M24  [CAP_A_0402V-0.1UF,16V,10%,X7R,A]
    1  PE_PCH_SPRV_TX_DN      A  @BASEBOARD_FAB2_LIB.BASEBOARD_FAB2(SCH_1):PE_PCH_SPRV_TX_DN
    2  PE_PCH_SPRV_TX_C_DN      B  @BASEBOARD_FAB2_LIB.BASEBOARD_FAB2(SCH_1):PE_PCH_SPRV_TX_C_DN

CAP_A  I78  C2M25  [CAP_A_0402V-1.0UF,6.3V,10%,X6SA]
    1  P1V05_PCH_STBY      A  @BASEBOARD_FAB2_LIB.BASEBOARD_FAB2(SCH_1):P1V05_PCH_STBY
    2  GND                B  @BASEBOARD_FAB2_LIB.BASEBOARD_FAB2(SCH_1):GND

CAP_A  I41  C2N2   [CAP_A_0402V-1.0UF,6.3V,10%,X6SA]
    1  P1V05_PCH_STBY      A  @BASEBOARD_FAB2_LIB.BASEBOARD_FAB2(SCH_1):P1V05_PCH_STBY
    2  GND                B  @BASEBOARD_FAB2_LIB.BASEBOARD_FAB2(SCH_1):GND

CAP_A  I27  C2N3   [CAP_A_0402V-1.0UF,6.3V,10%,X6SA]
    1  PVNN_PCH_STBY      A  @BASEBOARD_FAB2_LIB.BASEBOARD_FAB2(SCH_1):PVNN_PCH_STBY
    2  GND                B  @BASEBOARD_FAB2_LIB.BASEBOARD_FAB2(SCH_1):GND

CAP_A  I28  C2N4   [CAP_A_0402V-1.0UF,6.3V,10%,X6SA]
    1  PVNN_PCH_STBY      A  @BASEBOARD_FAB2_LIB.BASEBOARD_FAB2(SCH_1):PVNN_PCH_STBY
    2  GND                B  @BASEBOARD_FAB2_LIB.BASEBOARD_FAB2(SCH_1):GND

CAP_A  I65  C2N5   [CAP_A_0402V-1.0UF,6.3V,10%,X6SA]
    1  P1V05_PCH_STBY_KR_PLL      A  @BASEBOARD_FAB2_LIB.BASEBOARD_FAB2(SCH_1):P1V05_PCH_STBY_KR_PLL
    2  GND                B  @BASEBOARD_FAB2_LIB.BASEBOARD_FAB2(SCH_1):GND

CAP  I64  C2N6   [CAP_0603LF-10UF,4V,20%,X6S,E15A]
    1  P1V05_PCH_STBY_KR_PLL      A  @BASEBOARD_FAB2_LIB.BASEBOARD_FAB2(SCH_1):P1V05_PCH_STBY_KR_PLL
    2  GND                B  @BASEBOARD_FAB2_LIB.BASEBOARD_FAB2(SCH_1):GND

CAP_A  I43  C2N7   [CAP_A_0402V-1.0UF,6.3V,10%,X6SA]
    1  P1V05_PCH_STBY      A  @BASEBOARD_FAB2_LIB.BASEBOARD_FAB2(SCH_1):P1V05_PCH_STBY
    2  GND                B  @BASEBOARD_FAB2_LIB.BASEBOARD_FAB2(SCH_1):GND

CAP_A  I47  C2N8   [CAP_A_0402V-1.0UF,6.3V,10%,X6SA]
    1  P1V05_PCH_STBY      A  @BASEBOARD_FAB2_LIB.BASEBOARD_FAB2(SCH_1):P1V05_PCH_STBY
    2  GND                B  @BASEBOARD_FAB2_LIB.BASEBOARD_FAB2(SCH_1):GND

CAP_A  I26  C2N9   [CAP_A_0402V-1.0UF,6.3V,10%,X6SA]
    1  PVNN_PCH_STBY      A  @BASEBOARD_FAB2_LIB.BASEBOARD_FAB2(SCH_1):PVNN_PCH_STBY
    2  GND                B  @BASEBOARD_FAB2_LIB.BASEBOARD_FAB2(SCH_1):GND

CAP_A  I50  C2N10  [CAP_A_0603V-22.0UF,4V,20%,X6S,A]
    1  P1V05_PCH_STBY      A  @BASEBOARD_FAB2_LIB.BASEBOARD_FAB2(SCH_1):P1V05_PCH_STBY
    2  GND                B  @BASEBOARD_FAB2_LIB.BASEBOARD_FAB2(SCH_1):GND

CAP_A  I30  C2N11  [CAP_A_0402V-1.0UF,6.3V,10%,X6SA]
    1  PVNN_PCH_STBY      A  @BASEBOARD_FAB2_LIB.BASEBOARD_FAB2(SCH_1):PVNN_PCH_STBY
    2  GND                B  @BASEBOARD_FAB2_LIB.BASEBOARD_FAB2(SCH_1):GND

CAP_A  I29  C2N12  [CAP_A_0402V-1.0UF,6.3V,10%,X6SA]
    1  PVNN_PCH_STBY      A  @BASEBOARD_FAB2_LIB.BASEBOARD_FAB2(SCH_1):PVNN_PCH_STBY
    2  GND                B  @BASEBOARD_FAB2_LIB.BASEBOARD_FAB2(SCH_1):GND

CAP_A  I40  C2N13  [CAP_A_0402V-1.0UF,6.3V,10%,X6SA]
    1  P1V05_PCH_STBY      A  @BASEBOARD_FAB2_LIB.BASEBOARD_FAB2(SCH_1):P1V05_PCH_STBY
    2  GND                B  @BASEBOARD_FAB2_LIB.BASEBOARD_FAB2(SCH_1):GND

CAP  I25  C2N14  [CAP_0603-10UF,6.3V,20%,X6S,E15A]
    1  P3V3_STBY          A  @BASEBOARD_FAB2_LIB.BASEBOARD_FAB2(SCH_1):P3V3_STBY
    2  GND                B  @BASEBOARD_FAB2_LIB.BASEBOARD_FAB2(SCH_1):GND

CAP_A  I47  C2N15  [CAP_A_0402V-1.0UF,6.3V,10%,X6SA]
    1  P1V8_PCH_STBY      A  @BASEBOARD_FAB2_LIB.BASEBOARD_FAB2(SCH_1):P1V8_PCH_STBY
    2  GND                B  @BASEBOARD_FAB2_LIB.BASEBOARD_FAB2(SCH_1):GND

CAP_A  I52  C2N16  [CAP_A_0402V-1.0UF,6.3V,10%,X6SA]
    1  P1V8_PCH_STBY      A  @BASEBOARD_FAB2_LIB.BASEBOARD_FAB2(SCH_1):P1V8_PCH_STBY
    2  GND                B  @BASEBOARD_FAB2_LIB.BASEBOARD_FAB2(SCH_1):GND

CAP  I28  C2N17  [CAP_0603-10UF,6.3V,20%,X6S,E15A]
    1  P3V3_STBY          A  @BASEBOARD_FAB2_LIB.BASEBOARD_FAB2(SCH_1):P3V3_STBY
    2  GND                B  @BASEBOARD_FAB2_LIB.BASEBOARD_FAB2(SCH_1):GND

CAP_A  I29  C2N18  [CAP_A_0402V-1.0UF,6.3V,10%,X6SA]
    1  P3V3_STBY          A  @BASEBOARD_FAB2_LIB.BASEBOARD_FAB2(SCH_1):P3V3_STBY
    2  GND                B  @BASEBOARD_FAB2_LIB.BASEBOARD_FAB2(SCH_1):GND

CAP_A  I7   C2N19  [CAP_A_0402V-1.0UF,6.3V,10%,X6SA]
    1  P3V3_STBY          A  @BASEBOARD_FAB2_LIB.BASEBOARD_FAB2(SCH_1):P3V3_STBY
    2  GND                B  @BASEBOARD_FAB2_LIB.BASEBOARD_FAB2(SCH_1):GND

CAP_A  I12  C2N20  [CAP_A_0402V-1.0UF,6.3V,10%,X6SA]
    1  P3V3_STBY          A  @BASEBOARD_FAB2_LIB.BASEBOARD_FAB2(SCH_1):P3V3_STBY
    2  GND                B  @BASEBOARD_FAB2_LIB.BASEBOARD_FAB2(SCH_1):GND

CAP  I15  C2N21  [CAP_0603-10UF,6.3V,20%,X6S,E15A]
    1  P3V3_STBY          A  @BASEBOARD_FAB2_LIB.BASEBOARD_FAB2(SCH_1):P3V3_STBY
    2  GND                B  @BASEBOARD_FAB2_LIB.BASEBOARD_FAB2(SCH_1):GND

CAP  I9   C2N22  [CAP_0603-10UF,6.3V,20%,X6S,E15A]
    1  P3V3_STBY          A  @BASEBOARD_FAB2_LIB.BASEBOARD_FAB2(SCH_1):P3V3_STBY
    2  GND                B  @BASEBOARD_FAB2_LIB.BASEBOARD_FAB2(SCH_1):GND

CAP  I24  C2N23  [CAP_0603-10UF,6.3V,20%,X6S,E15A]
    1  P3V3_STBY          A  @BASEBOARD_FAB2_LIB.BASEBOARD_FAB2(SCH_1):P3V3_STBY
    2  GND                B  @BASEBOARD_FAB2_LIB.BASEBOARD_FAB2(SCH_1):GND

CAP  I8   C2N24  [CAP_0603-10UF,6.3V,20%,X6S,E15A]
    1  P3V3_STBY          A  @BASEBOARD_FAB2_LIB.BASEBOARD_FAB2(SCH_1):P3V3_STBY
    2  GND                B  @BASEBOARD_FAB2_LIB.BASEBOARD_FAB2(SCH_1):GND

CAP_A  I34  C2N25  [CAP_A_0402V-1.0UF,6.3V,10%,X6SA]
    1  P3V3_STBY          A  @BASEBOARD_FAB2_LIB.BASEBOARD_FAB2(SCH_1):P3V3_STBY
    2  GND                B  @BASEBOARD_FAB2_LIB.BASEBOARD_FAB2(SCH_1):GND

CAP_A  I4   C2N26  [CAP_A_0402V-1.0UF,6.3V,10%,X6SA]
    1  P3V3_STBY          A  @BASEBOARD_FAB2_LIB.BASEBOARD_FAB2(SCH_1):P3V3_STBY
    2  GND                B  @BASEBOARD_FAB2_LIB.BASEBOARD_FAB2(SCH_1):GND

CAP_A  I8   C2P1   [CAP_A_0402V-0.1UF,16V,10%,X7R,A]
    1  P3V3_STBY          A  @BASEBOARD_FAB2_LIB.BASEBOARD_FAB2(SCH_1):P3V3_STBY
    2  GND                B  @BASEBOARD_FAB2_LIB.BASEBOARD_FAB2(SCH_1):GND

CAP_A  I9   C2P2   [CAP_A_0402V-0.1UF,16V,10%,X7R,A]
    1  P3V3_STBY          A  @BASEBOARD_FAB2_LIB.BASEBOARD_FAB2(SCH_1):P3V3_STBY
    2  GND                B  @BASEBOARD_FAB2_LIB.BASEBOARD_FAB2(SCH_1):GND

CAP_A  I22  C2P3   [CAP_A_0402V-0.1UF,16V,10%,X7R,A]
    1  P3V3_STBY          A  @BASEBOARD_FAB2_LIB.BASEBOARD_FAB2(SCH_1):P3V3_STBY
    2  GND                B  @BASEBOARD_FAB2_LIB.BASEBOARD_FAB2(SCH_1):GND

CAP_A  I16  C2P4   [CAP_A_0402V-0.1UF,16V,10%,X7R,A]
    1  P3V3_STBY          A  @BASEBOARD_FAB2_LIB.BASEBOARD_FAB2(SCH_1):P3V3_STBY
    2  GND                B  @BASEBOARD_FAB2_LIB.BASEBOARD_FAB2(SCH_1):GND

CAP_A  I3   C2P5   [CAP_A_0402V-0.1UF,16V,10%,X7R,A]
    1  P3V3_STBY          A  @BASEBOARD_FAB2_LIB.BASEBOARD_FAB2(SCH_1):P3V3_STBY
    2  GND                B  @BASEBOARD_FAB2_LIB.BASEBOARD_FAB2(SCH_1):GND

CAP_A  I18  C2P6   [CAP_A_0402V-0.1UF,16V,10%,X7R,A]
    1  P3V3_STBY          A  @BASEBOARD_FAB2_LIB.BASEBOARD_FAB2(SCH_1):P3V3_STBY
    2  GND                B  @BASEBOARD_FAB2_LIB.BASEBOARD_FAB2(SCH_1):GND

CAP_A  I20  C2P7   [CAP_A_0402V-0.1UF,16V,10%,X7R,A]
    1  P3V3_STBY          A  @BASEBOARD_FAB2_LIB.BASEBOARD_FAB2(SCH_1):P3V3_STBY
    2  GND                B  @BASEBOARD_FAB2_LIB.BASEBOARD_FAB2(SCH_1):GND

CAP_A  I1   C2P8   [CAP_A_0402V-0.01UF,25V,10%,X7RA]
    1  P3V3_STBY          A  @BASEBOARD_FAB2_LIB.BASEBOARD_FAB2(SCH_1):P3V3_STBY
    2  GND                B  @BASEBOARD_FAB2_LIB.BASEBOARD_FAB2(SCH_1):GND

CAP_A  I117  C2P9   [CAP_A_0402V-0.1UF,16V,10%,X7R,A]
    1  P3V3_STBY          A  @BASEBOARD_FAB2_LIB.BASEBOARD_FAB2(SCH_1):P3V3_STBY
    2  GND                B  @BASEBOARD_FAB2_LIB.BASEBOARD_FAB2(SCH_1):GND

CAP  I41  C2P10  [CAP_1206LF-22UF,16V,10%,X6S,D3A]
    1  P12V_STBY          A  @BASEBOARD_FAB2_LIB.BASEBOARD_FAB2(SCH_1):P12V_STBY
    2  GND                B  @BASEBOARD_FAB2_LIB.BASEBOARD_FAB2(SCH_1):GND

CAP_A  I21  C2P11  [CAP_A_0402V-0.1UF,16V,10%,X7R,A]
    1  P12V_STBY          A  @BASEBOARD_FAB2_LIB.BASEBOARD_FAB2(SCH_1):P12V_STBY
    2  GND                B  @BASEBOARD_FAB2_LIB.BASEBOARD_FAB2(SCH_1):GND

CAP_A  I23  C2P12  [CAP_A_0402V-0.1UF,16V,10%,X7R,A]
    1  P12V_STBY          A  @BASEBOARD_FAB2_LIB.BASEBOARD_FAB2(SCH_1):P12V_STBY
    2  GND                B  @BASEBOARD_FAB2_LIB.BASEBOARD_FAB2(SCH_1):GND

CAP_A  I57  C2P13  [CAP_A_0402V-0.1UF,16V,10%,X7R,A]
    1  P12V_STBY          A  @BASEBOARD_FAB2_LIB.BASEBOARD_FAB2(SCH_1):P12V_STBY
    2  GND                B  @BASEBOARD_FAB2_LIB.BASEBOARD_FAB2(SCH_1):GND

CAP_A  I56  C2P14  [CAP_A_0402V-0.1UF,16V,10%,X7R,A]
    1  P12V_STBY          A  @BASEBOARD_FAB2_LIB.BASEBOARD_FAB2(SCH_1):P12V_STBY
    2  GND                B  @BASEBOARD_FAB2_LIB.BASEBOARD_FAB2(SCH_1):GND

CAP_A  I55  C2P15  [CAP_A_0402V-0.1UF,16V,10%,X7R,A]
    1  P12V_STBY          A  @BASEBOARD_FAB2_LIB.BASEBOARD_FAB2(SCH_1):P12V_STBY
    2  GND                B  @BASEBOARD_FAB2_LIB.BASEBOARD_FAB2(SCH_1):GND

CAP_A  I53  C2P16  [CAP_A_0402V-0.1UF,16V,10%,X7R,A]
    1  P12V_STBY          A  @BASEBOARD_FAB2_LIB.BASEBOARD_FAB2(SCH_1):P12V_STBY
    2  GND                B  @BASEBOARD_FAB2_LIB.BASEBOARD_FAB2(SCH_1):GND

CAP_A  I8   C2R1   [CAP_A_0402V-0.1UF,16V,10%,X7R,A]
    1  P3V3_STBY          A  @BASEBOARD_FAB2_LIB.BASEBOARD_FAB2(SCH_1):P3V3_STBY
    2  GND                B  @BASEBOARD_FAB2_LIB.BASEBOARD_FAB2(SCH_1):GND

CAP_A  I28  C2R2   [CAP_A_0402V-0.1UF,16V,10%,X7R,A]
    1  P3V3_STBY          A  @BASEBOARD_FAB2_LIB.BASEBOARD_FAB2(SCH_1):P3V3_STBY
    2  GND                B  @BASEBOARD_FAB2_LIB.BASEBOARD_FAB2(SCH_1):GND

CAP_A  I19  C2R3   [CAP_A_0402V-0.1UF,16V,10%,X7R,A]
    1  P3V3_STBY          A  @BASEBOARD_FAB2_LIB.BASEBOARD_FAB2(SCH_1):P3V3_STBY
    2  GND                B  @BASEBOARD_FAB2_LIB.BASEBOARD_FAB2(SCH_1):GND

CAP_A  I21  C2R4   [CAP_A_0402V-0.1UF,16V,10%,X7R,A]
    1  P3V3_STBY          A  @BASEBOARD_FAB2_LIB.BASEBOARD_FAB2(SCH_1):P3V3_STBY
    2  GND                B  @BASEBOARD_FAB2_LIB.BASEBOARD_FAB2(SCH_1):GND

CAP_A  I15  C2R5   [CAP_A_0402V-0.1UF,16V,10%,X7R,A]
    1  P3V3_STBY          A  @BASEBOARD_FAB2_LIB.BASEBOARD_FAB2(SCH_1):P3V3_STBY
    2  GND                B  @BASEBOARD_FAB2_LIB.BASEBOARD_FAB2(SCH_1):GND

CAP  I224  C2R6   [CAP_0402LF-470PF,50V,10%,EMPTYA]
    2  GND                B  @BASEBOARD_FAB2_LIB.BASEBOARD_FAB2(SCH_1):GND
    1  FM_PS_EN           A  @BASEBOARD_FAB2_LIB.BASEBOARD_FAB2(SCH_1):FM_PS_EN

CAP_0402  I123  C2R7   [CAP_0402-0.22UF,16V,10%,X7R,A3A]
    2  P3E_OCP_CPU0_PE3_C_TXN<6>      B  @BASEBOARD_FAB2_LIB.BASEBOARD_FAB2(SCH_1):P3E_OCP_CPU0_PE3_C_TXN<6>
    1  P3E_CPU0_PE3_OCP_TXN<6>      A  @BASEBOARD_FAB2_LIB.BASEBOARD_FAB2(SCH_1):P3E_CPU0_PE3_OCP_TXN<6>

CAP_0402  I141  C2R8   [CAP_0402-0.22UF,16V,10%,X7R,A3A]
    2  P3E_OCP_CPU0_PE3_C_TXP<6>      B  @BASEBOARD_FAB2_LIB.BASEBOARD_FAB2(SCH_1):P3E_OCP_CPU0_PE3_C_TXP<6>
    1  P3E_CPU0_PE3_OCP_TXP<6>      A  @BASEBOARD_FAB2_LIB.BASEBOARD_FAB2(SCH_1):P3E_CPU0_PE3_OCP_TXP<6>

CAP_0402  I147  C2R9   [CAP_0402-0.22UF,16V,10%,X7R,A3A]
    2  P3E_OCP_CPU0_PE3_C_TXN<7>      B  @BASEBOARD_FAB2_LIB.BASEBOARD_FAB2(SCH_1):P3E_OCP_CPU0_PE3_C_TXN<7>
    1  P3E_CPU0_PE3_OCP_TXN<7>      A  @BASEBOARD_FAB2_LIB.BASEBOARD_FAB2(SCH_1):P3E_CPU0_PE3_OCP_TXN<7>

CAP_0402  I142  C2R10  [CAP_0402-0.22UF,16V,10%,X7R,A3A]
    2  P3E_OCP_CPU0_PE3_C_TXP<7>      B  @BASEBOARD_FAB2_LIB.BASEBOARD_FAB2(SCH_1):P3E_OCP_CPU0_PE3_C_TXP<7>
    1  P3E_CPU0_PE3_OCP_TXP<7>      A  @BASEBOARD_FAB2_LIB.BASEBOARD_FAB2(SCH_1):P3E_CPU0_PE3_OCP_TXP<7>

CAP  I109  C2R11  [CAP_0603-4.7UF,6.3V,10%,X6S,E1A]
    1  P5V_STBY           A  @BASEBOARD_FAB2_LIB.BASEBOARD_FAB2(SCH_1):P5V_STBY
    2  AGND_P3V3_STBY      B  @BASEBOARD_FAB2_LIB.BASEBOARD_FAB2(SCH_1):AGND_P3V3_STBY

CAP_A  I353  C2R12  [CAP_A_0402V-1.0UF,6.3V,10%,X6SA]
    2  GND                B  @BASEBOARD_FAB2_LIB.BASEBOARD_FAB2(SCH_1):GND
    1  FP_NMI_BTN_OUT_N      A  @BASEBOARD_FAB2_LIB.BASEBOARD_FAB2(SCH_1):FP_NMI_BTN_OUT_N

CAP_0402  I137  C2R13  [CAP_0402-0.22UF,16V,10%,X7R,A3A]
    2  P3E_OCP_CPU0_PE3_C_TXN<5>      B  @BASEBOARD_FAB2_LIB.BASEBOARD_FAB2(SCH_1):P3E_OCP_CPU0_PE3_C_TXN<5>
    1  P3E_CPU0_PE3_OCP_TXN<5>      A  @BASEBOARD_FAB2_LIB.BASEBOARD_FAB2(SCH_1):P3E_CPU0_PE3_OCP_TXN<5>

CAP_0402  I130  C2R14  [CAP_0402-0.22UF,16V,10%,X7R,A3A]
    2  P3E_OCP_CPU0_PE3_C_TXP<5>      B  @BASEBOARD_FAB2_LIB.BASEBOARD_FAB2(SCH_1):P3E_OCP_CPU0_PE3_C_TXP<5>
    1  P3E_CPU0_PE3_OCP_TXP<5>      A  @BASEBOARD_FAB2_LIB.BASEBOARD_FAB2(SCH_1):P3E_CPU0_PE3_OCP_TXP<5>

CAP_A  I2   C2R15  [CAP_A_0402V-0.1UF,16V,10%,X7R,A]
    1  P12V_STBY          A  @BASEBOARD_FAB2_LIB.BASEBOARD_FAB2(SCH_1):P12V_STBY
    2  GND                B  @BASEBOARD_FAB2_LIB.BASEBOARD_FAB2(SCH_1):GND

CAP_A  I40  C2R16  [CAP_A_0402V-0.1UF,16V,10%,X7R,A]
    1  P12V_STBY          A  @BASEBOARD_FAB2_LIB.BASEBOARD_FAB2(SCH_1):P12V_STBY
    2  GND                B  @BASEBOARD_FAB2_LIB.BASEBOARD_FAB2(SCH_1):GND

CAP_A  I25  C2R17  [CAP_A_0402V-0.1UF,16V,10%,X7R,A]
    1  P12V_STBY          A  @BASEBOARD_FAB2_LIB.BASEBOARD_FAB2(SCH_1):P12V_STBY
    2  GND                B  @BASEBOARD_FAB2_LIB.BASEBOARD_FAB2(SCH_1):GND

CAP_A  I3   C2R18  [CAP_A_0402V-0.1UF,16V,10%,X7R,A]
    1  P12V_STBY          A  @BASEBOARD_FAB2_LIB.BASEBOARD_FAB2(SCH_1):P12V_STBY
    2  GND                B  @BASEBOARD_FAB2_LIB.BASEBOARD_FAB2(SCH_1):GND

CAP_A  I94  C2T1   [CAP_A_0402V-0.1UF,16V,10%,X7R,A]
    1  P3V3_STBY          A  @BASEBOARD_FAB2_LIB.BASEBOARD_FAB2(SCH_1):P3V3_STBY
    2  GND                B  @BASEBOARD_FAB2_LIB.BASEBOARD_FAB2(SCH_1):GND

CAP_A  I131  C2T2   [CAP_A_0402V-0.1UF,16V,10%,X7R,A]
    1  P3V3               A  @BASEBOARD_FAB2_LIB.BASEBOARD_FAB2(SCH_1):P3V3
    2  GND                B  @BASEBOARD_FAB2_LIB.BASEBOARD_FAB2(SCH_1):GND

CAP_A  I370  C2T3   [CAP_A_0402V-0.1UF,16V,10%,X7R,A]
    1  P3V3_STBY          A  @BASEBOARD_FAB2_LIB.BASEBOARD_FAB2(SCH_1):P3V3_STBY
    2  GND                B  @BASEBOARD_FAB2_LIB.BASEBOARD_FAB2(SCH_1):GND

CAP_A  I132  C2T4   [CAP_A_0402V-0.1UF,16V,10%,X7R,A]
    1  P3V3               A  @BASEBOARD_FAB2_LIB.BASEBOARD_FAB2(SCH_1):P3V3
    2  GND                B  @BASEBOARD_FAB2_LIB.BASEBOARD_FAB2(SCH_1):GND

CAP_A  I135  C2T5   [CAP_A_0402V-0.1UF,16V,10%,X7R,A]
    1  P3V3               A  @BASEBOARD_FAB2_LIB.BASEBOARD_FAB2(SCH_1):P3V3
    2  GND                B  @BASEBOARD_FAB2_LIB.BASEBOARD_FAB2(SCH_1):GND

CAP  I160  C2T6   [CAP_0805-22UF,6.3V,20%,X6S,C95A]
    1  P3V3_STBY          A  @BASEBOARD_FAB2_LIB.BASEBOARD_FAB2(SCH_1):P3V3_STBY
    2  GND                B  @BASEBOARD_FAB2_LIB.BASEBOARD_FAB2(SCH_1):GND

CAP  I158  C2T7   [CAP_0805-22UF,6.3V,20%,X6S,C95A]
    1  P3V3_STBY          A  @BASEBOARD_FAB2_LIB.BASEBOARD_FAB2(SCH_1):P3V3_STBY
    2  GND                B  @BASEBOARD_FAB2_LIB.BASEBOARD_FAB2(SCH_1):GND

CAP_A  I135  C2T8   [CAP_A_0402V-0.1UF,16V,10%,X7R,A]
    1  P3V3_STBY          A  @BASEBOARD_FAB2_LIB.BASEBOARD_FAB2(SCH_1):P3V3_STBY
    2  GND                B  @BASEBOARD_FAB2_LIB.BASEBOARD_FAB2(SCH_1):GND

CAP  I174  C2T9   [CAP_0805-22UF,6.3V,20%,X6S,C95A]
    1  P3V3_STBY          A  @BASEBOARD_FAB2_LIB.BASEBOARD_FAB2(SCH_1):P3V3_STBY
    2  GND                B  @BASEBOARD_FAB2_LIB.BASEBOARD_FAB2(SCH_1):GND

CAP_0402  I63  C2T10  [CAP_0402-0.22UF,16V,10%,X7R,A3A]
    2  P3E_PCH_M2_TX_DP<1>      B  @BASEBOARD_FAB2_LIB.BASEBOARD_FAB2(SCH_1):P3E_PCH_M2_TX_DP<1>
    1  P3E_PCH_M2_TX_C_DP<1>      A  @BASEBOARD_FAB2_LIB.BASEBOARD_FAB2(SCH_1):P3E_PCH_M2_TX_C_DP<1>

CAP_0402  I62  C2T11  [CAP_0402-0.22UF,16V,10%,X7R,A3A]
    2  P3E_PCH_M2_TX_DN<1>      B  @BASEBOARD_FAB2_LIB.BASEBOARD_FAB2(SCH_1):P3E_PCH_M2_TX_DN<1>
    1  P3E_PCH_M2_TX_C_DN<1>      A  @BASEBOARD_FAB2_LIB.BASEBOARD_FAB2(SCH_1):P3E_PCH_M2_TX_C_DN<1>

CAP_A  I132  C2T12  [CAP_A_0402V-0.1UF,16V,10%,X7R,A]
    1  P3V3_STBY          A  @BASEBOARD_FAB2_LIB.BASEBOARD_FAB2(SCH_1):P3V3_STBY
    2  GND                B  @BASEBOARD_FAB2_LIB.BASEBOARD_FAB2(SCH_1):GND

CAP_0402  I64  C2T13  [CAP_0402-0.22UF,16V,10%,X7R,A3A]
    2  P3E_PCH_M2_TX_DP<2>      B  @BASEBOARD_FAB2_LIB.BASEBOARD_FAB2(SCH_1):P3E_PCH_M2_TX_DP<2>
    1  P3E_PCH_M2_TX_C_DP<2>      A  @BASEBOARD_FAB2_LIB.BASEBOARD_FAB2(SCH_1):P3E_PCH_M2_TX_C_DP<2>

CAP_0402  I65  C2T14  [CAP_0402-0.22UF,16V,10%,X7R,A3A]
    2  P3E_PCH_M2_TX_DN<2>      B  @BASEBOARD_FAB2_LIB.BASEBOARD_FAB2(SCH_1):P3E_PCH_M2_TX_DN<2>
    1  P3E_PCH_M2_TX_C_DN<2>      A  @BASEBOARD_FAB2_LIB.BASEBOARD_FAB2(SCH_1):P3E_PCH_M2_TX_C_DN<2>

CAP_A  I127  C2T15  [CAP_A_0402V-0.1UF,16V,10%,X7R,A]
    1  P3V3               A  @BASEBOARD_FAB2_LIB.BASEBOARD_FAB2(SCH_1):P3V3
    2  GND                B  @BASEBOARD_FAB2_LIB.BASEBOARD_FAB2(SCH_1):GND

CAP_A  I126  C2T16  [CAP_A_0402V-0.1UF,16V,10%,X7R,A]
    1  P3V3               A  @BASEBOARD_FAB2_LIB.BASEBOARD_FAB2(SCH_1):P3V3
    2  GND                B  @BASEBOARD_FAB2_LIB.BASEBOARD_FAB2(SCH_1):GND

CAP_A  I112  C2T17  [CAP_A_0402V-0.1UF,16V,10%,X7R,A]
    1  P3V3_STBY_MNG      A  @BASEBOARD_FAB2_LIB.BASEBOARD_FAB2(SCH_1):P3V3_STBY_MNG
    2  GND                B  @BASEBOARD_FAB2_LIB.BASEBOARD_FAB2(SCH_1):GND

CAP_A  I104  C2T18  [CAP_A_0402V-0.01UF,25V,10%,X7RA]
    1  P3V3_STBY_MNG_CPU      A  @BASEBOARD_FAB2_LIB.BASEBOARD_FAB2(SCH_1):P3V3_STBY_MNG_CPU
    2  GND                B  @BASEBOARD_FAB2_LIB.BASEBOARD_FAB2(SCH_1):GND

CAP_A  I106  C2T19  [CAP_A_0402V-1.0UF,6.3V,10%,X6SA]
    1  P3V3_STBY_MNG_CPU      A  @BASEBOARD_FAB2_LIB.BASEBOARD_FAB2(SCH_1):P3V3_STBY_MNG_CPU
    2  GND                B  @BASEBOARD_FAB2_LIB.BASEBOARD_FAB2(SCH_1):GND

CAP_0402  I66  C2T20  [CAP_0402-0.22UF,16V,10%,X7R,A3A]
    2  P3E_PCH_M2_TX_DP<3>      B  @BASEBOARD_FAB2_LIB.BASEBOARD_FAB2(SCH_1):P3E_PCH_M2_TX_DP<3>
    1  P3E_PCH_M2_TX_C_DP<3>      A  @BASEBOARD_FAB2_LIB.BASEBOARD_FAB2(SCH_1):P3E_PCH_M2_TX_C_DP<3>

CAP_A  I124  C2T21  [CAP_A_0402V-0.1UF,16V,10%,X7R,A]
    1  P3V3               A  @BASEBOARD_FAB2_LIB.BASEBOARD_FAB2(SCH_1):P3V3
    2  GND                B  @BASEBOARD_FAB2_LIB.BASEBOARD_FAB2(SCH_1):GND

CAP  I113  C2T22  [CAP_0805-10UF,16V,10%,X6S,C953A]
    1  P3V3_STBY_MNG      A  @BASEBOARD_FAB2_LIB.BASEBOARD_FAB2(SCH_1):P3V3_STBY_MNG
    2  GND                B  @BASEBOARD_FAB2_LIB.BASEBOARD_FAB2(SCH_1):GND

CAP_0402  I67  C2T23  [CAP_0402-0.22UF,16V,10%,X7R,A3A]
    2  P3E_PCH_M2_TX_DN<3>      B  @BASEBOARD_FAB2_LIB.BASEBOARD_FAB2(SCH_1):P3E_PCH_M2_TX_DN<3>
    1  P3E_PCH_M2_TX_C_DN<3>      A  @BASEBOARD_FAB2_LIB.BASEBOARD_FAB2(SCH_1):P3E_PCH_M2_TX_C_DN<3>

CAP_A  I129  C2T24  [CAP_A_0402V-0.1UF,16V,10%,X7R,A]
    1  P3V3               A  @BASEBOARD_FAB2_LIB.BASEBOARD_FAB2(SCH_1):P3V3
    2  GND                B  @BASEBOARD_FAB2_LIB.BASEBOARD_FAB2(SCH_1):GND

CAP_A  I111  C2T25  [CAP_A_0402V-0.1UF,16V,10%,X7R,A]
    1  P3V3_STBY_MNG      A  @BASEBOARD_FAB2_LIB.BASEBOARD_FAB2(SCH_1):P3V3_STBY_MNG
    2  GND                B  @BASEBOARD_FAB2_LIB.BASEBOARD_FAB2(SCH_1):GND

CAP_A  I123  C2T26  [CAP_A_0402V-0.1UF,16V,10%,X7R,A]
    1  P3V3               A  @BASEBOARD_FAB2_LIB.BASEBOARD_FAB2(SCH_1):P3V3
    2  GND                B  @BASEBOARD_FAB2_LIB.BASEBOARD_FAB2(SCH_1):GND

CAP_A  I90  C2T27  [CAP_A_0402V-0.01UF,25V,10%,X7RA]
    1  P3V3_STBY_MNG_RGMII      A  @BASEBOARD_FAB2_LIB.BASEBOARD_FAB2(SCH_1):P3V3_STBY_MNG_RGMII
    2  GND                B  @BASEBOARD_FAB2_LIB.BASEBOARD_FAB2(SCH_1):GND

CAP_A  I116  C2T28  [CAP_A_0402V-1.0UF,6.3V,10%,X6SA]
    1  P3V3_STBY          A  @BASEBOARD_FAB2_LIB.BASEBOARD_FAB2(SCH_1):P3V3_STBY
    2  GND                B  @BASEBOARD_FAB2_LIB.BASEBOARD_FAB2(SCH_1):GND

CAP_A  I120  C2T29  [CAP_A_0402V-0.1UF,16V,10%,X7R,A]
    1  P3V3               A  @BASEBOARD_FAB2_LIB.BASEBOARD_FAB2(SCH_1):P3V3
    2  GND                B  @BASEBOARD_FAB2_LIB.BASEBOARD_FAB2(SCH_1):GND

CAP_A  I110  C2T30  [CAP_A_0402V-0.1UF,16V,10%,X7R,A]
    1  P3V3_STBY_MNG      A  @BASEBOARD_FAB2_LIB.BASEBOARD_FAB2(SCH_1):P3V3_STBY_MNG
    2  GND                B  @BASEBOARD_FAB2_LIB.BASEBOARD_FAB2(SCH_1):GND

CAP_A  I89  C2T31  [CAP_A_0402V-1.0UF,6.3V,10%,X6SA]
    1  P3V3_STBY_MNG_RGMII      A  @BASEBOARD_FAB2_LIB.BASEBOARD_FAB2(SCH_1):P3V3_STBY_MNG_RGMII
    2  GND                B  @BASEBOARD_FAB2_LIB.BASEBOARD_FAB2(SCH_1):GND

CAP_A  I95  C2T32  [CAP_A_0402V-0.1UF,16V,10%,X7R,A]
    1  P0V7_GTL2104_5_VREF      A  @BASEBOARD_FAB2_LIB.BASEBOARD_FAB2(SCH_1):P0V7_GTL2104_5_VREF
    2  GND                B  @BASEBOARD_FAB2_LIB.BASEBOARD_FAB2(SCH_1):GND

CAP_A  I72  C2T33  [CAP_A_0402V-1.0UF,6.3V,10%,X6SA]
    1  P3V3               A  @BASEBOARD_FAB2_LIB.BASEBOARD_FAB2(SCH_1):P3V3
    2  GND                B  @BASEBOARD_FAB2_LIB.BASEBOARD_FAB2(SCH_1):GND

CAP_A  I109  C2T34  [CAP_A_0402V-0.1UF,16V,10%,X7R,A]
    1  P3V3_STBY_MNG      A  @BASEBOARD_FAB2_LIB.BASEBOARD_FAB2(SCH_1):P3V3_STBY_MNG
    2  GND                B  @BASEBOARD_FAB2_LIB.BASEBOARD_FAB2(SCH_1):GND

CAP_A  I273  C2T35  [CAP_A_0402V-0.1UF,16V,10%,X7R,A]
    1  P3V3_STBY          A  @BASEBOARD_FAB2_LIB.BASEBOARD_FAB2(SCH_1):P3V3_STBY
    2  GND                B  @BASEBOARD_FAB2_LIB.BASEBOARD_FAB2(SCH_1):GND

CAP_A  I43  C2T36  [CAP_A_0402V-0.1UF,16V,10%,X7R,A]
    1  P3V3_STBY          A  @BASEBOARD_FAB2_LIB.BASEBOARD_FAB2(SCH_1):P3V3_STBY
    2  GND                B  @BASEBOARD_FAB2_LIB.BASEBOARD_FAB2(SCH_1):GND

CAP_A  I99  C2T37  [CAP_A_0402V-0.01UF,25V,10%,X7RA]
    1  P3V3_STBY_MNG_RMII      A  @BASEBOARD_FAB2_LIB.BASEBOARD_FAB2(SCH_1):P3V3_STBY_MNG_RMII
    2  GND                B  @BASEBOARD_FAB2_LIB.BASEBOARD_FAB2(SCH_1):GND

CAP_A  I97  C2T38  [CAP_A_0402V-1.0UF,6.3V,10%,X6SA]
    1  P3V3_STBY_MNG_RMII      A  @BASEBOARD_FAB2_LIB.BASEBOARD_FAB2(SCH_1):P3V3_STBY_MNG_RMII
    2  GND                B  @BASEBOARD_FAB2_LIB.BASEBOARD_FAB2(SCH_1):GND

CAP  I44  C2U1   [CAP_0805-10UF,16V,10%,X6S,C953A]
    1  P3V3_STBY          A  @BASEBOARD_FAB2_LIB.BASEBOARD_FAB2(SCH_1):P3V3_STBY
    2  GND                B  @BASEBOARD_FAB2_LIB.BASEBOARD_FAB2(SCH_1):GND

CAP  I47  C2U2   [CAP_0805-10UF,16V,10%,X6S,C953A]
    1  P3V3               A  @BASEBOARD_FAB2_LIB.BASEBOARD_FAB2(SCH_1):P3V3
    2  GND                B  @BASEBOARD_FAB2_LIB.BASEBOARD_FAB2(SCH_1):GND

CAP_0402  I272  C2U3   [CAP_0402-0.22UF,16V,10%,X7R,A3A]
    2  P3E_CPU0_PE1_SS_RXP<0>      B  @BASEBOARD_FAB2_LIB.BASEBOARD_FAB2(SCH_1):P3E_CPU0_PE1_SS_RXP<0>
    1  P3E_CPU0_PE1_PCH_RXP<0>      A  @BASEBOARD_FAB2_LIB.BASEBOARD_FAB2(SCH_1):P3E_CPU0_PE1_PCH_RXP<0>

CAP_0402  I257  C2U4   [CAP_0402-0.22UF,16V,10%,X7R,A3A]
    2  P3E_CPU0_PE1_SS_RXN<0>      B  @BASEBOARD_FAB2_LIB.BASEBOARD_FAB2(SCH_1):P3E_CPU0_PE1_SS_RXN<0>
    1  P3E_CPU0_PE1_PCH_RXN<0>      A  @BASEBOARD_FAB2_LIB.BASEBOARD_FAB2(SCH_1):P3E_CPU0_PE1_PCH_RXN<0>

CAP_0402  I274  C2U5   [CAP_0402-0.22UF,16V,10%,X7R,A3A]
    2  P3E_CPU0_PE1_SS_RXP<1>      B  @BASEBOARD_FAB2_LIB.BASEBOARD_FAB2(SCH_1):P3E_CPU0_PE1_SS_RXP<1>
    1  P3E_CPU0_PE1_PCH_RXP<1>      A  @BASEBOARD_FAB2_LIB.BASEBOARD_FAB2(SCH_1):P3E_CPU0_PE1_PCH_RXP<1>

CAP_0402  I260  C2U6   [CAP_0402-0.22UF,16V,10%,X7R,A3A]
    2  P3E_CPU0_PE1_SS_RXN<1>      B  @BASEBOARD_FAB2_LIB.BASEBOARD_FAB2(SCH_1):P3E_CPU0_PE1_SS_RXN<1>
    1  P3E_CPU0_PE1_PCH_RXN<1>      A  @BASEBOARD_FAB2_LIB.BASEBOARD_FAB2(SCH_1):P3E_CPU0_PE1_PCH_RXN<1>

CAP_0402  I277  C2U7   [CAP_0402-0.22UF,16V,10%,X7R,A3A]
    2  P3E_CPU0_PE1_SS_RXP<2>      B  @BASEBOARD_FAB2_LIB.BASEBOARD_FAB2(SCH_1):P3E_CPU0_PE1_SS_RXP<2>
    1  P3E_CPU0_PE1_PCH_RXP<2>      A  @BASEBOARD_FAB2_LIB.BASEBOARD_FAB2(SCH_1):P3E_CPU0_PE1_PCH_RXP<2>

CAP_0402  I264  C2U8   [CAP_0402-0.22UF,16V,10%,X7R,A3A]
    2  P3E_CPU0_PE1_SS_RXN<2>      B  @BASEBOARD_FAB2_LIB.BASEBOARD_FAB2(SCH_1):P3E_CPU0_PE1_SS_RXN<2>
    1  P3E_CPU0_PE1_PCH_RXN<2>      A  @BASEBOARD_FAB2_LIB.BASEBOARD_FAB2(SCH_1):P3E_CPU0_PE1_PCH_RXN<2>

CAP_0402  I279  C2U9   [CAP_0402-0.22UF,16V,10%,X7R,A3A]
    2  P3E_CPU0_PE1_SS_RXP<3>      B  @BASEBOARD_FAB2_LIB.BASEBOARD_FAB2(SCH_1):P3E_CPU0_PE1_SS_RXP<3>
    1  P3E_CPU0_PE1_PCH_RXP<3>      A  @BASEBOARD_FAB2_LIB.BASEBOARD_FAB2(SCH_1):P3E_CPU0_PE1_PCH_RXP<3>

CAP_0402  I267  C2U10  [CAP_0402-0.22UF,16V,10%,X7R,A3A]
    2  P3E_CPU0_PE1_SS_RXN<3>      B  @BASEBOARD_FAB2_LIB.BASEBOARD_FAB2(SCH_1):P3E_CPU0_PE1_SS_RXN<3>
    1  P3E_CPU0_PE1_PCH_RXN<3>      A  @BASEBOARD_FAB2_LIB.BASEBOARD_FAB2(SCH_1):P3E_CPU0_PE1_PCH_RXN<3>

CAP_0402  I278  C2U11  [CAP_0402-0.22UF,16V,10%,X7R,A3A]
    2  P3E_CPU0_PE1_SS_RXP<4>      B  @BASEBOARD_FAB2_LIB.BASEBOARD_FAB2(SCH_1):P3E_CPU0_PE1_SS_RXP<4>
    1  P3E_CPU0_PE1_PCH_RXP<4>      A  @BASEBOARD_FAB2_LIB.BASEBOARD_FAB2(SCH_1):P3E_CPU0_PE1_PCH_RXP<4>

CAP_0402  I265  C2U12  [CAP_0402-0.22UF,16V,10%,X7R,A3A]
    2  P3E_CPU0_PE1_SS_RXN<4>      B  @BASEBOARD_FAB2_LIB.BASEBOARD_FAB2(SCH_1):P3E_CPU0_PE1_SS_RXN<4>
    1  P3E_CPU0_PE1_PCH_RXN<4>      A  @BASEBOARD_FAB2_LIB.BASEBOARD_FAB2(SCH_1):P3E_CPU0_PE1_PCH_RXN<4>

CAP_0402  I297  C2U13  [CAP_0402-0.22UF,16V,10%,X7R,A3A]
    2  P3E_CPU0_PE1_SS_RXP<5>      B  @BASEBOARD_FAB2_LIB.BASEBOARD_FAB2(SCH_1):P3E_CPU0_PE1_SS_RXP<5>
    1  P3E_CPU0_PE1_PCH_RXP<5>      A  @BASEBOARD_FAB2_LIB.BASEBOARD_FAB2(SCH_1):P3E_CPU0_PE1_PCH_RXP<5>

CAP_0402  I287  C2U14  [CAP_0402-0.22UF,16V,10%,X7R,A3A]
    2  P3E_CPU0_PE1_SS_RXN<5>      B  @BASEBOARD_FAB2_LIB.BASEBOARD_FAB2(SCH_1):P3E_CPU0_PE1_SS_RXN<5>
    1  P3E_CPU0_PE1_PCH_RXN<5>      A  @BASEBOARD_FAB2_LIB.BASEBOARD_FAB2(SCH_1):P3E_CPU0_PE1_PCH_RXN<5>

CAP_0402  I296  C2U15  [CAP_0402-0.22UF,16V,10%,X7R,A3A]
    2  P3E_CPU0_PE1_SS_RXP<6>      B  @BASEBOARD_FAB2_LIB.BASEBOARD_FAB2(SCH_1):P3E_CPU0_PE1_SS_RXP<6>
    1  P3E_CPU0_PE1_PCH_RXP<6>      A  @BASEBOARD_FAB2_LIB.BASEBOARD_FAB2(SCH_1):P3E_CPU0_PE1_PCH_RXP<6>

CAP_0402  I286  C2U16  [CAP_0402-0.22UF,16V,10%,X7R,A3A]
    2  P3E_CPU0_PE1_SS_RXN<6>      B  @BASEBOARD_FAB2_LIB.BASEBOARD_FAB2(SCH_1):P3E_CPU0_PE1_SS_RXN<6>
    1  P3E_CPU0_PE1_PCH_RXN<6>      A  @BASEBOARD_FAB2_LIB.BASEBOARD_FAB2(SCH_1):P3E_CPU0_PE1_PCH_RXN<6>

CAP_0402  I300  C2U17  [CAP_0402-0.22UF,16V,10%,X7R,A3A]
    2  P3E_CPU0_PE1_SS_RXP<7>      B  @BASEBOARD_FAB2_LIB.BASEBOARD_FAB2(SCH_1):P3E_CPU0_PE1_SS_RXP<7>
    1  P3E_CPU0_PE1_PCH_RXP<7>      A  @BASEBOARD_FAB2_LIB.BASEBOARD_FAB2(SCH_1):P3E_CPU0_PE1_PCH_RXP<7>

CAP_0402  I294  C2U18  [CAP_0402-0.22UF,16V,10%,X7R,A3A]
    2  P3E_CPU0_PE1_SS_RXN<7>      B  @BASEBOARD_FAB2_LIB.BASEBOARD_FAB2(SCH_1):P3E_CPU0_PE1_SS_RXN<7>
    1  P3E_CPU0_PE1_PCH_RXN<7>      A  @BASEBOARD_FAB2_LIB.BASEBOARD_FAB2(SCH_1):P3E_CPU0_PE1_PCH_RXN<7>

CAP_A  I46  C2U19  [CAP_A_0402V-0.1UF,16V,10%,X7R,A]
    1  P3V3               A  @BASEBOARD_FAB2_LIB.BASEBOARD_FAB2(SCH_1):P3V3
    2  GND                B  @BASEBOARD_FAB2_LIB.BASEBOARD_FAB2(SCH_1):GND

CAP_A  I1   C2U20  [CAP_A_0402V-0.1UF,16V,10%,X7R,A]
    1  P12V               A  @BASEBOARD_FAB2_LIB.BASEBOARD_FAB2(SCH_1):P12V
    2  GND                B  @BASEBOARD_FAB2_LIB.BASEBOARD_FAB2(SCH_1):GND

CAP_A  I5   C2U21  [CAP_A_0402V-0.1UF,16V,10%,X7R,A]
    1  P3V3               A  @BASEBOARD_FAB2_LIB.BASEBOARD_FAB2(SCH_1):P3V3
    2  GND                B  @BASEBOARD_FAB2_LIB.BASEBOARD_FAB2(SCH_1):GND

CAP_A  I318  C2U22  [CAP_A_0402V-0.1UF,16V,10%,X7R,A]
    1  P3V3_STBY          A  @BASEBOARD_FAB2_LIB.BASEBOARD_FAB2(SCH_1):P3V3_STBY
    2  GND                B  @BASEBOARD_FAB2_LIB.BASEBOARD_FAB2(SCH_1):GND

CAP_A  I315  C2U23  [CAP_A_0402V-0.1UF,16V,10%,X7R,A]
    1  P3V3_STBY          A  @BASEBOARD_FAB2_LIB.BASEBOARD_FAB2(SCH_1):P3V3_STBY
    2  GND                B  @BASEBOARD_FAB2_LIB.BASEBOARD_FAB2(SCH_1):GND

CAP_A  I2   C2U24  [CAP_A_0402V-0.1UF,16V,10%,X7R,A]
    1  P12V               A  @BASEBOARD_FAB2_LIB.BASEBOARD_FAB2(SCH_1):P12V
    2  GND                B  @BASEBOARD_FAB2_LIB.BASEBOARD_FAB2(SCH_1):GND

CAP_A  I7   C2U25  [CAP_A_0402V-0.1UF,16V,10%,X7R,A]
    1  P3V3               A  @BASEBOARD_FAB2_LIB.BASEBOARD_FAB2(SCH_1):P3V3
    2  GND                B  @BASEBOARD_FAB2_LIB.BASEBOARD_FAB2(SCH_1):GND

CAP_A  I102  C2U26  [CAP_A_0402V-1.0UF,6.3V,10%,X6SA]
    1  P3V3_RTC_STBY      A  @BASEBOARD_FAB2_LIB.BASEBOARD_FAB2(SCH_1):P3V3_RTC_STBY
    2  GND                B  @BASEBOARD_FAB2_LIB.BASEBOARD_FAB2(SCH_1):GND

CAP_A  I90  C2U27  [CAP_A_0402V-0.1UF,16V,10%,X7R,A]
    1  P3V3_STBY          A  @BASEBOARD_FAB2_LIB.BASEBOARD_FAB2(SCH_1):P3V3_STBY
    2  GND                B  @BASEBOARD_FAB2_LIB.BASEBOARD_FAB2(SCH_1):GND

CAP_A  I93  C2U28  [CAP_A_0402V-0.1UF,16V,10%,X7R,A]
    1  P3V3_STBY          A  @BASEBOARD_FAB2_LIB.BASEBOARD_FAB2(SCH_1):P3V3_STBY
    2  GND                B  @BASEBOARD_FAB2_LIB.BASEBOARD_FAB2(SCH_1):GND

CAP_A  I217  C3A1   [CAP_A_0603V-22.0UF,4V,20%,X6S,A]
    1  PVDDQ_KLM          A  @BASEBOARD_FAB2_LIB.BASEBOARD_FAB2(SCH_1):PVDDQ_KLM
    2  GND                B  @BASEBOARD_FAB2_LIB.BASEBOARD_FAB2(SCH_1):GND

CAP_A  I216  C3A2   [CAP_A_0603V-22.0UF,4V,20%,X6S,A]
    1  PVDDQ_KLM          A  @BASEBOARD_FAB2_LIB.BASEBOARD_FAB2(SCH_1):PVDDQ_KLM
    2  GND                B  @BASEBOARD_FAB2_LIB.BASEBOARD_FAB2(SCH_1):GND

CAP  I97  C3A3   [CAP_0603LF-10UF,4V,20%,X6S,E15A]
    1  PVPP_KLM           A  @BASEBOARD_FAB2_LIB.BASEBOARD_FAB2(SCH_1):PVPP_KLM
    2  GND                B  @BASEBOARD_FAB2_LIB.BASEBOARD_FAB2(SCH_1):GND

CAP  I93  C3A4   [CAP_0603LF-10UF,4V,20%,X6S,E15A]
    1  PVPP_KLM           A  @BASEBOARD_FAB2_LIB.BASEBOARD_FAB2(SCH_1):PVPP_KLM
    2  GND                B  @BASEBOARD_FAB2_LIB.BASEBOARD_FAB2(SCH_1):GND

CAP_A  I222  C3A5   [CAP_A_0603V-22.0UF,4V,20%,X6S,A]
    1  PVDDQ_KLM          A  @BASEBOARD_FAB2_LIB.BASEBOARD_FAB2(SCH_1):PVDDQ_KLM
    2  GND                B  @BASEBOARD_FAB2_LIB.BASEBOARD_FAB2(SCH_1):GND

CAP_A  I223  C3A6   [CAP_A_0603V-22.0UF,4V,20%,X6S,A]
    1  PVDDQ_KLM          A  @BASEBOARD_FAB2_LIB.BASEBOARD_FAB2(SCH_1):PVDDQ_KLM
    2  GND                B  @BASEBOARD_FAB2_LIB.BASEBOARD_FAB2(SCH_1):GND

CAP  I95  C3A7   [CAP_0603LF-10UF,4V,20%,X6S,E15A]
    1  PVPP_KLM           A  @BASEBOARD_FAB2_LIB.BASEBOARD_FAB2(SCH_1):PVPP_KLM
    2  GND                B  @BASEBOARD_FAB2_LIB.BASEBOARD_FAB2(SCH_1):GND

CAP  I86  C3A8   [CAP_0603LF-10UF,4V,20%,X6S,E15A]
    1  PVPP_KLM           A  @BASEBOARD_FAB2_LIB.BASEBOARD_FAB2(SCH_1):PVPP_KLM
    2  GND                B  @BASEBOARD_FAB2_LIB.BASEBOARD_FAB2(SCH_1):GND

CAP  I94  C3B1   [CAP_0603LF-10UF,4V,20%,X6S,E15A]
    1  PVPP_KLM           A  @BASEBOARD_FAB2_LIB.BASEBOARD_FAB2(SCH_1):PVPP_KLM
    2  GND                B  @BASEBOARD_FAB2_LIB.BASEBOARD_FAB2(SCH_1):GND

CAP  I84  C3B2   [CAP_0603LF-10UF,4V,20%,X6S,E15A]
    1  PVPP_KLM           A  @BASEBOARD_FAB2_LIB.BASEBOARD_FAB2(SCH_1):PVPP_KLM
    2  GND                B  @BASEBOARD_FAB2_LIB.BASEBOARD_FAB2(SCH_1):GND

CAPP  I167  C3B3   [CAPP_7343LF-330UF,6.3V,20%,POSA]
    1  PVPP_KLM           A  @BASEBOARD_FAB2_LIB.BASEBOARD_FAB2(SCH_1):PVPP_KLM
    2  GND                B  @BASEBOARD_FAB2_LIB.BASEBOARD_FAB2(SCH_1):GND

CAP_A  I47  C3B4   [CAP_A_0402V-0.1UF,16V,10%,X7R,A]
    1  PVCCIO_CPU1        A  @BASEBOARD_FAB2_LIB.BASEBOARD_FAB2(SCH_1):PVCCIO_CPU1
    2  GND                B  @BASEBOARD_FAB2_LIB.BASEBOARD_FAB2(SCH_1):GND

CAP_A  I53  C3B5   [CAP_A_0402V-0.1UF,16V,10%,X7R,A]
    1  PVPP_KLM           A  @BASEBOARD_FAB2_LIB.BASEBOARD_FAB2(SCH_1):PVPP_KLM
    2  GND                B  @BASEBOARD_FAB2_LIB.BASEBOARD_FAB2(SCH_1):GND

CAPP  I100  C3B6   [CAPP_3018-68UF,16V,20%,TANT,72A]
    1  P12V_STBY          A  @BASEBOARD_FAB2_LIB.BASEBOARD_FAB2(SCH_1):P12V_STBY
    2  GND                B  @BASEBOARD_FAB2_LIB.BASEBOARD_FAB2(SCH_1):GND

CAP_A  I38  C3C1   [CAP_A_0402V-1.0UF,6.3V,10%,X6SA]
    1  PVCCIOMCP_CPU1      A  @BASEBOARD_FAB2_LIB.BASEBOARD_FAB2(SCH_1):PVCCIOMCP_CPU1
    2  GND                B  @BASEBOARD_FAB2_LIB.BASEBOARD_FAB2(SCH_1):GND

CAP_A  I31  C3C2   [CAP_A_0402V-1.0UF,6.3V,10%,X6SA]
    1  PVCCIOMCP_CPU1      A  @BASEBOARD_FAB2_LIB.BASEBOARD_FAB2(SCH_1):PVCCIOMCP_CPU1
    2  GND                B  @BASEBOARD_FAB2_LIB.BASEBOARD_FAB2(SCH_1):GND

CAP_A  I111  C3D1   [CAP_A_0603V-22.0UF,4V,20%,X6S,A]
    1  PVCCIN_CPU1        A  @BASEBOARD_FAB2_LIB.BASEBOARD_FAB2(SCH_1):PVCCIN_CPU1
    2  GND                B  @BASEBOARD_FAB2_LIB.BASEBOARD_FAB2(SCH_1):GND

CAP_A  I69  C3D2   [CAP_A_0603V-22.0UF,4V,20%,X6S,A]
    1  PVCCIN_CPU1        A  @BASEBOARD_FAB2_LIB.BASEBOARD_FAB2(SCH_1):PVCCIN_CPU1
    2  GND                B  @BASEBOARD_FAB2_LIB.BASEBOARD_FAB2(SCH_1):GND

CAP  I25  C3D3   [CAP_0603LF-10UF,4V,20%,X6S,E15A]
    1  P1V8_MCP_CPU1      A  @BASEBOARD_FAB2_LIB.BASEBOARD_FAB2(SCH_1):P1V8_MCP_CPU1
    2  GND                B  @BASEBOARD_FAB2_LIB.BASEBOARD_FAB2(SCH_1):GND

CAP_A  I5   C3D4   [CAP_A_0603V-22.0UF,4V,20%,X6S,A]
    1  PVCCMCP_CPU1       A  @BASEBOARD_FAB2_LIB.BASEBOARD_FAB2(SCH_1):PVCCMCP_CPU1
    2  GND                B  @BASEBOARD_FAB2_LIB.BASEBOARD_FAB2(SCH_1):GND

CAP_A  I3   C3D5   [CAP_A_0603V-22.0UF,4V,20%,X6S,A]
    1  PVCCMCP_CPU1       A  @BASEBOARD_FAB2_LIB.BASEBOARD_FAB2(SCH_1):PVCCMCP_CPU1
    2  GND                B  @BASEBOARD_FAB2_LIB.BASEBOARD_FAB2(SCH_1):GND

CAP_A  I170  C3D6   [CAP_A_0603V-22.0UF,4V,20%,X6S,A]
    1  PVCCMCP_CPU1       A  @BASEBOARD_FAB2_LIB.BASEBOARD_FAB2(SCH_1):PVCCMCP_CPU1
    2  GND                B  @BASEBOARD_FAB2_LIB.BASEBOARD_FAB2(SCH_1):GND

CAP_A  I164  C3D7   [CAP_A_0603V-22.0UF,4V,20%,X6S,A]
    1  PVCCMCP_CPU1       A  @BASEBOARD_FAB2_LIB.BASEBOARD_FAB2(SCH_1):PVCCMCP_CPU1
    2  GND                B  @BASEBOARD_FAB2_LIB.BASEBOARD_FAB2(SCH_1):GND

CAP_A  I18  C3D8   [CAP_A_0603V-22.0UF,4V,20%,X6S,A]
    1  PVCCIO_CPU1        A  @BASEBOARD_FAB2_LIB.BASEBOARD_FAB2(SCH_1):PVCCIO_CPU1
    2  GND                B  @BASEBOARD_FAB2_LIB.BASEBOARD_FAB2(SCH_1):GND

CAP_A  I15  C3D9   [CAP_A_0603V-22.0UF,4V,20%,X6S,A]
    1  PVCCIO_CPU1        A  @BASEBOARD_FAB2_LIB.BASEBOARD_FAB2(SCH_1):PVCCIO_CPU1
    2  GND                B  @BASEBOARD_FAB2_LIB.BASEBOARD_FAB2(SCH_1):GND

CAP_A  I196  C3D10  [CAP_A_0603V-22.0UF,4V,20%,X6S,A]
    1  PVCCMCP_CPU1       A  @BASEBOARD_FAB2_LIB.BASEBOARD_FAB2(SCH_1):PVCCMCP_CPU1
    2  GND                B  @BASEBOARD_FAB2_LIB.BASEBOARD_FAB2(SCH_1):GND

CAP_A  I7   C3D11  [CAP_A_0603V-22.0UF,4V,20%,X6S,A]
    1  PVCCMCP_CPU1       A  @BASEBOARD_FAB2_LIB.BASEBOARD_FAB2(SCH_1):PVCCMCP_CPU1
    2  GND                B  @BASEBOARD_FAB2_LIB.BASEBOARD_FAB2(SCH_1):GND

CAP_A  I4   C3D12  [CAP_A_0603V-22.0UF,4V,20%,X6S,A]
    1  PVCCMCP_CPU1       A  @BASEBOARD_FAB2_LIB.BASEBOARD_FAB2(SCH_1):PVCCMCP_CPU1
    2  GND                B  @BASEBOARD_FAB2_LIB.BASEBOARD_FAB2(SCH_1):GND

CAP_A  I8   C3D13  [CAP_A_0603V-22.0UF,4V,20%,X6S,A]
    1  PVCCMCP_CPU1       A  @BASEBOARD_FAB2_LIB.BASEBOARD_FAB2(SCH_1):PVCCMCP_CPU1
    2  GND                B  @BASEBOARD_FAB2_LIB.BASEBOARD_FAB2(SCH_1):GND

CAP_A  I171  C3D14  [CAP_A_0603V-22.0UF,4V,20%,X6S,A]
    1  PVCCMCP_CPU1       A  @BASEBOARD_FAB2_LIB.BASEBOARD_FAB2(SCH_1):PVCCMCP_CPU1
    2  GND                B  @BASEBOARD_FAB2_LIB.BASEBOARD_FAB2(SCH_1):GND

CAP_A  I174  C3D15  [CAP_A_0603V-22.0UF,4V,20%,X6S,A]
    1  PVCCIO_CPU1        A  @BASEBOARD_FAB2_LIB.BASEBOARD_FAB2(SCH_1):PVCCIO_CPU1
    2  GND                B  @BASEBOARD_FAB2_LIB.BASEBOARD_FAB2(SCH_1):GND

CAP_A  I176  C3D16  [CAP_A_0603V-22.0UF,4V,20%,X6S,A]
    1  PVCCIO_CPU1        A  @BASEBOARD_FAB2_LIB.BASEBOARD_FAB2(SCH_1):PVCCIO_CPU1
    2  GND                B  @BASEBOARD_FAB2_LIB.BASEBOARD_FAB2(SCH_1):GND

CAP_A  I166  C3D17  [CAP_A_0603V-22.0UF,4V,20%,X6S,A]
    1  PVCCMCP_CPU1       A  @BASEBOARD_FAB2_LIB.BASEBOARD_FAB2(SCH_1):PVCCMCP_CPU1
    2  GND                B  @BASEBOARD_FAB2_LIB.BASEBOARD_FAB2(SCH_1):GND

CAP_A  I169  C3D18  [CAP_A_0603V-22.0UF,4V,20%,X6S,A]
    1  PVCCMCP_CPU1       A  @BASEBOARD_FAB2_LIB.BASEBOARD_FAB2(SCH_1):PVCCMCP_CPU1
    2  GND                B  @BASEBOARD_FAB2_LIB.BASEBOARD_FAB2(SCH_1):GND

CAP_A  I208  C3D19  [CAP_A_0603V-22.0UF,4V,20%,X6S,A]
    1  PVCCMCP_CPU1       A  @BASEBOARD_FAB2_LIB.BASEBOARD_FAB2(SCH_1):PVCCMCP_CPU1
    2  GND                B  @BASEBOARD_FAB2_LIB.BASEBOARD_FAB2(SCH_1):GND

CAP_A  I207  C3D20  [CAP_A_0603V-22.0UF,4V,20%,X6S,A]
    1  PVCCMCP_CPU1       A  @BASEBOARD_FAB2_LIB.BASEBOARD_FAB2(SCH_1):PVCCMCP_CPU1
    2  GND                B  @BASEBOARD_FAB2_LIB.BASEBOARD_FAB2(SCH_1):GND

CAP_A  I1   C3D21  [CAP_A_0603V-22.0UF,4V,20%,X6S,A]
    1  PVCCMCP_CPU1       A  @BASEBOARD_FAB2_LIB.BASEBOARD_FAB2(SCH_1):PVCCMCP_CPU1
    2  GND                B  @BASEBOARD_FAB2_LIB.BASEBOARD_FAB2(SCH_1):GND

CAP  I10  C3D22  [CAP_0805-10UF,16V,10%,X7R,G106A]
    1  P3V3_DB1200        A  @BASEBOARD_FAB2_LIB.BASEBOARD_FAB2(SCH_1):P3V3_DB1200
    2  GND                B  @BASEBOARD_FAB2_LIB.BASEBOARD_FAB2(SCH_1):GND

CAP_A  I172  C3D23  [CAP_A_0603V-22.0UF,4V,20%,X6S,A]
    1  PVCCIO_CPU1        A  @BASEBOARD_FAB2_LIB.BASEBOARD_FAB2(SCH_1):PVCCIO_CPU1
    2  GND                B  @BASEBOARD_FAB2_LIB.BASEBOARD_FAB2(SCH_1):GND

CAP_A  I175  C3D24  [CAP_A_0603V-22.0UF,4V,20%,X6S,A]
    1  PVCCIO_CPU1        A  @BASEBOARD_FAB2_LIB.BASEBOARD_FAB2(SCH_1):PVCCIO_CPU1
    2  GND                B  @BASEBOARD_FAB2_LIB.BASEBOARD_FAB2(SCH_1):GND

CAP_A  I205  C3D25  [CAP_A_0603V-22.0UF,4V,20%,X6S,A]
    1  PVCCIN_CPU1        A  @BASEBOARD_FAB2_LIB.BASEBOARD_FAB2(SCH_1):PVCCIN_CPU1
    2  GND                B  @BASEBOARD_FAB2_LIB.BASEBOARD_FAB2(SCH_1):GND

CAP_A  I96  C3D27  [CAP_A_0402V-0.1UF,16V,10%,EMPTA]
    1  VSENSE_PVCCIO_CPU1_SKT_VSEN      A  @BASEBOARD_FAB2_LIB.BASEBOARD_FAB2(SCH_1):VSENSE_PVCCIO_CPU1_SKT_VSEN
    2  VSENSE_PVCCIO_CPU1_SKT_VRTN      B  @BASEBOARD_FAB2_LIB.BASEBOARD_FAB2(SCH_1):VSENSE_PVCCIO_CPU1_SKT_VRTN

CAP_A  I108  C3E1   [CAP_A_0603V-22.0UF,4V,20%,X6S,A]
    1  PVCCIO_CPU1        A  @BASEBOARD_FAB2_LIB.BASEBOARD_FAB2(SCH_1):PVCCIO_CPU1
    2  GND                B  @BASEBOARD_FAB2_LIB.BASEBOARD_FAB2(SCH_1):GND

CAP_A  I140  C3F1   [CAP_A_0603V-47UF,4V,20%,X5R,60A]
    1  P1V8_MCP_CPU1      A  @BASEBOARD_FAB2_LIB.BASEBOARD_FAB2(SCH_1):P1V8_MCP_CPU1
    2  GND                B  @BASEBOARD_FAB2_LIB.BASEBOARD_FAB2(SCH_1):GND

CAP_A  I34  C3F2   [CAP_A_0402V-0.1UF,16V,10%,X7R,A]
    1  P3V3               A  @BASEBOARD_FAB2_LIB.BASEBOARD_FAB2(SCH_1):P3V3
    2  GND                B  @BASEBOARD_FAB2_LIB.BASEBOARD_FAB2(SCH_1):GND

CAP  I116  C3F3   [CAP_0603LF-10UF,4V,20%,X6S,E15A]
    1  PVPP_GHJ           A  @BASEBOARD_FAB2_LIB.BASEBOARD_FAB2(SCH_1):PVPP_GHJ
    2  GND                B  @BASEBOARD_FAB2_LIB.BASEBOARD_FAB2(SCH_1):GND

CAP  I117  C3F4   [CAP_0603LF-10UF,4V,20%,X6S,E15A]
    1  PVPP_GHJ           A  @BASEBOARD_FAB2_LIB.BASEBOARD_FAB2(SCH_1):PVPP_GHJ
    2  GND                B  @BASEBOARD_FAB2_LIB.BASEBOARD_FAB2(SCH_1):GND

CAP_A  I212  C3G1   [CAP_A_0603V-22.0UF,4V,20%,X6S,A]
    1  PVDDQ_GHJ          A  @BASEBOARD_FAB2_LIB.BASEBOARD_FAB2(SCH_1):PVDDQ_GHJ
    2  GND                B  @BASEBOARD_FAB2_LIB.BASEBOARD_FAB2(SCH_1):GND

CAP_A  I211  C3G2   [CAP_A_0603V-22.0UF,4V,20%,X6S,A]
    1  PVDDQ_GHJ          A  @BASEBOARD_FAB2_LIB.BASEBOARD_FAB2(SCH_1):PVDDQ_GHJ
    2  GND                B  @BASEBOARD_FAB2_LIB.BASEBOARD_FAB2(SCH_1):GND

CAP  I118  C3G3   [CAP_0603LF-10UF,4V,20%,X6S,E15A]
    1  PVPP_GHJ           A  @BASEBOARD_FAB2_LIB.BASEBOARD_FAB2(SCH_1):PVPP_GHJ
    2  GND                B  @BASEBOARD_FAB2_LIB.BASEBOARD_FAB2(SCH_1):GND

CAP  I133  C3G4   [CAP_0603LF-10UF,4V,20%,X6S,E15A]
    1  PVPP_GHJ           A  @BASEBOARD_FAB2_LIB.BASEBOARD_FAB2(SCH_1):PVPP_GHJ
    2  GND                B  @BASEBOARD_FAB2_LIB.BASEBOARD_FAB2(SCH_1):GND

CAP_A  I208  C3G5   [CAP_A_0603V-22.0UF,4V,20%,X6S,A]
    1  PVDDQ_GHJ          A  @BASEBOARD_FAB2_LIB.BASEBOARD_FAB2(SCH_1):PVDDQ_GHJ
    2  GND                B  @BASEBOARD_FAB2_LIB.BASEBOARD_FAB2(SCH_1):GND

CAP_A  I207  C3G6   [CAP_A_0603V-22.0UF,4V,20%,X6S,A]
    1  PVDDQ_GHJ          A  @BASEBOARD_FAB2_LIB.BASEBOARD_FAB2(SCH_1):PVDDQ_GHJ
    2  GND                B  @BASEBOARD_FAB2_LIB.BASEBOARD_FAB2(SCH_1):GND

CAP  I132  C3G7   [CAP_0603LF-10UF,4V,20%,X6S,E15A]
    1  PVPP_GHJ           A  @BASEBOARD_FAB2_LIB.BASEBOARD_FAB2(SCH_1):PVPP_GHJ
    2  GND                B  @BASEBOARD_FAB2_LIB.BASEBOARD_FAB2(SCH_1):GND

CAP  I135  C3G8   [CAP_0603LF-10UF,4V,20%,X6S,E15A]
    1  PVPP_GHJ           A  @BASEBOARD_FAB2_LIB.BASEBOARD_FAB2(SCH_1):PVPP_GHJ
    2  GND                B  @BASEBOARD_FAB2_LIB.BASEBOARD_FAB2(SCH_1):GND

CAP_A  I17  C3L1   [CAP_A_0402V-1.0UF,6.3V,10%,X6SA]
    1  P5V_STBY           A  @BASEBOARD_FAB2_LIB.BASEBOARD_FAB2(SCH_1):P5V_STBY
    2  GND                B  @BASEBOARD_FAB2_LIB.BASEBOARD_FAB2(SCH_1):GND

CAP  I45  C3L2   [CAP_0805-10UF,16V,10%,X6S,C953A]
    1  VR_FET_SW_P12V_STBY_PVDDQ_DEF      A  @BASEBOARD_FAB2_LIB.BASEBOARD_FAB2(SCH_1):VR_FET_SW_P12V_STBY_PVDDQ_DEF
    2  GND                B  @BASEBOARD_FAB2_LIB.BASEBOARD_FAB2(SCH_1):GND

CAP  I46  C3L4   [CAP_0805-10UF,16V,10%,X6S,C953A]
    1  VR_FET_SW_P12V_STBY_PVDDQ_DEF      A  @BASEBOARD_FAB2_LIB.BASEBOARD_FAB2(SCH_1):VR_FET_SW_P12V_STBY_PVDDQ_DEF
    2  GND                B  @BASEBOARD_FAB2_LIB.BASEBOARD_FAB2(SCH_1):GND

CAPP  I75  C3L6   [CAPP_3018-470UF,2.5V,20%,ALUM,A]
    1  PVDDQ_DEF          A  @BASEBOARD_FAB2_LIB.BASEBOARD_FAB2(SCH_1):PVDDQ_DEF
    2  GND                B  @BASEBOARD_FAB2_LIB.BASEBOARD_FAB2(SCH_1):GND

CAP  I31  C3L7   [CAP_0805-10UF,16V,10%,X6S,C953A]
    1  VR_FET_SW_P12V_STBY_PVDDQ_DEF      A  @BASEBOARD_FAB2_LIB.BASEBOARD_FAB2(SCH_1):VR_FET_SW_P12V_STBY_PVDDQ_DEF
    2  GND                B  @BASEBOARD_FAB2_LIB.BASEBOARD_FAB2(SCH_1):GND

CAP  I26  C3L8   [CAP_0805-10UF,16V,10%,X6S,C953A]
    1  VR_FET_SW_P12V_STBY_PVDDQ_DEF      A  @BASEBOARD_FAB2_LIB.BASEBOARD_FAB2(SCH_1):VR_FET_SW_P12V_STBY_PVDDQ_DEF
    2  GND                B  @BASEBOARD_FAB2_LIB.BASEBOARD_FAB2(SCH_1):GND

CAP  I29  C3L9   [CAP_0805-10UF,16V,10%,X6S,C953A]
    1  VR_FET_SW_P12V_STBY_PVDDQ_DEF      A  @BASEBOARD_FAB2_LIB.BASEBOARD_FAB2(SCH_1):VR_FET_SW_P12V_STBY_PVDDQ_DEF
    2  GND                B  @BASEBOARD_FAB2_LIB.BASEBOARD_FAB2(SCH_1):GND

CAP  I32  C3L10  [CAP_0805-10UF,16V,10%,X6S,C953A]
    1  VR_FET_SW_P12V_STBY_PVDDQ_DEF      A  @BASEBOARD_FAB2_LIB.BASEBOARD_FAB2(SCH_1):VR_FET_SW_P12V_STBY_PVDDQ_DEF
    2  GND                B  @BASEBOARD_FAB2_LIB.BASEBOARD_FAB2(SCH_1):GND

CAP  I24  C3L11  [CAP_0805-10UF,16V,10%,X6S,C953A]
    1  VR_FET_SW_P12V_STBY_PVDDQ_DEF      A  @BASEBOARD_FAB2_LIB.BASEBOARD_FAB2(SCH_1):VR_FET_SW_P12V_STBY_PVDDQ_DEF
    2  GND                B  @BASEBOARD_FAB2_LIB.BASEBOARD_FAB2(SCH_1):GND

CAP  I23  C3L12  [CAP_0805-10UF,16V,10%,X6S,C953A]
    1  VR_FET_SW_P12V_STBY_PVDDQ_DEF      A  @BASEBOARD_FAB2_LIB.BASEBOARD_FAB2(SCH_1):VR_FET_SW_P12V_STBY_PVDDQ_DEF
    2  GND                B  @BASEBOARD_FAB2_LIB.BASEBOARD_FAB2(SCH_1):GND

CAP  I47  C3L13  [CAP_0805-10UF,16V,10%,X6S,C953A]
    1  VR_FET_SW_P12V_STBY_PVDDQ_DEF      A  @BASEBOARD_FAB2_LIB.BASEBOARD_FAB2(SCH_1):VR_FET_SW_P12V_STBY_PVDDQ_DEF
    2  GND                B  @BASEBOARD_FAB2_LIB.BASEBOARD_FAB2(SCH_1):GND

CAPP  I76  C3L14  [CAPP_3018-470UF,2.5V,20%,ALUM,A]
    1  PVDDQ_DEF          A  @BASEBOARD_FAB2_LIB.BASEBOARD_FAB2(SCH_1):PVDDQ_DEF
    2  GND                B  @BASEBOARD_FAB2_LIB.BASEBOARD_FAB2(SCH_1):GND

CAP  I84  C3L15  [CAP_0805-10UF,16V,10%,X6S,C953A]
    1  VR_FET_SW_P12V_STBY_PVDDQ_DEF      A  @BASEBOARD_FAB2_LIB.BASEBOARD_FAB2(SCH_1):VR_FET_SW_P12V_STBY_PVDDQ_DEF
    2  GND                B  @BASEBOARD_FAB2_LIB.BASEBOARD_FAB2(SCH_1):GND

CAP  I81  C3L16  [CAP_0805-10UF,16V,10%,X6S,C953A]
    1  VR_FET_SW_P12V_STBY_PVDDQ_DEF      A  @BASEBOARD_FAB2_LIB.BASEBOARD_FAB2(SCH_1):VR_FET_SW_P12V_STBY_PVDDQ_DEF
    2  GND                B  @BASEBOARD_FAB2_LIB.BASEBOARD_FAB2(SCH_1):GND

CAP  I80  C3L17  [CAP_0805-10UF,16V,10%,X6S,C953A]
    1  VR_FET_SW_P12V_STBY_PVDDQ_DEF      A  @BASEBOARD_FAB2_LIB.BASEBOARD_FAB2(SCH_1):VR_FET_SW_P12V_STBY_PVDDQ_DEF
    2  GND                B  @BASEBOARD_FAB2_LIB.BASEBOARD_FAB2(SCH_1):GND

CAPP  I71  C3L18  [CAPP_SM-470UF,2V,20%,ALUM,6990A]
    1  PVNN_PCH_STBY      A  @BASEBOARD_FAB2_LIB.BASEBOARD_FAB2(SCH_1):PVNN_PCH_STBY
    2  GND                B  @BASEBOARD_FAB2_LIB.BASEBOARD_FAB2(SCH_1):GND

CAPP  I76  C3L19  [CAPP_SM-470UF,2V,20%,ALUM,6990A]
    1  P1V05_PCH_STBY      A  @BASEBOARD_FAB2_LIB.BASEBOARD_FAB2(SCH_1):P1V05_PCH_STBY
    2  GND                B  @BASEBOARD_FAB2_LIB.BASEBOARD_FAB2(SCH_1):GND

CAPP  I73  C3L20  [CAPP_SM-470UF,2V,20%,ALUM,6990A]
    1  PVNN_PCH_STBY      A  @BASEBOARD_FAB2_LIB.BASEBOARD_FAB2(SCH_1):PVNN_PCH_STBY
    2  GND                B  @BASEBOARD_FAB2_LIB.BASEBOARD_FAB2(SCH_1):GND

CAPP  I74  C3L21  [CAPP_SM-470UF,2V,20%,ALUM,6990A]
    1  PVNN_PCH_STBY      A  @BASEBOARD_FAB2_LIB.BASEBOARD_FAB2(SCH_1):PVNN_PCH_STBY
    2  GND                B  @BASEBOARD_FAB2_LIB.BASEBOARD_FAB2(SCH_1):GND

CAP_A  I54  C3L22  [CAP_A_0603V-22.0UF,4V,20%,X6S,A]
    1  PVNN_PCH_STBY      A  @BASEBOARD_FAB2_LIB.BASEBOARD_FAB2(SCH_1):PVNN_PCH_STBY
    2  GND                B  @BASEBOARD_FAB2_LIB.BASEBOARD_FAB2(SCH_1):GND

CAP_A  I52  C3L23  [CAP_A_0603V-22.0UF,4V,20%,X6S,A]
    1  PVNN_PCH_STBY      A  @BASEBOARD_FAB2_LIB.BASEBOARD_FAB2(SCH_1):PVNN_PCH_STBY
    2  GND                B  @BASEBOARD_FAB2_LIB.BASEBOARD_FAB2(SCH_1):GND

CAP_A  I56  C3L24  [CAP_A_0603V-22.0UF,4V,20%,X6S,A]
    1  PVNN_PCH_STBY      A  @BASEBOARD_FAB2_LIB.BASEBOARD_FAB2(SCH_1):PVNN_PCH_STBY
    2  GND                B  @BASEBOARD_FAB2_LIB.BASEBOARD_FAB2(SCH_1):GND

CAP_A  I1   C3L25  [CAP_A_0603V-22.0UF,4V,20%,X6S,A]
    1  PVNN_PCH_STBY      A  @BASEBOARD_FAB2_LIB.BASEBOARD_FAB2(SCH_1):PVNN_PCH_STBY
    2  GND                B  @BASEBOARD_FAB2_LIB.BASEBOARD_FAB2(SCH_1):GND

CAP_A  I3   C3L26  [CAP_A_0603V-22.0UF,4V,20%,X6S,A]
    1  PVNN_PCH_STBY      A  @BASEBOARD_FAB2_LIB.BASEBOARD_FAB2(SCH_1):PVNN_PCH_STBY
    2  GND                B  @BASEBOARD_FAB2_LIB.BASEBOARD_FAB2(SCH_1):GND

CAP_A  I4   C3L27  [CAP_A_0603V-22.0UF,4V,20%,X6S,A]
    1  PVNN_PCH_STBY      A  @BASEBOARD_FAB2_LIB.BASEBOARD_FAB2(SCH_1):PVNN_PCH_STBY
    2  GND                B  @BASEBOARD_FAB2_LIB.BASEBOARD_FAB2(SCH_1):GND

CAP_A  I38  C3L29  [CAP_A_0402V-1.0UF,6.3V,10%,X6SA]
    1  P5V_STBY           A  @BASEBOARD_FAB2_LIB.BASEBOARD_FAB2(SCH_1):P5V_STBY
    2  GND                B  @BASEBOARD_FAB2_LIB.BASEBOARD_FAB2(SCH_1):GND

CAP_A  I77  C3L31  [CAP_A_0402V-0.1UF,16V,10%,X7R,A]
    1  VR_PVDDQ_DEF_AIINSEN      A  @BASEBOARD_FAB2_LIB.BASEBOARD_FAB2(SCH_1):VR_PVDDQ_DEF_AIINSEN
    2  GND                B  @BASEBOARD_FAB2_LIB.BASEBOARD_FAB2(SCH_1):GND

CAP_0402  I255  C3M1   [CAP_0402-0.22UF,16V,10%,X7R,A3A]
    1  P3E_CPU0_PE1_PCH_R_RXN<15>      A  @BASEBOARD_FAB2_LIB.BASEBOARD_FAB2(SCH_1):P3E_CPU0_PE1_PCH_R_RXN<15>
    2  P3E_CPU0_PE1_PCH_RXN<15>      B  @BASEBOARD_FAB2_LIB.BASEBOARD_FAB2(SCH_1):P3E_CPU0_PE1_PCH_RXN<15>

CAP_0402  I247  C3M2   [CAP_0402-0.22UF,16V,10%,X7R,A3A]
    1  P3E_CPU0_PE1_PCH_R_RXP<15>      A  @BASEBOARD_FAB2_LIB.BASEBOARD_FAB2(SCH_1):P3E_CPU0_PE1_PCH_R_RXP<15>
    2  P3E_CPU0_PE1_PCH_RXP<15>      B  @BASEBOARD_FAB2_LIB.BASEBOARD_FAB2(SCH_1):P3E_CPU0_PE1_PCH_RXP<15>

CAP_0402  I232  C3M3   [CAP_0402-0.22UF,16V,10%,X7R,A3A]
    1  P3E_CPU0_PE1_PCH_R_RXP<12>      A  @BASEBOARD_FAB2_LIB.BASEBOARD_FAB2(SCH_1):P3E_CPU0_PE1_PCH_R_RXP<12>
    2  P3E_CPU0_PE1_PCH_RXP<12>      B  @BASEBOARD_FAB2_LIB.BASEBOARD_FAB2(SCH_1):P3E_CPU0_PE1_PCH_RXP<12>

CAP_0402  I244  C3M4   [CAP_0402-0.22UF,16V,10%,X7R,A3A]
    1  P3E_CPU0_PE1_PCH_R_RXN<12>      A  @BASEBOARD_FAB2_LIB.BASEBOARD_FAB2(SCH_1):P3E_CPU0_PE1_PCH_R_RXN<12>
    2  P3E_CPU0_PE1_PCH_RXN<12>      B  @BASEBOARD_FAB2_LIB.BASEBOARD_FAB2(SCH_1):P3E_CPU0_PE1_PCH_RXN<12>

CAP_A  I6   C3M6   [CAP_A_0603V-22.0UF,4V,20%,X6S,A]
    1  PVNN_PCH_STBY      A  @BASEBOARD_FAB2_LIB.BASEBOARD_FAB2(SCH_1):PVNN_PCH_STBY
    2  GND                B  @BASEBOARD_FAB2_LIB.BASEBOARD_FAB2(SCH_1):GND

CAP_A  I2   C3M7   [CAP_A_0603V-22.0UF,4V,20%,X6S,A]
    1  PVNN_PCH_STBY      A  @BASEBOARD_FAB2_LIB.BASEBOARD_FAB2(SCH_1):PVNN_PCH_STBY
    2  GND                B  @BASEBOARD_FAB2_LIB.BASEBOARD_FAB2(SCH_1):GND

CAP  I259  C3M8   [CAP_0805-10UF,16V,10%,X6S,C953A]
    1  VR_FET_SW_P12V_STBY_PVPP_DEF      A  @BASEBOARD_FAB2_LIB.BASEBOARD_FAB2(SCH_1):VR_FET_SW_P12V_STBY_PVPP_DEF
    2  GND                B  @BASEBOARD_FAB2_LIB.BASEBOARD_FAB2(SCH_1):GND

CAP_0402  I207  C3M9   [CAP_0402-1.0UF,16V,10%,X6S,D97A]
    1  VR_FET_SW_P12V_STBY_PVPP_DEF      A  @BASEBOARD_FAB2_LIB.BASEBOARD_FAB2(SCH_1):VR_FET_SW_P12V_STBY_PVPP_DEF
    2  GND                B  @BASEBOARD_FAB2_LIB.BASEBOARD_FAB2(SCH_1):GND

CAP  I253  C3M10  [CAP_0603-4.7UF,6.3V,10%,X6S,E1A]
    1  VR_VB_PVPP_DEF      A  @BASEBOARD_FAB2_LIB.BASEBOARD_FAB2(SCH_1):VR_VB_PVPP_DEF
    2  AGND_PVPP_DEF      B  @BASEBOARD_FAB2_LIB.BASEBOARD_FAB2(SCH_1):AGND_PVPP_DEF

CAP_0402  I234  C3M11  [CAP_0402-0.22UF,16V,10%,X7R,A3A]
    1  P3E_CPU0_PE1_PCH_R_RXP<14>      A  @BASEBOARD_FAB2_LIB.BASEBOARD_FAB2(SCH_1):P3E_CPU0_PE1_PCH_R_RXP<14>
    2  P3E_CPU0_PE1_PCH_RXP<14>      B  @BASEBOARD_FAB2_LIB.BASEBOARD_FAB2(SCH_1):P3E_CPU0_PE1_PCH_RXP<14>

CAP_0402  I246  C3M12  [CAP_0402-0.22UF,16V,10%,X7R,A3A]
    1  P3E_CPU0_PE1_PCH_R_RXN<14>      A  @BASEBOARD_FAB2_LIB.BASEBOARD_FAB2(SCH_1):P3E_CPU0_PE1_PCH_R_RXN<14>
    2  P3E_CPU0_PE1_PCH_RXN<14>      B  @BASEBOARD_FAB2_LIB.BASEBOARD_FAB2(SCH_1):P3E_CPU0_PE1_PCH_RXN<14>

CAP_0402  I239  C3M13  [CAP_0402-0.22UF,16V,10%,X7R,A3A]
    1  P3E_CPU0_PE1_PCH_R_RXP<13>      A  @BASEBOARD_FAB2_LIB.BASEBOARD_FAB2(SCH_1):P3E_CPU0_PE1_PCH_R_RXP<13>
    2  P3E_CPU0_PE1_PCH_RXP<13>      B  @BASEBOARD_FAB2_LIB.BASEBOARD_FAB2(SCH_1):P3E_CPU0_PE1_PCH_RXP<13>

CAP_0402  I253  C3M14  [CAP_0402-0.22UF,16V,10%,X7R,A3A]
    1  P3E_CPU0_PE1_PCH_R_RXN<13>      A  @BASEBOARD_FAB2_LIB.BASEBOARD_FAB2(SCH_1):P3E_CPU0_PE1_PCH_R_RXN<13>
    2  P3E_CPU0_PE1_PCH_RXN<13>      B  @BASEBOARD_FAB2_LIB.BASEBOARD_FAB2(SCH_1):P3E_CPU0_PE1_PCH_RXN<13>

CAP  I260  C3M15  [CAP_0805-10UF,16V,10%,X6S,C953A]
    1  VR_FET_SW_P12V_STBY_PVPP_DEF      A  @BASEBOARD_FAB2_LIB.BASEBOARD_FAB2(SCH_1):VR_FET_SW_P12V_STBY_PVPP_DEF
    2  GND                B  @BASEBOARD_FAB2_LIB.BASEBOARD_FAB2(SCH_1):GND

CAP  I261  C3M16  [CAP_0805-10UF,16V,10%,X6S,C953A]
    1  VR_FET_SW_P12V_STBY_PVPP_DEF      A  @BASEBOARD_FAB2_LIB.BASEBOARD_FAB2(SCH_1):VR_FET_SW_P12V_STBY_PVPP_DEF
    2  GND                B  @BASEBOARD_FAB2_LIB.BASEBOARD_FAB2(SCH_1):GND

CAP  I86  C3M17  [CAP_0603LF-10UF,4V,20%,X6S,E15A]
    1  P1V05_PCH_STBY_VCCA_PLL1      A  @BASEBOARD_FAB2_LIB.BASEBOARD_FAB2(SCH_1):P1V05_PCH_STBY_VCCA_PLL1
    2  GND                B  @BASEBOARD_FAB2_LIB.BASEBOARD_FAB2(SCH_1):GND

CAP  I85  C3M18  [CAP_0603LF-10UF,4V,20%,X6S,E15A]
    1  P1V05_PCH_STBY_VCCA_PLL0      A  @BASEBOARD_FAB2_LIB.BASEBOARD_FAB2(SCH_1):P1V05_PCH_STBY_VCCA_PLL0
    2  GND                B  @BASEBOARD_FAB2_LIB.BASEBOARD_FAB2(SCH_1):GND

CAP_A  I87  C3M19  [CAP_A_0402V-1.0UF,6.3V,10%,X6SA]
    1  P1V05_PCH_STBY_VCCA_PLL1      A  @BASEBOARD_FAB2_LIB.BASEBOARD_FAB2(SCH_1):P1V05_PCH_STBY_VCCA_PLL1
    2  GND                B  @BASEBOARD_FAB2_LIB.BASEBOARD_FAB2(SCH_1):GND

CAP_A  I84  C3M20  [CAP_A_0402V-1.0UF,6.3V,10%,X6SA]
    1  P1V05_PCH_STBY_VCCA_PLL0      A  @BASEBOARD_FAB2_LIB.BASEBOARD_FAB2(SCH_1):P1V05_PCH_STBY_VCCA_PLL0
    2  GND                B  @BASEBOARD_FAB2_LIB.BASEBOARD_FAB2(SCH_1):GND

CAP_A  I9   C3M21  [CAP_A_0402V-1.0UF,6.3V,10%,X6SA]
    1  P1V05_PCH_STBY      A  @BASEBOARD_FAB2_LIB.BASEBOARD_FAB2(SCH_1):P1V05_PCH_STBY
    2  GND                B  @BASEBOARD_FAB2_LIB.BASEBOARD_FAB2(SCH_1):GND

CAP_A  I18  C3M22  [CAP_A_0402V-1.0UF,6.3V,10%,X6SA]
    1  P1V05_PCH_STBY      A  @BASEBOARD_FAB2_LIB.BASEBOARD_FAB2(SCH_1):P1V05_PCH_STBY
    2  GND                B  @BASEBOARD_FAB2_LIB.BASEBOARD_FAB2(SCH_1):GND

CAP  I82  C3M23  [CAP_0603LF-10UF,4V,20%,X6S,E15A]
    1  P1V05_PCH_STBY_VCCA_XTAL      A  @BASEBOARD_FAB2_LIB.BASEBOARD_FAB2(SCH_1):P1V05_PCH_STBY_VCCA_XTAL
    2  GND                B  @BASEBOARD_FAB2_LIB.BASEBOARD_FAB2(SCH_1):GND

CAP  I81  C3M24  [CAP_0603LF-10UF,4V,20%,X6S,E15A]
    1  P1V05_PCH_STBY_ISCLK_PLL      A  @BASEBOARD_FAB2_LIB.BASEBOARD_FAB2(SCH_1):P1V05_PCH_STBY_ISCLK_PLL
    2  GND                B  @BASEBOARD_FAB2_LIB.BASEBOARD_FAB2(SCH_1):GND

CAP_0402  I205  C3M25  [CAP_0402-0.22UF,16V,10%,X7R,A3A]
    1  P3E_CPU0_PE1_PCH_R_RXP<11>      A  @BASEBOARD_FAB2_LIB.BASEBOARD_FAB2(SCH_1):P3E_CPU0_PE1_PCH_R_RXP<11>
    2  P3E_CPU0_PE1_PCH_RXP<11>      B  @BASEBOARD_FAB2_LIB.BASEBOARD_FAB2(SCH_1):P3E_CPU0_PE1_PCH_RXP<11>

CAP_0402  I229  C3M26  [CAP_0402-0.22UF,16V,10%,X7R,A3A]
    1  P3E_CPU0_PE1_PCH_R_RXN<11>      A  @BASEBOARD_FAB2_LIB.BASEBOARD_FAB2(SCH_1):P3E_CPU0_PE1_PCH_R_RXN<11>
    2  P3E_CPU0_PE1_PCH_RXN<11>      B  @BASEBOARD_FAB2_LIB.BASEBOARD_FAB2(SCH_1):P3E_CPU0_PE1_PCH_RXN<11>

CAP_A  I83  C3M27  [CAP_A_0402V-1.0UF,6.3V,10%,X6SA]
    1  P1V05_PCH_STBY_VCCA_XTAL      A  @BASEBOARD_FAB2_LIB.BASEBOARD_FAB2(SCH_1):P1V05_PCH_STBY_VCCA_XTAL
    2  GND                B  @BASEBOARD_FAB2_LIB.BASEBOARD_FAB2(SCH_1):GND

CAP_0402  I212  C3M28  [CAP_0402-0.22UF,16V,10%,X7R,A3A]
    1  P3E_CPU0_PE1_PCH_R_RXP<10>      A  @BASEBOARD_FAB2_LIB.BASEBOARD_FAB2(SCH_1):P3E_CPU0_PE1_PCH_R_RXP<10>
    2  P3E_CPU0_PE1_PCH_RXP<10>      B  @BASEBOARD_FAB2_LIB.BASEBOARD_FAB2(SCH_1):P3E_CPU0_PE1_PCH_RXP<10>

CAP_A  I80  C3M29  [CAP_A_0402V-1.0UF,6.3V,10%,X6SA]
    1  P1V05_PCH_STBY_ISCLK_PLL      A  @BASEBOARD_FAB2_LIB.BASEBOARD_FAB2(SCH_1):P1V05_PCH_STBY_ISCLK_PLL
    2  GND                B  @BASEBOARD_FAB2_LIB.BASEBOARD_FAB2(SCH_1):GND

CAP_A  I27  C3M30  [CAP_A_0402V-1.0UF,6.3V,10%,X6SA]
    1  P1V05_PCH_STBY      A  @BASEBOARD_FAB2_LIB.BASEBOARD_FAB2(SCH_1):P1V05_PCH_STBY
    2  GND                B  @BASEBOARD_FAB2_LIB.BASEBOARD_FAB2(SCH_1):GND

CAP_A  I57  C3M31  [CAP_A_0402V-1.0UF,6.3V,10%,X6SA]
    1  P1V05_PCH_STBY      A  @BASEBOARD_FAB2_LIB.BASEBOARD_FAB2(SCH_1):P1V05_PCH_STBY
    2  GND                B  @BASEBOARD_FAB2_LIB.BASEBOARD_FAB2(SCH_1):GND

CAP_0402  I223  C3M32  [CAP_0402-0.22UF,16V,10%,X7R,A3A]
    1  P3E_CPU0_PE1_PCH_R_RXN<10>      A  @BASEBOARD_FAB2_LIB.BASEBOARD_FAB2(SCH_1):P3E_CPU0_PE1_PCH_R_RXN<10>
    2  P3E_CPU0_PE1_PCH_RXN<10>      B  @BASEBOARD_FAB2_LIB.BASEBOARD_FAB2(SCH_1):P3E_CPU0_PE1_PCH_RXN<10>

CAP_0402  I217  C3M33  [CAP_0402-0.22UF,16V,10%,X7R,A3A]
    1  P3E_CPU0_PE1_PCH_R_RXN<8>      A  @BASEBOARD_FAB2_LIB.BASEBOARD_FAB2(SCH_1):P3E_CPU0_PE1_PCH_R_RXN<8>
    2  P3E_CPU0_PE1_PCH_RXN<8>      B  @BASEBOARD_FAB2_LIB.BASEBOARD_FAB2(SCH_1):P3E_CPU0_PE1_PCH_RXN<8>

CAP_0402  I206  C3M34  [CAP_0402-0.22UF,16V,10%,X7R,A3A]
    1  P3E_CPU0_PE1_PCH_R_RXP<8>      A  @BASEBOARD_FAB2_LIB.BASEBOARD_FAB2(SCH_1):P3E_CPU0_PE1_PCH_R_RXP<8>
    2  P3E_CPU0_PE1_PCH_RXP<8>      B  @BASEBOARD_FAB2_LIB.BASEBOARD_FAB2(SCH_1):P3E_CPU0_PE1_PCH_RXP<8>

CAP_0402  I225  C3M35  [CAP_0402-0.22UF,16V,10%,X7R,A3A]
    1  P3E_CPU0_PE1_PCH_R_RXN<9>      A  @BASEBOARD_FAB2_LIB.BASEBOARD_FAB2(SCH_1):P3E_CPU0_PE1_PCH_R_RXN<9>
    2  P3E_CPU0_PE1_PCH_RXN<9>      B  @BASEBOARD_FAB2_LIB.BASEBOARD_FAB2(SCH_1):P3E_CPU0_PE1_PCH_RXN<9>

CAP_0402  I218  C3M36  [CAP_0402-0.22UF,16V,10%,X7R,A3A]
    1  P3E_CPU0_PE1_PCH_R_RXP<9>      A  @BASEBOARD_FAB2_LIB.BASEBOARD_FAB2(SCH_1):P3E_CPU0_PE1_PCH_R_RXP<9>
    2  P3E_CPU0_PE1_PCH_RXP<9>      B  @BASEBOARD_FAB2_LIB.BASEBOARD_FAB2(SCH_1):P3E_CPU0_PE1_PCH_RXP<9>

CAP_0402  I73  C3M37  [CAP_0402-0.22UF,16V,10%,X7R,A3A]
    1  DMI_CPU0_PCH_RX_DP<1>      A  @BASEBOARD_FAB2_LIB.BASEBOARD_FAB2(SCH_1):DMI_CPU0_PCH_RX_DP<1>
    2  DMI_CPU0_PCH_RX_C_DP<1>      B  @BASEBOARD_FAB2_LIB.BASEBOARD_FAB2(SCH_1):DMI_CPU0_PCH_RX_C_DP<1>

CAP_A  I32  C3M38  [CAP_A_0402V-1.0UF,6.3V,10%,X6SA]
    1  P1V05_PCH_STBY      A  @BASEBOARD_FAB2_LIB.BASEBOARD_FAB2(SCH_1):P1V05_PCH_STBY
    2  GND                B  @BASEBOARD_FAB2_LIB.BASEBOARD_FAB2(SCH_1):GND

CAP_A  I44  C3M39  [CAP_A_0402V-1.0UF,6.3V,10%,X6SA]
    1  P1V05_PCH_STBY      A  @BASEBOARD_FAB2_LIB.BASEBOARD_FAB2(SCH_1):P1V05_PCH_STBY
    2  GND                B  @BASEBOARD_FAB2_LIB.BASEBOARD_FAB2(SCH_1):GND

CAP_0402  I72  C3M40  [CAP_0402-0.22UF,16V,10%,X7R,A3A]
    1  DMI_CPU0_PCH_RX_DP<0>      A  @BASEBOARD_FAB2_LIB.BASEBOARD_FAB2(SCH_1):DMI_CPU0_PCH_RX_DP<0>
    2  DMI_CPU0_PCH_RX_C_DP<0>      B  @BASEBOARD_FAB2_LIB.BASEBOARD_FAB2(SCH_1):DMI_CPU0_PCH_RX_C_DP<0>

CAP_0402  I81  C3M41  [CAP_0402-0.22UF,16V,10%,X7R,A3A]
    1  DMI_CPU0_PCH_RX_DN<1>      A  @BASEBOARD_FAB2_LIB.BASEBOARD_FAB2(SCH_1):DMI_CPU0_PCH_RX_DN<1>
    2  DMI_CPU0_PCH_RX_C_DN<1>      B  @BASEBOARD_FAB2_LIB.BASEBOARD_FAB2(SCH_1):DMI_CPU0_PCH_RX_C_DN<1>

CAP_A  I45  C3M42  [CAP_A_0402V-1.0UF,6.3V,10%,X6SA]
    1  P1V05_PCH_STBY      A  @BASEBOARD_FAB2_LIB.BASEBOARD_FAB2(SCH_1):P1V05_PCH_STBY
    2  GND                B  @BASEBOARD_FAB2_LIB.BASEBOARD_FAB2(SCH_1):GND

CAP_A  I42  C3M43  [CAP_A_0402V-1.0UF,6.3V,10%,X6SA]
    1  P1V05_PCH_STBY      A  @BASEBOARD_FAB2_LIB.BASEBOARD_FAB2(SCH_1):P1V05_PCH_STBY
    2  GND                B  @BASEBOARD_FAB2_LIB.BASEBOARD_FAB2(SCH_1):GND

CAP_0402  I80  C3M44  [CAP_0402-0.22UF,16V,10%,X7R,A3A]
    1  DMI_CPU0_PCH_RX_DN<0>      A  @BASEBOARD_FAB2_LIB.BASEBOARD_FAB2(SCH_1):DMI_CPU0_PCH_RX_DN<0>
    2  DMI_CPU0_PCH_RX_C_DN<0>      B  @BASEBOARD_FAB2_LIB.BASEBOARD_FAB2(SCH_1):DMI_CPU0_PCH_RX_C_DN<0>

CAP_0402  I82  C3M45  [CAP_0402-0.22UF,16V,10%,X7R,A3A]
    1  DMI_CPU0_PCH_RX_DN<2>      A  @BASEBOARD_FAB2_LIB.BASEBOARD_FAB2(SCH_1):DMI_CPU0_PCH_RX_DN<2>
    2  DMI_CPU0_PCH_RX_C_DN<2>      B  @BASEBOARD_FAB2_LIB.BASEBOARD_FAB2(SCH_1):DMI_CPU0_PCH_RX_C_DN<2>

CAP_A  I99  C3M46  [CAP_A_0402V-1.0UF,6.3V,10%,X6SA]
    1  PVCCIOMCP_CPU0      A  @BASEBOARD_FAB2_LIB.BASEBOARD_FAB2(SCH_1):PVCCIOMCP_CPU0
    2  GND                B  @BASEBOARD_FAB2_LIB.BASEBOARD_FAB2(SCH_1):GND

CAP_A  I34  C3N1   [CAP_A_0402V-1.0UF,6.3V,10%,X6SA]
    1  PVNN_PCH_STBY      A  @BASEBOARD_FAB2_LIB.BASEBOARD_FAB2(SCH_1):PVNN_PCH_STBY
    2  GND                B  @BASEBOARD_FAB2_LIB.BASEBOARD_FAB2(SCH_1):GND

CAP_A  I43  C3N2   [CAP_A_0402V-1.0UF,6.3V,10%,X6SA]
    1  PVNN_PCH_STBY      A  @BASEBOARD_FAB2_LIB.BASEBOARD_FAB2(SCH_1):PVNN_PCH_STBY
    2  GND                B  @BASEBOARD_FAB2_LIB.BASEBOARD_FAB2(SCH_1):GND

CAP_A  I32  C3N3   [CAP_A_0402V-1.0UF,6.3V,10%,X6SA]
    1  PVNN_PCH_STBY      A  @BASEBOARD_FAB2_LIB.BASEBOARD_FAB2(SCH_1):PVNN_PCH_STBY
    2  GND                B  @BASEBOARD_FAB2_LIB.BASEBOARD_FAB2(SCH_1):GND

CAP_A  I46  C3N4   [CAP_A_0402V-1.0UF,6.3V,10%,X6SA]
    1  PVNN_PCH_STBY      A  @BASEBOARD_FAB2_LIB.BASEBOARD_FAB2(SCH_1):PVNN_PCH_STBY
    2  GND                B  @BASEBOARD_FAB2_LIB.BASEBOARD_FAB2(SCH_1):GND

CAP_A  I48  C3N5   [CAP_A_0402V-1.0UF,6.3V,10%,X6SA]
    1  PVNN_PCH_STBY      A  @BASEBOARD_FAB2_LIB.BASEBOARD_FAB2(SCH_1):PVNN_PCH_STBY
    2  GND                B  @BASEBOARD_FAB2_LIB.BASEBOARD_FAB2(SCH_1):GND

CAP_A  I44  C3N6   [CAP_A_0402V-1.0UF,6.3V,10%,X6SA]
    1  PVNN_PCH_STBY      A  @BASEBOARD_FAB2_LIB.BASEBOARD_FAB2(SCH_1):PVNN_PCH_STBY
    2  GND                B  @BASEBOARD_FAB2_LIB.BASEBOARD_FAB2(SCH_1):GND

CAP_A  I35  C3N7   [CAP_A_0402V-1.0UF,6.3V,10%,X6SA]
    1  PVNN_PCH_STBY      A  @BASEBOARD_FAB2_LIB.BASEBOARD_FAB2(SCH_1):PVNN_PCH_STBY
    2  GND                B  @BASEBOARD_FAB2_LIB.BASEBOARD_FAB2(SCH_1):GND

CAP_0402  I75  C3N8   [CAP_0402-0.22UF,16V,10%,X7R,A3A]
    1  DMI_CPU0_PCH_RX_DP<3>      A  @BASEBOARD_FAB2_LIB.BASEBOARD_FAB2(SCH_1):DMI_CPU0_PCH_RX_DP<3>
    2  DMI_CPU0_PCH_RX_C_DP<3>      B  @BASEBOARD_FAB2_LIB.BASEBOARD_FAB2(SCH_1):DMI_CPU0_PCH_RX_C_DP<3>

CAP_0402  I74  C3N9   [CAP_0402-0.22UF,16V,10%,X7R,A3A]
    1  DMI_CPU0_PCH_RX_DP<2>      A  @BASEBOARD_FAB2_LIB.BASEBOARD_FAB2(SCH_1):DMI_CPU0_PCH_RX_DP<2>
    2  DMI_CPU0_PCH_RX_C_DP<2>      B  @BASEBOARD_FAB2_LIB.BASEBOARD_FAB2(SCH_1):DMI_CPU0_PCH_RX_C_DP<2>

CAP_A  I13  C3N10  [CAP_A_0603V-22.0UF,4V,20%,X6S,A]
    1  PVNN_PCH_STBY      A  @BASEBOARD_FAB2_LIB.BASEBOARD_FAB2(SCH_1):PVNN_PCH_STBY
    2  GND                B  @BASEBOARD_FAB2_LIB.BASEBOARD_FAB2(SCH_1):GND

CAP_A  I19  C3N11  [CAP_A_0603V-22.0UF,4V,20%,X6S,A]
    1  PVNN_PCH_STBY      A  @BASEBOARD_FAB2_LIB.BASEBOARD_FAB2(SCH_1):PVNN_PCH_STBY
    2  GND                B  @BASEBOARD_FAB2_LIB.BASEBOARD_FAB2(SCH_1):GND

CAP_A  I12  C3N12  [CAP_A_0603V-22.0UF,4V,20%,X6S,A]
    1  PVNN_PCH_STBY      A  @BASEBOARD_FAB2_LIB.BASEBOARD_FAB2(SCH_1):PVNN_PCH_STBY
    2  GND                B  @BASEBOARD_FAB2_LIB.BASEBOARD_FAB2(SCH_1):GND

CAP_0402  I83  C3N13  [CAP_0402-0.22UF,16V,10%,X7R,A3A]
    1  DMI_CPU0_PCH_RX_DN<3>      A  @BASEBOARD_FAB2_LIB.BASEBOARD_FAB2(SCH_1):DMI_CPU0_PCH_RX_DN<3>
    2  DMI_CPU0_PCH_RX_C_DN<3>      B  @BASEBOARD_FAB2_LIB.BASEBOARD_FAB2(SCH_1):DMI_CPU0_PCH_RX_C_DN<3>

CAPP  I101  C3N14  [CAPP_3018-470UF,2.5V,20%,ALUM,A]
    1  PVCCIOMCP_CPU0      A  @BASEBOARD_FAB2_LIB.BASEBOARD_FAB2(SCH_1):PVCCIOMCP_CPU0
    2  GND                B  @BASEBOARD_FAB2_LIB.BASEBOARD_FAB2(SCH_1):GND

CAP_A  I49  C3N15  [CAP_A_0402V-1.0UF,6.3V,10%,X6SA]
    1  PVNN_PCH_STBY      A  @BASEBOARD_FAB2_LIB.BASEBOARD_FAB2(SCH_1):PVNN_PCH_STBY
    2  GND                B  @BASEBOARD_FAB2_LIB.BASEBOARD_FAB2(SCH_1):GND

CAP_A  I36  C3N16  [CAP_A_0402V-1.0UF,6.3V,10%,X6SA]
    1  PVNN_PCH_STBY      A  @BASEBOARD_FAB2_LIB.BASEBOARD_FAB2(SCH_1):PVNN_PCH_STBY
    2  GND                B  @BASEBOARD_FAB2_LIB.BASEBOARD_FAB2(SCH_1):GND

CAP_A  I45  C3N17  [CAP_A_0402V-1.0UF,6.3V,10%,X6SA]
    1  PVNN_PCH_STBY      A  @BASEBOARD_FAB2_LIB.BASEBOARD_FAB2(SCH_1):PVNN_PCH_STBY
    2  GND                B  @BASEBOARD_FAB2_LIB.BASEBOARD_FAB2(SCH_1):GND

CAP_A  I42  C3N18  [CAP_A_0402V-1.0UF,6.3V,10%,X6SA]
    1  PVNN_PCH_STBY      A  @BASEBOARD_FAB2_LIB.BASEBOARD_FAB2(SCH_1):PVNN_PCH_STBY
    2  GND                B  @BASEBOARD_FAB2_LIB.BASEBOARD_FAB2(SCH_1):GND

CAP_A  I31  C3N19  [CAP_A_0402V-1.0UF,6.3V,10%,X6SA]
    1  PVNN_PCH_STBY      A  @BASEBOARD_FAB2_LIB.BASEBOARD_FAB2(SCH_1):PVNN_PCH_STBY
    2  GND                B  @BASEBOARD_FAB2_LIB.BASEBOARD_FAB2(SCH_1):GND

CAP_A  I51  C3N20  [CAP_A_0402V-1.0UF,6.3V,10%,X6SA]
    1  PVNN_PCH_STBY      A  @BASEBOARD_FAB2_LIB.BASEBOARD_FAB2(SCH_1):PVNN_PCH_STBY
    2  GND                B  @BASEBOARD_FAB2_LIB.BASEBOARD_FAB2(SCH_1):GND

CAP_A  I49  C3N21  [CAP_A_0402V-1.0UF,6.3V,10%,X6SA]
    1  P1V8_PCH_STBY      A  @BASEBOARD_FAB2_LIB.BASEBOARD_FAB2(SCH_1):P1V8_PCH_STBY
    2  GND                B  @BASEBOARD_FAB2_LIB.BASEBOARD_FAB2(SCH_1):GND

CAP_A  I53  C3N22  [CAP_A_0402V-1.0UF,6.3V,10%,X6SA]
    1  P1V8_PCH_STBY      A  @BASEBOARD_FAB2_LIB.BASEBOARD_FAB2(SCH_1):P1V8_PCH_STBY
    2  GND                B  @BASEBOARD_FAB2_LIB.BASEBOARD_FAB2(SCH_1):GND

CAP_A  I42  C3N23  [CAP_A_0402V-1.0UF,6.3V,10%,X6SA]
    1  P3V3_STBY          A  @BASEBOARD_FAB2_LIB.BASEBOARD_FAB2(SCH_1):P3V3_STBY
    2  GND                B  @BASEBOARD_FAB2_LIB.BASEBOARD_FAB2(SCH_1):GND

CAP_A  I16  C3N24  [CAP_A_0603V-22.0UF,4V,20%,X6S,A]
    1  PVNN_PCH_STBY      A  @BASEBOARD_FAB2_LIB.BASEBOARD_FAB2(SCH_1):PVNN_PCH_STBY
    2  GND                B  @BASEBOARD_FAB2_LIB.BASEBOARD_FAB2(SCH_1):GND

CAP_A  I50  C3N25  [CAP_A_0402V-1.0UF,6.3V,10%,X6SA]
    1  P1V8_PCH_STBY      A  @BASEBOARD_FAB2_LIB.BASEBOARD_FAB2(SCH_1):P1V8_PCH_STBY
    2  GND                B  @BASEBOARD_FAB2_LIB.BASEBOARD_FAB2(SCH_1):GND

CAPP  I17  C3N26  [CAPP_3018-470UF,2.5V,20%,ALUM,A]
    1  PVCCIO_CPU0        A  @BASEBOARD_FAB2_LIB.BASEBOARD_FAB2(SCH_1):PVCCIO_CPU0
    2  GND                B  @BASEBOARD_FAB2_LIB.BASEBOARD_FAB2(SCH_1):GND

CAP_A  I8   C3N27  [CAP_A_0603V-22.0UF,4V,20%,X6S,A]
    1  PVNN_PCH_STBY      A  @BASEBOARD_FAB2_LIB.BASEBOARD_FAB2(SCH_1):PVNN_PCH_STBY
    2  GND                B  @BASEBOARD_FAB2_LIB.BASEBOARD_FAB2(SCH_1):GND

CAP_A  I17  C3N28  [CAP_A_0603V-22.0UF,4V,20%,X6S,A]
    1  PVNN_PCH_STBY      A  @BASEBOARD_FAB2_LIB.BASEBOARD_FAB2(SCH_1):PVNN_PCH_STBY
    2  GND                B  @BASEBOARD_FAB2_LIB.BASEBOARD_FAB2(SCH_1):GND

CAP_A  I16  C3N29  [CAP_A_0402V-0.1UF,16V,10%,X7R,A]
    2  GND                B  @BASEBOARD_FAB2_LIB.BASEBOARD_FAB2(SCH_1):GND
    1  A_PVCCRTC_EXT_CAP      A  @BASEBOARD_FAB2_LIB.BASEBOARD_FAB2(SCH_1):A_PVCCRTC_EXT_CAP

CAP_A  I9   C3N30  [CAP_A_0603V-22.0UF,4V,20%,X6S,A]
    1  PVNN_PCH_STBY      A  @BASEBOARD_FAB2_LIB.BASEBOARD_FAB2(SCH_1):PVNN_PCH_STBY
    2  GND                B  @BASEBOARD_FAB2_LIB.BASEBOARD_FAB2(SCH_1):GND

CAP_A  I20  C3N31  [CAP_A_0603V-22.0UF,4V,20%,X6S,A]
    1  PVNN_PCH_STBY      A  @BASEBOARD_FAB2_LIB.BASEBOARD_FAB2(SCH_1):PVNN_PCH_STBY
    2  GND                B  @BASEBOARD_FAB2_LIB.BASEBOARD_FAB2(SCH_1):GND

CAP_A  I20  C3N32  [CAP_A_0402V-1.0UF,6.3V,10%,X6SA]
    1  RST_SRTCRST_N      A  @BASEBOARD_FAB2_LIB.BASEBOARD_FAB2(SCH_1):RST_SRTCRST_N
    2  GND                B  @BASEBOARD_FAB2_LIB.BASEBOARD_FAB2(SCH_1):GND

CAP  I41  C3N33  [CAP_0805-10UF,16V,10%,X6S,C953A]
    1  VR_FET_SW_P12V_STBY_PVCCIO_CPU0      A  @BASEBOARD_FAB2_LIB.BASEBOARD_FAB2(SCH_1):VR_FET_SW_P12V_STBY_PVCCIO_CPU0
    2  GND                B  @BASEBOARD_FAB2_LIB.BASEBOARD_FAB2(SCH_1):GND

CAP  I43  C3N34  [CAP_0805-10UF,16V,10%,X6S,C953A]
    1  VR_FET_SW_P12V_STBY_PVCCIO_CPU0      A  @BASEBOARD_FAB2_LIB.BASEBOARD_FAB2(SCH_1):VR_FET_SW_P12V_STBY_PVCCIO_CPU0
    2  GND                B  @BASEBOARD_FAB2_LIB.BASEBOARD_FAB2(SCH_1):GND

CAPP  I18  C3N35  [CAPP_3018-470UF,2.5V,20%,ALUM,A]
    1  PVCCIO_CPU0        A  @BASEBOARD_FAB2_LIB.BASEBOARD_FAB2(SCH_1):PVCCIO_CPU0
    2  GND                B  @BASEBOARD_FAB2_LIB.BASEBOARD_FAB2(SCH_1):GND

CAP  I40  C3N36  [CAP_0805-10UF,16V,10%,X6S,C953A]
    1  VR_FET_SW_P12V_STBY_PVCCIO_CPU0      A  @BASEBOARD_FAB2_LIB.BASEBOARD_FAB2(SCH_1):VR_FET_SW_P12V_STBY_PVCCIO_CPU0
    2  GND                B  @BASEBOARD_FAB2_LIB.BASEBOARD_FAB2(SCH_1):GND

CAPP  I16  C3N38  [CAPP_3018-470UF,2.5V,20%,ALUM,A]
    1  PVCCIO_CPU0        A  @BASEBOARD_FAB2_LIB.BASEBOARD_FAB2(SCH_1):PVCCIO_CPU0
    2  GND                B  @BASEBOARD_FAB2_LIB.BASEBOARD_FAB2(SCH_1):GND

CAP  I83  C3N39  [CAP_0402LF-220PF,50V,10%,X7R,AA]
    2  VSENSE_PVCCIO_CPU0_AVSN      B  @BASEBOARD_FAB2_LIB.BASEBOARD_FAB2(SCH_1):VSENSE_PVCCIO_CPU0_AVSN
    1  VR_PVCCIO_CPU0_AVSP      A  @BASEBOARD_FAB2_LIB.BASEBOARD_FAB2(SCH_1):VR_PVCCIO_CPU0_AVSP

CAP_A  I86  C3N40  [CAP_A_0402V-1.0UF,6.3V,10%,X6SA]
    1  PVCCIOMCP_CPU0      A  @BASEBOARD_FAB2_LIB.BASEBOARD_FAB2(SCH_1):PVCCIOMCP_CPU0
    2  GND                B  @BASEBOARD_FAB2_LIB.BASEBOARD_FAB2(SCH_1):GND

CAP_A  I60  C3P1   [CAP_A_0402V-0.1UF,16V,10%,EMPTA]
    1  VSENSE_PVCCIO_CPU0_SKT_VSEN      A  @BASEBOARD_FAB2_LIB.BASEBOARD_FAB2(SCH_1):VSENSE_PVCCIO_CPU0_SKT_VSEN
    2  VSENSE_PVCCIO_CPU0_SKT_VRTN      B  @BASEBOARD_FAB2_LIB.BASEBOARD_FAB2(SCH_1):VSENSE_PVCCIO_CPU0_SKT_VRTN

CAP  I33  C3P2   [CAP_0402LF-1000PF,50V,10%,X7R,A]
    1  VR_PVCCIO_CPU0_VINSEN      A  @BASEBOARD_FAB2_LIB.BASEBOARD_FAB2(SCH_1):VR_PVCCIO_CPU0_VINSEN
    2  GND                B  @BASEBOARD_FAB2_LIB.BASEBOARD_FAB2(SCH_1):GND

CAP_A  I20  C3P3   [CAP_A_0402V-1.0UF,6.3V,10%,X6SA]
    1  VR_PVCCIO_CPU0_VDD      A  @BASEBOARD_FAB2_LIB.BASEBOARD_FAB2(SCH_1):VR_PVCCIO_CPU0_VDD
    2  GND                B  @BASEBOARD_FAB2_LIB.BASEBOARD_FAB2(SCH_1):GND

CAP_A  I11  C3P4   [CAP_A_0402V-1.0UF,6.3V,10%,X6SA]
    1  VR_PVCCIO_CPU0_VD12      A  @BASEBOARD_FAB2_LIB.BASEBOARD_FAB2(SCH_1):VR_PVCCIO_CPU0_VD12
    2  GND                B  @BASEBOARD_FAB2_LIB.BASEBOARD_FAB2(SCH_1):GND

CAP_A  I13  C3P5   [CAP_A_0402V-0.1UF,16V,10%,X7R,A]
    1  VR_PVCCIO_CPU0_VD12      A  @BASEBOARD_FAB2_LIB.BASEBOARD_FAB2(SCH_1):VR_PVCCIO_CPU0_VD12
    2  GND                B  @BASEBOARD_FAB2_LIB.BASEBOARD_FAB2(SCH_1):GND

CAP  I71  C3P6   [CAP_0402LF-1000PF,50V,10%,X7R,A]
    1  PWRGD_PVCCIO_CPU0_R      A  @BASEBOARD_FAB2_LIB.BASEBOARD_FAB2(SCH_1):PWRGD_PVCCIO_CPU0_R
    2  GND                B  @BASEBOARD_FAB2_LIB.BASEBOARD_FAB2(SCH_1):GND

CAP_A  I22  C3P7   [CAP_A_0402V-0.1UF,16V,10%,X7R,A]
    1  VR_PVCCIO_CPU0_VDD      A  @BASEBOARD_FAB2_LIB.BASEBOARD_FAB2(SCH_1):VR_PVCCIO_CPU0_VDD
    2  GND                B  @BASEBOARD_FAB2_LIB.BASEBOARD_FAB2(SCH_1):GND

CAP_0402  I417  C3P10  [CAP_0402-0.22UF,16V,10%,EMPTY,A]
    1  P3E_CPU0_PE1_SS_TXP<0>      A  @BASEBOARD_FAB2_LIB.BASEBOARD_FAB2(SCH_1):P3E_CPU0_PE1_SS_TXP<0>
    2  P3E_CPU0_PE1_SS_C_TXP<0>      B  @BASEBOARD_FAB2_LIB.BASEBOARD_FAB2(SCH_1):P3E_CPU0_PE1_SS_C_TXP<0>

CAP_0402  I212  C3P11  [CAP_0402-0.22UF,16V,10%,X7R,A3A]
    1  P3E_CPU0_PE1_SS_TXP<0>      A  @BASEBOARD_FAB2_LIB.BASEBOARD_FAB2(SCH_1):P3E_CPU0_PE1_SS_TXP<0>
    2  P3E_CPU0_PE1_PCH_TXP<0>      B  @BASEBOARD_FAB2_LIB.BASEBOARD_FAB2(SCH_1):P3E_CPU0_PE1_PCH_TXP<0>

CAP_0402  I415  C3P12  [CAP_0402-0.22UF,16V,10%,EMPTY,A]
    1  P3E_CPU0_PE1_SS_TXN<0>      A  @BASEBOARD_FAB2_LIB.BASEBOARD_FAB2(SCH_1):P3E_CPU0_PE1_SS_TXN<0>
    2  P3E_CPU0_PE1_SS_C_TXN<0>      B  @BASEBOARD_FAB2_LIB.BASEBOARD_FAB2(SCH_1):P3E_CPU0_PE1_SS_C_TXN<0>

CAP_0402  I207  C3P13  [CAP_0402-0.22UF,16V,10%,X7R,A3A]
    1  P3E_CPU0_PE1_SS_TXN<0>      A  @BASEBOARD_FAB2_LIB.BASEBOARD_FAB2(SCH_1):P3E_CPU0_PE1_SS_TXN<0>
    2  P3E_CPU0_PE1_PCH_TXN<0>      B  @BASEBOARD_FAB2_LIB.BASEBOARD_FAB2(SCH_1):P3E_CPU0_PE1_PCH_TXN<0>

CAP_0402  I431  C3P14  [CAP_0402-0.22UF,16V,10%,EMPTY,A]
    1  P3E_CPU0_PE1_SS_TXP<1>      A  @BASEBOARD_FAB2_LIB.BASEBOARD_FAB2(SCH_1):P3E_CPU0_PE1_SS_TXP<1>
    2  P3E_CPU0_PE1_SS_C_TXP<1>      B  @BASEBOARD_FAB2_LIB.BASEBOARD_FAB2(SCH_1):P3E_CPU0_PE1_SS_C_TXP<1>

CAP_0402  I226  C3P15  [CAP_0402-0.22UF,16V,10%,X7R,A3A]
    1  P3E_CPU0_PE1_SS_TXP<1>      A  @BASEBOARD_FAB2_LIB.BASEBOARD_FAB2(SCH_1):P3E_CPU0_PE1_SS_TXP<1>
    2  P3E_CPU0_PE1_PCH_TXP<1>      B  @BASEBOARD_FAB2_LIB.BASEBOARD_FAB2(SCH_1):P3E_CPU0_PE1_PCH_TXP<1>

CAP_0402  I422  C3P16  [CAP_0402-0.22UF,16V,10%,EMPTY,A]
    1  P3E_CPU0_PE1_SS_TXN<1>      A  @BASEBOARD_FAB2_LIB.BASEBOARD_FAB2(SCH_1):P3E_CPU0_PE1_SS_TXN<1>
    2  P3E_CPU0_PE1_SS_C_TXN<1>      B  @BASEBOARD_FAB2_LIB.BASEBOARD_FAB2(SCH_1):P3E_CPU0_PE1_SS_C_TXN<1>

CAP_0402  I208  C3P17  [CAP_0402-0.22UF,16V,10%,X7R,A3A]
    1  P3E_CPU0_PE1_SS_TXN<1>      A  @BASEBOARD_FAB2_LIB.BASEBOARD_FAB2(SCH_1):P3E_CPU0_PE1_SS_TXN<1>
    2  P3E_CPU0_PE1_PCH_TXN<1>      B  @BASEBOARD_FAB2_LIB.BASEBOARD_FAB2(SCH_1):P3E_CPU0_PE1_PCH_TXN<1>

CAP_0402  I219  C3P18  [CAP_0402-0.22UF,16V,10%,X7R,A3A]
    1  P3E_CPU0_PE1_SS_TXP<2>      A  @BASEBOARD_FAB2_LIB.BASEBOARD_FAB2(SCH_1):P3E_CPU0_PE1_SS_TXP<2>
    2  P3E_CPU0_PE1_PCH_TXP<2>      B  @BASEBOARD_FAB2_LIB.BASEBOARD_FAB2(SCH_1):P3E_CPU0_PE1_PCH_TXP<2>

CAP_0402  I427  C3P19  [CAP_0402-0.22UF,16V,10%,EMPTY,A]
    1  P3E_CPU0_PE1_SS_TXP<2>      A  @BASEBOARD_FAB2_LIB.BASEBOARD_FAB2(SCH_1):P3E_CPU0_PE1_SS_TXP<2>
    2  P3E_CPU0_PE1_SS_C_TXP<2>      B  @BASEBOARD_FAB2_LIB.BASEBOARD_FAB2(SCH_1):P3E_CPU0_PE1_SS_C_TXP<2>

CAP_0402  I215  C3P20  [CAP_0402-0.22UF,16V,10%,X7R,A3A]
    1  P3E_CPU0_PE1_SS_TXN<2>      A  @BASEBOARD_FAB2_LIB.BASEBOARD_FAB2(SCH_1):P3E_CPU0_PE1_SS_TXN<2>
    2  P3E_CPU0_PE1_PCH_TXN<2>      B  @BASEBOARD_FAB2_LIB.BASEBOARD_FAB2(SCH_1):P3E_CPU0_PE1_PCH_TXN<2>

CAP_0402  I423  C3P21  [CAP_0402-0.22UF,16V,10%,EMPTY,A]
    1  P3E_CPU0_PE1_SS_TXN<2>      A  @BASEBOARD_FAB2_LIB.BASEBOARD_FAB2(SCH_1):P3E_CPU0_PE1_SS_TXN<2>
    2  P3E_CPU0_PE1_SS_C_TXN<2>      B  @BASEBOARD_FAB2_LIB.BASEBOARD_FAB2(SCH_1):P3E_CPU0_PE1_SS_C_TXN<2>

CAP_0402  I435  C3P22  [CAP_0402-0.22UF,16V,10%,EMPTY,A]
    1  P3E_CPU0_PE1_SS_TXP<3>      A  @BASEBOARD_FAB2_LIB.BASEBOARD_FAB2(SCH_1):P3E_CPU0_PE1_SS_TXP<3>
    2  P3E_CPU0_PE1_SS_C_TXP<3>      B  @BASEBOARD_FAB2_LIB.BASEBOARD_FAB2(SCH_1):P3E_CPU0_PE1_SS_C_TXP<3>

CAP_0402  I229  C3P23  [CAP_0402-0.22UF,16V,10%,X7R,A3A]
    1  P3E_CPU0_PE1_SS_TXP<3>      A  @BASEBOARD_FAB2_LIB.BASEBOARD_FAB2(SCH_1):P3E_CPU0_PE1_SS_TXP<3>
    2  P3E_CPU0_PE1_PCH_TXP<3>      B  @BASEBOARD_FAB2_LIB.BASEBOARD_FAB2(SCH_1):P3E_CPU0_PE1_PCH_TXP<3>

CAP_0402  I424  C3P24  [CAP_0402-0.22UF,16V,10%,EMPTY,A]
    1  P3E_CPU0_PE1_SS_TXN<3>      A  @BASEBOARD_FAB2_LIB.BASEBOARD_FAB2(SCH_1):P3E_CPU0_PE1_SS_TXN<3>
    2  P3E_CPU0_PE1_SS_C_TXN<3>      B  @BASEBOARD_FAB2_LIB.BASEBOARD_FAB2(SCH_1):P3E_CPU0_PE1_SS_C_TXN<3>

CAP_0402  I216  C3P25  [CAP_0402-0.22UF,16V,10%,X7R,A3A]
    1  P3E_CPU0_PE1_SS_TXN<3>      A  @BASEBOARD_FAB2_LIB.BASEBOARD_FAB2(SCH_1):P3E_CPU0_PE1_SS_TXN<3>
    2  P3E_CPU0_PE1_PCH_TXN<3>      B  @BASEBOARD_FAB2_LIB.BASEBOARD_FAB2(SCH_1):P3E_CPU0_PE1_PCH_TXN<3>

CAP_0402  I444  C3P26  [CAP_0402-0.22UF,16V,10%,EMPTY,A]
    1  P3E_CPU0_PE1_SS_TXP<4>      A  @BASEBOARD_FAB2_LIB.BASEBOARD_FAB2(SCH_1):P3E_CPU0_PE1_SS_TXP<4>
    2  P3E_CPU0_PE1_SS_C_TXP<4>      B  @BASEBOARD_FAB2_LIB.BASEBOARD_FAB2(SCH_1):P3E_CPU0_PE1_SS_C_TXP<4>

CAP_0402  I223  C3P27  [CAP_0402-0.22UF,16V,10%,X7R,A3A]
    1  P3E_CPU0_PE1_SS_TXP<4>      A  @BASEBOARD_FAB2_LIB.BASEBOARD_FAB2(SCH_1):P3E_CPU0_PE1_SS_TXP<4>
    2  P3E_CPU0_PE1_PCH_TXP<4>      B  @BASEBOARD_FAB2_LIB.BASEBOARD_FAB2(SCH_1):P3E_CPU0_PE1_PCH_TXP<4>

CAP_0402  I232  C3P28  [CAP_0402-0.22UF,16V,10%,X7R,A3A]
    1  P3E_CPU0_PE1_SS_TXN<4>      A  @BASEBOARD_FAB2_LIB.BASEBOARD_FAB2(SCH_1):P3E_CPU0_PE1_SS_TXN<4>
    2  P3E_CPU0_PE1_PCH_TXN<4>      B  @BASEBOARD_FAB2_LIB.BASEBOARD_FAB2(SCH_1):P3E_CPU0_PE1_PCH_TXN<4>

CAP_0402  I437  C3P29  [CAP_0402-0.22UF,16V,10%,EMPTY,A]
    1  P3E_CPU0_PE1_SS_TXN<4>      A  @BASEBOARD_FAB2_LIB.BASEBOARD_FAB2(SCH_1):P3E_CPU0_PE1_SS_TXN<4>
    2  P3E_CPU0_PE1_SS_C_TXN<4>      B  @BASEBOARD_FAB2_LIB.BASEBOARD_FAB2(SCH_1):P3E_CPU0_PE1_SS_C_TXN<4>

CAP_0402  I245  C3P30  [CAP_0402-0.22UF,16V,10%,X7R,A3A]
    1  P3E_CPU0_PE1_SS_TXP<5>      A  @BASEBOARD_FAB2_LIB.BASEBOARD_FAB2(SCH_1):P3E_CPU0_PE1_SS_TXP<5>
    2  P3E_CPU0_PE1_PCH_TXP<5>      B  @BASEBOARD_FAB2_LIB.BASEBOARD_FAB2(SCH_1):P3E_CPU0_PE1_PCH_TXP<5>

CAP_0402  I452  C3P31  [CAP_0402-0.22UF,16V,10%,EMPTY,A]
    1  P3E_CPU0_PE1_SS_TXP<5>      A  @BASEBOARD_FAB2_LIB.BASEBOARD_FAB2(SCH_1):P3E_CPU0_PE1_SS_TXP<5>
    2  P3E_CPU0_PE1_SS_C_TXP<5>      B  @BASEBOARD_FAB2_LIB.BASEBOARD_FAB2(SCH_1):P3E_CPU0_PE1_SS_C_TXP<5>

CAP_0402  I234  C3P32  [CAP_0402-0.22UF,16V,10%,X7R,A3A]
    1  P3E_CPU0_PE1_SS_TXN<5>      A  @BASEBOARD_FAB2_LIB.BASEBOARD_FAB2(SCH_1):P3E_CPU0_PE1_SS_TXN<5>
    2  P3E_CPU0_PE1_PCH_TXN<5>      B  @BASEBOARD_FAB2_LIB.BASEBOARD_FAB2(SCH_1):P3E_CPU0_PE1_PCH_TXN<5>

CAP_0402  I439  C3P33  [CAP_0402-0.22UF,16V,10%,EMPTY,A]
    1  P3E_CPU0_PE1_SS_TXN<5>      A  @BASEBOARD_FAB2_LIB.BASEBOARD_FAB2(SCH_1):P3E_CPU0_PE1_SS_TXN<5>
    2  P3E_CPU0_PE1_SS_C_TXN<5>      B  @BASEBOARD_FAB2_LIB.BASEBOARD_FAB2(SCH_1):P3E_CPU0_PE1_SS_C_TXN<5>

CAP_0402  I447  C3P34  [CAP_0402-0.22UF,16V,10%,EMPTY,A]
    1  P3E_CPU0_PE1_SS_TXP<6>      A  @BASEBOARD_FAB2_LIB.BASEBOARD_FAB2(SCH_1):P3E_CPU0_PE1_SS_TXP<6>
    2  P3E_CPU0_PE1_SS_C_TXP<6>      B  @BASEBOARD_FAB2_LIB.BASEBOARD_FAB2(SCH_1):P3E_CPU0_PE1_SS_C_TXP<6>

CAP_0402  I240  C3P35  [CAP_0402-0.22UF,16V,10%,X7R,A3A]
    1  P3E_CPU0_PE1_SS_TXP<6>      A  @BASEBOARD_FAB2_LIB.BASEBOARD_FAB2(SCH_1):P3E_CPU0_PE1_SS_TXP<6>
    2  P3E_CPU0_PE1_PCH_TXP<6>      B  @BASEBOARD_FAB2_LIB.BASEBOARD_FAB2(SCH_1):P3E_CPU0_PE1_PCH_TXP<6>

CAP_0402  I438  C3P36  [CAP_0402-0.22UF,16V,10%,EMPTY,A]
    1  P3E_CPU0_PE1_SS_TXN<6>      A  @BASEBOARD_FAB2_LIB.BASEBOARD_FAB2(SCH_1):P3E_CPU0_PE1_SS_TXN<6>
    2  P3E_CPU0_PE1_SS_C_TXN<6>      B  @BASEBOARD_FAB2_LIB.BASEBOARD_FAB2(SCH_1):P3E_CPU0_PE1_SS_C_TXN<6>

CAP_0402  I235  C3P37  [CAP_0402-0.22UF,16V,10%,X7R,A3A]
    1  P3E_CPU0_PE1_SS_TXN<6>      A  @BASEBOARD_FAB2_LIB.BASEBOARD_FAB2(SCH_1):P3E_CPU0_PE1_SS_TXN<6>
    2  P3E_CPU0_PE1_PCH_TXN<6>      B  @BASEBOARD_FAB2_LIB.BASEBOARD_FAB2(SCH_1):P3E_CPU0_PE1_PCH_TXN<6>

CAP_0402  I455  C3P38  [CAP_0402-0.22UF,16V,10%,EMPTY,A]
    1  P3E_CPU0_PE1_SS_TXP<7>      A  @BASEBOARD_FAB2_LIB.BASEBOARD_FAB2(SCH_1):P3E_CPU0_PE1_SS_TXP<7>
    2  P3E_CPU0_PE1_SS_C_TXP<7>      B  @BASEBOARD_FAB2_LIB.BASEBOARD_FAB2(SCH_1):P3E_CPU0_PE1_SS_C_TXP<7>

CAP_0402  I248  C3P39  [CAP_0402-0.22UF,16V,10%,X7R,A3A]
    1  P3E_CPU0_PE1_SS_TXP<7>      A  @BASEBOARD_FAB2_LIB.BASEBOARD_FAB2(SCH_1):P3E_CPU0_PE1_SS_TXP<7>
    2  P3E_CPU0_PE1_PCH_TXP<7>      B  @BASEBOARD_FAB2_LIB.BASEBOARD_FAB2(SCH_1):P3E_CPU0_PE1_PCH_TXP<7>

CAP_0402  I241  C3P40  [CAP_0402-0.22UF,16V,10%,X7R,A3A]
    1  P3E_CPU0_PE1_SS_TXN<7>      A  @BASEBOARD_FAB2_LIB.BASEBOARD_FAB2(SCH_1):P3E_CPU0_PE1_SS_TXN<7>
    2  P3E_CPU0_PE1_PCH_TXN<7>      B  @BASEBOARD_FAB2_LIB.BASEBOARD_FAB2(SCH_1):P3E_CPU0_PE1_PCH_TXN<7>

CAP_0402  I448  C3P41  [CAP_0402-0.22UF,16V,10%,EMPTY,A]
    1  P3E_CPU0_PE1_SS_TXN<7>      A  @BASEBOARD_FAB2_LIB.BASEBOARD_FAB2(SCH_1):P3E_CPU0_PE1_SS_TXN<7>
    2  P3E_CPU0_PE1_SS_C_TXN<7>      B  @BASEBOARD_FAB2_LIB.BASEBOARD_FAB2(SCH_1):P3E_CPU0_PE1_SS_C_TXN<7>

CAP_A  I73  C3P42  [CAP_A_0402V-1.0UF,6.3V,10%,X6SA]
    1  P3V3_STBY          A  @BASEBOARD_FAB2_LIB.BASEBOARD_FAB2(SCH_1):P3V3_STBY
    2  GND                B  @BASEBOARD_FAB2_LIB.BASEBOARD_FAB2(SCH_1):GND

CAP_A  I6   C3P43  [CAP_A_0402V-0.1UF,16V,10%,X7R,A]
    1  P3V3_STBY          A  @BASEBOARD_FAB2_LIB.BASEBOARD_FAB2(SCH_1):P3V3_STBY
    2  GND                B  @BASEBOARD_FAB2_LIB.BASEBOARD_FAB2(SCH_1):GND

CAP_A  I23  C3P44  [CAP_A_0402V-0.1UF,16V,10%,X7R,A]
    1  P3V3_STBY          A  @BASEBOARD_FAB2_LIB.BASEBOARD_FAB2(SCH_1):P3V3_STBY
    2  GND                B  @BASEBOARD_FAB2_LIB.BASEBOARD_FAB2(SCH_1):GND

CAP_0402  I60  C3P45  [CAP_0402-0.047UF,25V,10%,X7R,AA]
    2  GND                B  @BASEBOARD_FAB2_LIB.BASEBOARD_FAB2(SCH_1):GND
    1  A_ADM1085_CEXT      A  @BASEBOARD_FAB2_LIB.BASEBOARD_FAB2(SCH_1):A_ADM1085_CEXT

CAP_A  I72  C3P46  [CAP_A_0402V-0.1UF,16V,10%,X7R,A]
    1  P3V3_STBY          A  @BASEBOARD_FAB2_LIB.BASEBOARD_FAB2(SCH_1):P3V3_STBY
    2  GND                B  @BASEBOARD_FAB2_LIB.BASEBOARD_FAB2(SCH_1):GND

CAP_A  I12  C3P47  [CAP_A_0402V-0.1UF,16V,10%,X7R,A]
    1  P3V3_STBY          A  @BASEBOARD_FAB2_LIB.BASEBOARD_FAB2(SCH_1):P3V3_STBY
    2  GND                B  @BASEBOARD_FAB2_LIB.BASEBOARD_FAB2(SCH_1):GND

CAP_A  I25  C3P48  [CAP_A_0402V-0.1UF,16V,10%,X7R,A]
    1  P3V3_STBY          A  @BASEBOARD_FAB2_LIB.BASEBOARD_FAB2(SCH_1):P3V3_STBY
    2  GND                B  @BASEBOARD_FAB2_LIB.BASEBOARD_FAB2(SCH_1):GND

CAP_A  I37  C3P49  [CAP_A_0402V-0.1UF,16V,10%,X7R,A]
    1  P0V7_GTL2104_VREF_1      A  @BASEBOARD_FAB2_LIB.BASEBOARD_FAB2(SCH_1):P0V7_GTL2104_VREF_1
    2  GND                B  @BASEBOARD_FAB2_LIB.BASEBOARD_FAB2(SCH_1):GND

CAP_0402  I84  C3P50  [CAP_0402-1.0UF,16V,10%,X6S,D97A]
    1  P3V3               A  @BASEBOARD_FAB2_LIB.BASEBOARD_FAB2(SCH_1):P3V3
    2  GND                B  @BASEBOARD_FAB2_LIB.BASEBOARD_FAB2(SCH_1):GND

CAP_A  I11  C3P51  [CAP_A_0402V-0.1UF,16V,10%,X7R,A]
    1  P3V3_STBY          A  @BASEBOARD_FAB2_LIB.BASEBOARD_FAB2(SCH_1):P3V3_STBY
    2  GND                B  @BASEBOARD_FAB2_LIB.BASEBOARD_FAB2(SCH_1):GND

CAP_A  I17  C3P52  [CAP_A_0402V-0.1UF,16V,10%,X7R,A]
    1  P3V3_STBY          A  @BASEBOARD_FAB2_LIB.BASEBOARD_FAB2(SCH_1):P3V3_STBY
    2  GND                B  @BASEBOARD_FAB2_LIB.BASEBOARD_FAB2(SCH_1):GND

CAP_A  I4   C3R1   [CAP_A_0402V-0.1UF,16V,10%,X7R,A]
    1  P3V3_STBY          A  @BASEBOARD_FAB2_LIB.BASEBOARD_FAB2(SCH_1):P3V3_STBY
    2  GND                B  @BASEBOARD_FAB2_LIB.BASEBOARD_FAB2(SCH_1):GND

CAP_A  I10  C3R2   [CAP_A_0402V-0.1UF,16V,10%,X7R,A]
    1  P3V3_STBY          A  @BASEBOARD_FAB2_LIB.BASEBOARD_FAB2(SCH_1):P3V3_STBY
    2  GND                B  @BASEBOARD_FAB2_LIB.BASEBOARD_FAB2(SCH_1):GND

CAP_A  I7   C3R3   [CAP_A_0402V-0.1UF,16V,10%,X7R,A]
    1  P3V3_STBY          A  @BASEBOARD_FAB2_LIB.BASEBOARD_FAB2(SCH_1):P3V3_STBY
    2  GND                B  @BASEBOARD_FAB2_LIB.BASEBOARD_FAB2(SCH_1):GND

CAPP  I31  C3R4   [CAPP_3018-470UF,2.5V,20%,ALUM,A]
    1  PVCCMCP_CPU0       A  @BASEBOARD_FAB2_LIB.BASEBOARD_FAB2(SCH_1):PVCCMCP_CPU0
    2  GND                B  @BASEBOARD_FAB2_LIB.BASEBOARD_FAB2(SCH_1):GND

CAP_A  I149  C3T1   [CAP_A_0603V-47UF,4V,20%,X5R,60A]
    1  P1V8_MCP_CPU0      A  @BASEBOARD_FAB2_LIB.BASEBOARD_FAB2(SCH_1):P1V8_MCP_CPU0
    2  GND                B  @BASEBOARD_FAB2_LIB.BASEBOARD_FAB2(SCH_1):GND

CAP_A  I150  C3T2   [CAP_A_0603V-47UF,4V,20%,X5R,60A]
    1  P1V8_MCP_CPU0      A  @BASEBOARD_FAB2_LIB.BASEBOARD_FAB2(SCH_1):P1V8_MCP_CPU0
    2  GND                B  @BASEBOARD_FAB2_LIB.BASEBOARD_FAB2(SCH_1):GND

CAPP  I113  C3T3   [CAPP_3018-68UF,16V,20%,TANT,72A]
    1  P12V_STBY          A  @BASEBOARD_FAB2_LIB.BASEBOARD_FAB2(SCH_1):P12V_STBY
    2  GND                B  @BASEBOARD_FAB2_LIB.BASEBOARD_FAB2(SCH_1):GND

CAP_A  I138  C3T4   [CAP_A_0402V-1.0UF,6.3V,10%,X6SA]
    1  P3V3_STBY          A  @BASEBOARD_FAB2_LIB.BASEBOARD_FAB2(SCH_1):P3V3_STBY
    2  GND                B  @BASEBOARD_FAB2_LIB.BASEBOARD_FAB2(SCH_1):GND

CAP_A  I136  C3T5   [CAP_A_0402V-0.01UF,25V,10%,X7RA]
    1  P3V3_STBY          A  @BASEBOARD_FAB2_LIB.BASEBOARD_FAB2(SCH_1):P3V3_STBY
    2  GND                B  @BASEBOARD_FAB2_LIB.BASEBOARD_FAB2(SCH_1):GND

CAPP  I98  C3T6   [CAPP_3018-68UF,16V,20%,TANT,72A]
    1  P12V_STBY          A  @BASEBOARD_FAB2_LIB.BASEBOARD_FAB2(SCH_1):P12V_STBY
    2  GND                B  @BASEBOARD_FAB2_LIB.BASEBOARD_FAB2(SCH_1):GND

CAP  I184  C3T7   [CAP_0805-47UF,4V,20%,X6S,C9533A]
    1  PVPP_ABC           A  @BASEBOARD_FAB2_LIB.BASEBOARD_FAB2(SCH_1):PVPP_ABC
    2  GND                B  @BASEBOARD_FAB2_LIB.BASEBOARD_FAB2(SCH_1):GND

CAP  I210  C3T8   [CAP_0805-10UF,16V,10%,X6S,C953A]
    1  VR_FET_SW_P12V_STBY_PVPP_ABC      A  @BASEBOARD_FAB2_LIB.BASEBOARD_FAB2(SCH_1):VR_FET_SW_P12V_STBY_PVPP_ABC
    2  GND                B  @BASEBOARD_FAB2_LIB.BASEBOARD_FAB2(SCH_1):GND

CAP  I186  C3T9   [CAP_0805-47UF,4V,20%,X6S,C9533A]
    1  PVPP_ABC           A  @BASEBOARD_FAB2_LIB.BASEBOARD_FAB2(SCH_1):PVPP_ABC
    2  GND                B  @BASEBOARD_FAB2_LIB.BASEBOARD_FAB2(SCH_1):GND

CAP_0402  I161  C3T10  [CAP_0402-1.0UF,16V,10%,X6S,D97A]
    1  VR_FET_SW_P12V_STBY_PVPP_ABC      A  @BASEBOARD_FAB2_LIB.BASEBOARD_FAB2(SCH_1):VR_FET_SW_P12V_STBY_PVPP_ABC
    2  GND                B  @BASEBOARD_FAB2_LIB.BASEBOARD_FAB2(SCH_1):GND

CAP  I202  C3T11  [CAP_0603-4.7UF,6.3V,10%,X6S,E1A]
    1  VR_VB_PVPP_ABC      A  @BASEBOARD_FAB2_LIB.BASEBOARD_FAB2(SCH_1):VR_VB_PVPP_ABC
    2  AGND_PVPP_ABC      B  @BASEBOARD_FAB2_LIB.BASEBOARD_FAB2(SCH_1):AGND_PVPP_ABC

CAP  I215  C3T12  [CAP_0805-10UF,16V,10%,X6S,C953A]
    1  VR_FET_SW_P12V_STBY_PVPP_ABC      A  @BASEBOARD_FAB2_LIB.BASEBOARD_FAB2(SCH_1):VR_FET_SW_P12V_STBY_PVPP_ABC
    2  GND                B  @BASEBOARD_FAB2_LIB.BASEBOARD_FAB2(SCH_1):GND

CAPP  I104  C3T13  [CAPP_3018-68UF,16V,20%,TANT,72A]
    1  P12V_STBY          A  @BASEBOARD_FAB2_LIB.BASEBOARD_FAB2(SCH_1):P12V_STBY
    2  GND                B  @BASEBOARD_FAB2_LIB.BASEBOARD_FAB2(SCH_1):GND

CAP  I211  C3T14  [CAP_0805-10UF,16V,10%,X6S,C953A]
    1  VR_FET_SW_P12V_STBY_PVPP_ABC      A  @BASEBOARD_FAB2_LIB.BASEBOARD_FAB2(SCH_1):VR_FET_SW_P12V_STBY_PVPP_ABC
    2  GND                B  @BASEBOARD_FAB2_LIB.BASEBOARD_FAB2(SCH_1):GND

CAPP  I106  C3T15  [CAPP_3018-68UF,16V,20%,TANT,72A]
    1  P12V_STBY          A  @BASEBOARD_FAB2_LIB.BASEBOARD_FAB2(SCH_1):P12V_STBY
    2  GND                B  @BASEBOARD_FAB2_LIB.BASEBOARD_FAB2(SCH_1):GND

CAPP  I76  C3U1   [CAPP_3018-470UF,2.5V,20%,ALUM,A]
    1  PVDDQ_ABC          A  @BASEBOARD_FAB2_LIB.BASEBOARD_FAB2(SCH_1):PVDDQ_ABC
    2  GND                B  @BASEBOARD_FAB2_LIB.BASEBOARD_FAB2(SCH_1):GND

CAP  I45  C3U2   [CAP_0805-10UF,16V,10%,X6S,C953A]
    1  VR_FET_SW_P12V_STBY_PVDDQ_ABC      A  @BASEBOARD_FAB2_LIB.BASEBOARD_FAB2(SCH_1):VR_FET_SW_P12V_STBY_PVDDQ_ABC
    2  GND                B  @BASEBOARD_FAB2_LIB.BASEBOARD_FAB2(SCH_1):GND

CAP  I46  C3U3   [CAP_0805-10UF,16V,10%,X6S,C953A]
    1  VR_FET_SW_P12V_STBY_PVDDQ_ABC      A  @BASEBOARD_FAB2_LIB.BASEBOARD_FAB2(SCH_1):VR_FET_SW_P12V_STBY_PVDDQ_ABC
    2  GND                B  @BASEBOARD_FAB2_LIB.BASEBOARD_FAB2(SCH_1):GND

CAP  I47  C3U4   [CAP_0805-10UF,16V,10%,X6S,C953A]
    1  VR_FET_SW_P12V_STBY_PVDDQ_ABC      A  @BASEBOARD_FAB2_LIB.BASEBOARD_FAB2(SCH_1):VR_FET_SW_P12V_STBY_PVDDQ_ABC
    2  GND                B  @BASEBOARD_FAB2_LIB.BASEBOARD_FAB2(SCH_1):GND

CAPP  I77  C3U5   [CAPP_3018-470UF,2.5V,20%,ALUM,A]
    1  PVDDQ_ABC          A  @BASEBOARD_FAB2_LIB.BASEBOARD_FAB2(SCH_1):PVDDQ_ABC
    2  GND                B  @BASEBOARD_FAB2_LIB.BASEBOARD_FAB2(SCH_1):GND

CAP  I84  C3U6   [CAP_0805-10UF,16V,10%,X6S,C953A]
    1  VR_FET_SW_P12V_STBY_PVDDQ_ABC      A  @BASEBOARD_FAB2_LIB.BASEBOARD_FAB2(SCH_1):VR_FET_SW_P12V_STBY_PVDDQ_ABC
    2  GND                B  @BASEBOARD_FAB2_LIB.BASEBOARD_FAB2(SCH_1):GND

CAP  I81  C3U7   [CAP_0805-10UF,16V,10%,X6S,C953A]
    1  VR_FET_SW_P12V_STBY_PVDDQ_ABC      A  @BASEBOARD_FAB2_LIB.BASEBOARD_FAB2(SCH_1):VR_FET_SW_P12V_STBY_PVDDQ_ABC
    2  GND                B  @BASEBOARD_FAB2_LIB.BASEBOARD_FAB2(SCH_1):GND

CAPP  I78  C3U8   [CAPP_3018-470UF,2.5V,20%,ALUM,A]
    1  PVDDQ_ABC          A  @BASEBOARD_FAB2_LIB.BASEBOARD_FAB2(SCH_1):PVDDQ_ABC
    2  GND                B  @BASEBOARD_FAB2_LIB.BASEBOARD_FAB2(SCH_1):GND

CAP  I80  C3U9   [CAP_0805-10UF,16V,10%,X6S,C953A]
    1  VR_FET_SW_P12V_STBY_PVDDQ_ABC      A  @BASEBOARD_FAB2_LIB.BASEBOARD_FAB2(SCH_1):VR_FET_SW_P12V_STBY_PVDDQ_ABC
    2  GND                B  @BASEBOARD_FAB2_LIB.BASEBOARD_FAB2(SCH_1):GND

CAP_A  I360  C3U10  [CAP_A_0402V-0.1UF,16V,10%,X7R,A]
    1  VR_PVDDQ_ABC_AIINSEN      A  @BASEBOARD_FAB2_LIB.BASEBOARD_FAB2(SCH_1):VR_PVDDQ_ABC_AIINSEN
    2  GND                B  @BASEBOARD_FAB2_LIB.BASEBOARD_FAB2(SCH_1):GND

CAP  I16  C4A1   [CAP_0805LF-22UF,4V,20%,X6S,C95A]
    1  PVTT_DEF           A  @BASEBOARD_FAB2_LIB.BASEBOARD_FAB2(SCH_1):PVTT_DEF
    2  GND                B  @BASEBOARD_FAB2_LIB.BASEBOARD_FAB2(SCH_1):GND

CAP  I40  C4A2   [CAP_0402LF-1000PF,50V,10%,EMPTA]
    2  GND                B  @BASEBOARD_FAB2_LIB.BASEBOARD_FAB2(SCH_1):GND
    1  FM_PVTT_DEF_EN_R      A  @BASEBOARD_FAB2_LIB.BASEBOARD_FAB2(SCH_1):FM_PVTT_DEF_EN_R

CAP  I16  C4A3   [CAP_0402LF-1000PF,50V,10%,X7R,A]
    1  PWRGD_PVTT_KLM_CPU1_R      A  @BASEBOARD_FAB2_LIB.BASEBOARD_FAB2(SCH_1):PWRGD_PVTT_KLM_CPU1_R
    2  GND                B  @BASEBOARD_FAB2_LIB.BASEBOARD_FAB2(SCH_1):GND

CAP  I62  C4A4   [CAP_0805-10UF,16V,10%,X7R,G106A]
    1  P12V_NVDIMM_DEF      A  @BASEBOARD_FAB2_LIB.BASEBOARD_FAB2(SCH_1):P12V_NVDIMM_DEF
    2  GND                B  @BASEBOARD_FAB2_LIB.BASEBOARD_FAB2(SCH_1):GND

CAP_A  I179  C4A5   [CAP_A_0402V-0.01UF,25V,10%,X7RA]
    1  M_F_VREF           A  @BASEBOARD_FAB2_LIB.BASEBOARD_FAB2(SCH_1):M_F_VREF
    2  GND                B  @BASEBOARD_FAB2_LIB.BASEBOARD_FAB2(SCH_1):GND

CAP  I39  C4A6   [CAP_0402LF-1000PF,50V,10%,EMPTA]
    2  GND                B  @BASEBOARD_FAB2_LIB.BASEBOARD_FAB2(SCH_1):GND
    1  FM_PVTT_KLM_EN_R      A  @BASEBOARD_FAB2_LIB.BASEBOARD_FAB2(SCH_1):FM_PVTT_KLM_EN_R

CAP  I46  C4A7   [CAP_0603-4.7UF,6.3V,10%,X6S,E1A]
    1  VSENSE_PVDDQ_KLM_VTT      A  @BASEBOARD_FAB2_LIB.BASEBOARD_FAB2(SCH_1):VSENSE_PVDDQ_KLM_VTT
    2  GND                B  @BASEBOARD_FAB2_LIB.BASEBOARD_FAB2(SCH_1):GND

CAP_0402  I28  C4A8   [CAP_0402-1.0UF,16V,10%,X6S,D97A]
    1  VR_PVTT_KLM_BIAS      A  @BASEBOARD_FAB2_LIB.BASEBOARD_FAB2(SCH_1):VR_PVTT_KLM_BIAS
    2  GND                B  @BASEBOARD_FAB2_LIB.BASEBOARD_FAB2(SCH_1):GND

CAP_0402  I21  C4A9   [CAP_0402-1.0UF,16V,10%,X6S,D97A]
    1  VR_PVTT_DEF_VREF      A  @BASEBOARD_FAB2_LIB.BASEBOARD_FAB2(SCH_1):VR_PVTT_DEF_VREF
    2  GND                B  @BASEBOARD_FAB2_LIB.BASEBOARD_FAB2(SCH_1):GND

CAP_0402  I28  C4A10  [CAP_0402-1.0UF,16V,10%,X6S,D97A]
    1  VR_PVTT_DEF_BIAS      A  @BASEBOARD_FAB2_LIB.BASEBOARD_FAB2(SCH_1):VR_PVTT_DEF_BIAS
    2  GND                B  @BASEBOARD_FAB2_LIB.BASEBOARD_FAB2(SCH_1):GND

CAP  I46  C4A11  [CAP_0603-4.7UF,6.3V,10%,X6S,E1A]
    1  VSENSE_PVDDQ_DEF_VTT      A  @BASEBOARD_FAB2_LIB.BASEBOARD_FAB2(SCH_1):VSENSE_PVDDQ_DEF_VTT
    2  GND                B  @BASEBOARD_FAB2_LIB.BASEBOARD_FAB2(SCH_1):GND

CAP  I12  C4A12  [CAP_0402LF-1000PF,50V,10%,X7R,A]
    1  PWRGD_PVTT_DEF_CPU0_R      A  @BASEBOARD_FAB2_LIB.BASEBOARD_FAB2(SCH_1):PWRGD_PVTT_DEF_CPU0_R
    2  GND                B  @BASEBOARD_FAB2_LIB.BASEBOARD_FAB2(SCH_1):GND

CAP  I18  C4A13  [CAP_0805LF-22UF,4V,20%,X6S,C95A]
    1  PVTT_KLM           A  @BASEBOARD_FAB2_LIB.BASEBOARD_FAB2(SCH_1):PVTT_KLM
    2  GND                B  @BASEBOARD_FAB2_LIB.BASEBOARD_FAB2(SCH_1):GND

CAP_0402  I21  C4A14  [CAP_0402-1.0UF,16V,10%,X6S,D97A]
    1  VR_PVTT_KLM_VREF      A  @BASEBOARD_FAB2_LIB.BASEBOARD_FAB2(SCH_1):VR_PVTT_KLM_VREF
    2  GND                B  @BASEBOARD_FAB2_LIB.BASEBOARD_FAB2(SCH_1):GND

CAP  I25  C4A15  [CAP_0603LF-10UF,4V,20%,X6S,E15A]
    1  PVDDQ_KLM          A  @BASEBOARD_FAB2_LIB.BASEBOARD_FAB2(SCH_1):PVDDQ_KLM
    2  GND                B  @BASEBOARD_FAB2_LIB.BASEBOARD_FAB2(SCH_1):GND

CAP  I163  C4A16  [CAP_0402LF-3300PF,50V,10%,EMPTA]
    2  VR_PVPP_KLM_SNUB      B  @BASEBOARD_FAB2_LIB.BASEBOARD_FAB2(SCH_1):VR_PVPP_KLM_SNUB
    1  VR_PVPP_KLM_PHASE      A  @BASEBOARD_FAB2_LIB.BASEBOARD_FAB2(SCH_1):VR_PVPP_KLM_PHASE

CAP  I67  C4A17  [CAP_0805-10UF,16V,10%,X7R,G106A]
    1  P12V_NVDIMM_DEF      A  @BASEBOARD_FAB2_LIB.BASEBOARD_FAB2(SCH_1):P12V_NVDIMM_DEF
    2  GND                B  @BASEBOARD_FAB2_LIB.BASEBOARD_FAB2(SCH_1):GND

CAP_A  I3   C4A18  [CAP_A_0402V-0.01UF,25V,10%,X7RA]
    1  M_E_VREF           A  @BASEBOARD_FAB2_LIB.BASEBOARD_FAB2(SCH_1):M_E_VREF
    2  GND                B  @BASEBOARD_FAB2_LIB.BASEBOARD_FAB2(SCH_1):GND

CAP  I205  C4A19  [CAP_0805-10UF,16V,10%,X6S,C953A]
    1  VR_FET_SW_P12V_STBY_PVPP_KLM      A  @BASEBOARD_FAB2_LIB.BASEBOARD_FAB2(SCH_1):VR_FET_SW_P12V_STBY_PVPP_KLM
    2  GND                B  @BASEBOARD_FAB2_LIB.BASEBOARD_FAB2(SCH_1):GND

CAP_A  I199  C4A20  [CAP_A_0402V-0.1UF,16V,10%,X7R,A]
    1  VR_FET_SW_P12V_STBY_PVPP_KLM      A  @BASEBOARD_FAB2_LIB.BASEBOARD_FAB2(SCH_1):VR_FET_SW_P12V_STBY_PVPP_KLM
    2  GND                B  @BASEBOARD_FAB2_LIB.BASEBOARD_FAB2(SCH_1):GND

CAP  I130  C4B1   [CAP_1210-47UF,16V,20%,X6S,D384A]
    1  VR_FET_SW_P12V_STBY_PVPP_KLM      A  @BASEBOARD_FAB2_LIB.BASEBOARD_FAB2(SCH_1):VR_FET_SW_P12V_STBY_PVPP_KLM
    2  GND                B  @BASEBOARD_FAB2_LIB.BASEBOARD_FAB2(SCH_1):GND

CAP  I180  C4B2   [CAP_0805-47UF,4V,20%,X6S,C9533A]
    1  PVPP_KLM           A  @BASEBOARD_FAB2_LIB.BASEBOARD_FAB2(SCH_1):PVPP_KLM
    2  GND                B  @BASEBOARD_FAB2_LIB.BASEBOARD_FAB2(SCH_1):GND

CAP  I177  C4B3   [CAP_0805-47UF,4V,20%,X6S,C9533A]
    1  PVPP_KLM           A  @BASEBOARD_FAB2_LIB.BASEBOARD_FAB2(SCH_1):PVPP_KLM
    2  GND                B  @BASEBOARD_FAB2_LIB.BASEBOARD_FAB2(SCH_1):GND

CAP  I212  C4B4   [CAP_0402LF-100.0PF,50V,5%,COG,A]
    1  VR_FB_PVPP_KLM      A  @BASEBOARD_FAB2_LIB.BASEBOARD_FAB2(SCH_1):VR_FB_PVPP_KLM
    2  VR_COMP_PVPP_KLM_3      B  @BASEBOARD_FAB2_LIB.BASEBOARD_FAB2(SCH_1):VR_COMP_PVPP_KLM_3

CAP  I129  C4B5   [CAP_0402LF-1000PF,50V,10%,EMPTA]
    1  FM_PVPP_CPU1_EN      A  @BASEBOARD_FAB2_LIB.BASEBOARD_FAB2(SCH_1):FM_PVPP_CPU1_EN
    2  AGND_PVPP_KLM      B  @BASEBOARD_FAB2_LIB.BASEBOARD_FAB2(SCH_1):AGND_PVPP_KLM

CAP_0402  I146  C4B6   [CAP_0402-0.027UF,16V,10%,X7R,AA]
    1  VR_PVPP_KLM_SS      A  @BASEBOARD_FAB2_LIB.BASEBOARD_FAB2(SCH_1):VR_PVPP_KLM_SS
    2  AGND_PVPP_KLM      B  @BASEBOARD_FAB2_LIB.BASEBOARD_FAB2(SCH_1):AGND_PVPP_KLM

CAP  I218  C4B7   [CAP_0402LF-2200PF,50V,10%,X7R,A]
    2  VR_FB_PVPP_KLM      B  @BASEBOARD_FAB2_LIB.BASEBOARD_FAB2(SCH_1):VR_FB_PVPP_KLM
    1  VR_COMP_PVPP_KLM      A  @BASEBOARD_FAB2_LIB.BASEBOARD_FAB2(SCH_1):VR_COMP_PVPP_KLM

CAP  I139  C4B8   [CAP_0402LF-1000PF,50V,10%,X7R,A]
    1  PWRGD_PVPP_KLM_R      A  @BASEBOARD_FAB2_LIB.BASEBOARD_FAB2(SCH_1):PWRGD_PVPP_KLM_R
    2  GND                B  @BASEBOARD_FAB2_LIB.BASEBOARD_FAB2(SCH_1):GND

CAP  I211  C4B9   [CAP_0402LF-2200PF,50V,10%,X7R,A]
    1  VR_COMP_RC_PVPP_KLM      A  @BASEBOARD_FAB2_LIB.BASEBOARD_FAB2(SCH_1):VR_COMP_RC_PVPP_KLM
    2  VR_COMP_PVPP_KLM_3      B  @BASEBOARD_FAB2_LIB.BASEBOARD_FAB2(SCH_1):VR_COMP_PVPP_KLM_3

CAP  I59  C4B11  [CAP_0805-10UF,16V,10%,X7R,G106A]
    1  P12V_NVDIMM_DEF      A  @BASEBOARD_FAB2_LIB.BASEBOARD_FAB2(SCH_1):P12V_NVDIMM_DEF
    2  GND                B  @BASEBOARD_FAB2_LIB.BASEBOARD_FAB2(SCH_1):GND

CAP_A  I179  C4B12  [CAP_A_0402V-0.01UF,25V,10%,X7RA]
    1  M_D_VREF           A  @BASEBOARD_FAB2_LIB.BASEBOARD_FAB2(SCH_1):M_D_VREF
    2  GND                B  @BASEBOARD_FAB2_LIB.BASEBOARD_FAB2(SCH_1):GND

CAPP  I83  C4B13  [CAPP_4040LF-470UF,16V,20%,ALUMA]
    1  P12V_STBY          A  @BASEBOARD_FAB2_LIB.BASEBOARD_FAB2(SCH_1):P12V_STBY
    2  GND                B  @BASEBOARD_FAB2_LIB.BASEBOARD_FAB2(SCH_1):GND

CAPP  I97  C4B14  [CAPP_3018-68UF,16V,20%,TANT,72A]
    1  P12V_STBY          A  @BASEBOARD_FAB2_LIB.BASEBOARD_FAB2(SCH_1):P12V_STBY
    2  GND                B  @BASEBOARD_FAB2_LIB.BASEBOARD_FAB2(SCH_1):GND

CAP  I182  C4B15  [CAP_0603LF-0.1UF,25V,10%,X7R,6A]
    1  VR_PVPP_KLM_PHASE      A  @BASEBOARD_FAB2_LIB.BASEBOARD_FAB2(SCH_1):VR_PVPP_KLM_PHASE
    2  VR_PVPP_KLM_BOOT_R      B  @BASEBOARD_FAB2_LIB.BASEBOARD_FAB2(SCH_1):VR_PVPP_KLM_BOOT_R

CAPP  I29  C4C1   [CAPP_3018-470UF,2.5V,20%,ALUM,A]
    1  PVCCIOMCP_CPU1      A  @BASEBOARD_FAB2_LIB.BASEBOARD_FAB2(SCH_1):PVCCIOMCP_CPU1
    2  GND                B  @BASEBOARD_FAB2_LIB.BASEBOARD_FAB2(SCH_1):GND

CAP_A  I51  C4C2   [CAP_A_0402V-0.1UF,16V,10%,EMPTA]
    1  VR_FET_SW_P12V_PVCCIN_CPU0_R      A  @BASEBOARD_FAB2_LIB.BASEBOARD_FAB2(SCH_1):VR_FET_SW_P12V_PVCCIN_CPU0_R
    2  GND                B  @BASEBOARD_FAB2_LIB.BASEBOARD_FAB2(SCH_1):GND

CAP_A  I75  C4C3   [CAP_A_0402V-1.0UF,6.3V,10%,X6SA]
    1  P3V3_STBY          A  @BASEBOARD_FAB2_LIB.BASEBOARD_FAB2(SCH_1):P3V3_STBY
    2  GND                B  @BASEBOARD_FAB2_LIB.BASEBOARD_FAB2(SCH_1):GND

CAP_A  I18  C4C4   [CAP_A_0402V-1.0UF,6.3V,10%,X6SA]
    1  P5V_STBY           A  @BASEBOARD_FAB2_LIB.BASEBOARD_FAB2(SCH_1):P5V_STBY
    2  GND                B  @BASEBOARD_FAB2_LIB.BASEBOARD_FAB2(SCH_1):GND

CAP_0402  I16  C4C5   [CAP_0402-0.22UF,16V,10%,X7R,A3A]
    1  P5V_STBY           A  @BASEBOARD_FAB2_LIB.BASEBOARD_FAB2(SCH_1):P5V_STBY
    2  GND                B  @BASEBOARD_FAB2_LIB.BASEBOARD_FAB2(SCH_1):GND

CAP_0402  I20  C4C6   [CAP_0402-1.0UF,16V,10%,X6S,D97A]
    1  VR_PVSA_CPU0_VCIN      A  @BASEBOARD_FAB2_LIB.BASEBOARD_FAB2(SCH_1):VR_PVSA_CPU0_VCIN
    2  GND                B  @BASEBOARD_FAB2_LIB.BASEBOARD_FAB2(SCH_1):GND

CAP_0402  I25  C4C8   [CAP_0402-0.220UF,16V,10%,X7R,AA]
    2  VR_PVSA_CPU0_PHASE      B  @BASEBOARD_FAB2_LIB.BASEBOARD_FAB2(SCH_1):VR_PVSA_CPU0_PHASE
    1  VR_PVSA_CPU0_BOOT      A  @BASEBOARD_FAB2_LIB.BASEBOARD_FAB2(SCH_1):VR_PVSA_CPU0_BOOT

CAP_0402  I32  C4C9   [CAP_0402-1.0UF,16V,10%,X6S,D97A]
    1  VR_FET_SW_P12V_STBY_PVCCIN_CPU0      A  @BASEBOARD_FAB2_LIB.BASEBOARD_FAB2(SCH_1):VR_FET_SW_P12V_STBY_PVCCIN_CPU0
    2  GND                B  @BASEBOARD_FAB2_LIB.BASEBOARD_FAB2(SCH_1):GND

CAP_A  I31  C4C10  [CAP_A_0402V-0.1UF,16V,10%,X7R,A]
    1  VR_FET_SW_P12V_STBY_PVCCIN_CPU0      A  @BASEBOARD_FAB2_LIB.BASEBOARD_FAB2(SCH_1):VR_FET_SW_P12V_STBY_PVCCIN_CPU0
    2  GND                B  @BASEBOARD_FAB2_LIB.BASEBOARD_FAB2(SCH_1):GND

CAP_A  I43  C4C11  [CAP_A_0603V-22.0UF,4V,20%,X6S,A]
    1  PVSA_CPU0          A  @BASEBOARD_FAB2_LIB.BASEBOARD_FAB2(SCH_1):PVSA_CPU0
    2  GND                B  @BASEBOARD_FAB2_LIB.BASEBOARD_FAB2(SCH_1):GND

CAPP  I67  C4C12  [CAPP_2626-270UF,16V,20%,OSCON,A]
    1  VR_FET_SW_P12V_STBY_PVCCIN_CPU0      A  @BASEBOARD_FAB2_LIB.BASEBOARD_FAB2(SCH_1):VR_FET_SW_P12V_STBY_PVCCIN_CPU0
    2  GND                B  @BASEBOARD_FAB2_LIB.BASEBOARD_FAB2(SCH_1):GND

CAP_A  I19  C4C14  [CAP_A_0402V-1.0UF,6.3V,10%,X6SA]
    1  P5V_STBY           A  @BASEBOARD_FAB2_LIB.BASEBOARD_FAB2(SCH_1):P5V_STBY
    2  GND                B  @BASEBOARD_FAB2_LIB.BASEBOARD_FAB2(SCH_1):GND

CAP_0402  I22  C4C17  [CAP_0402-0.220UF,16V,10%,X7R,AA]
    2  VR_PVCCIN_CPU0_PH5_PHASE      B  @BASEBOARD_FAB2_LIB.BASEBOARD_FAB2(SCH_1):VR_PVCCIN_CPU0_PH5_PHASE
    1  VR_PVCCIN_CPU0_PH5_BOOT      A  @BASEBOARD_FAB2_LIB.BASEBOARD_FAB2(SCH_1):VR_PVCCIN_CPU0_PH5_BOOT

CAP_0402  I36  C4C18  [CAP_0402-1.0UF,16V,10%,X6S,D97A]
    1  VR_FET_SW_P12V_STBY_PVCCIN_CPU0      A  @BASEBOARD_FAB2_LIB.BASEBOARD_FAB2(SCH_1):VR_FET_SW_P12V_STBY_PVCCIN_CPU0
    2  GND                B  @BASEBOARD_FAB2_LIB.BASEBOARD_FAB2(SCH_1):GND

CAP_A  I35  C4C19  [CAP_A_0402V-0.1UF,16V,10%,X7R,A]
    1  VR_FET_SW_P12V_STBY_PVCCIN_CPU0      A  @BASEBOARD_FAB2_LIB.BASEBOARD_FAB2(SCH_1):VR_FET_SW_P12V_STBY_PVCCIN_CPU0
    2  GND                B  @BASEBOARD_FAB2_LIB.BASEBOARD_FAB2(SCH_1):GND

CAPP  I48  C4D2   [CAPP_2626-270UF,16V,20%,OSCON,A]
    1  VR_FET_SW_P12V_STBY_PVCCIN_CPU0      A  @BASEBOARD_FAB2_LIB.BASEBOARD_FAB2(SCH_1):VR_FET_SW_P12V_STBY_PVCCIN_CPU0
    2  GND                B  @BASEBOARD_FAB2_LIB.BASEBOARD_FAB2(SCH_1):GND

CAP_A  I69  C4D4   [CAP_A_0603V-22.0UF,4V,20%,X6S,A]
    1  PVCCIN_CPU0        A  @BASEBOARD_FAB2_LIB.BASEBOARD_FAB2(SCH_1):PVCCIN_CPU0
    2  GND                B  @BASEBOARD_FAB2_LIB.BASEBOARD_FAB2(SCH_1):GND

CAP_0402  I48  C4D5   [CAP_0402-0.22UF,16V,10%,X7R,A3A]
    1  P5V_STBY           A  @BASEBOARD_FAB2_LIB.BASEBOARD_FAB2(SCH_1):P5V_STBY
    2  GND                B  @BASEBOARD_FAB2_LIB.BASEBOARD_FAB2(SCH_1):GND

CAP_A  I49  C4D6   [CAP_A_0402V-1.0UF,6.3V,10%,X6SA]
    1  P5V_STBY           A  @BASEBOARD_FAB2_LIB.BASEBOARD_FAB2(SCH_1):P5V_STBY
    2  GND                B  @BASEBOARD_FAB2_LIB.BASEBOARD_FAB2(SCH_1):GND

CAP_0402  I51  C4D7   [CAP_0402-1.0UF,16V,10%,X6S,D97A]
    1  VR_PVCCIN_CPU0_PH4_VCIN      A  @BASEBOARD_FAB2_LIB.BASEBOARD_FAB2(SCH_1):VR_PVCCIN_CPU0_PH4_VCIN
    2  GND                B  @BASEBOARD_FAB2_LIB.BASEBOARD_FAB2(SCH_1):GND

CAP_0402  I3   C4D9   [CAP_0402-0.220UF,16V,10%,X7R,AA]
    2  VR_PVCCIN_CPU0_PH4_PHASE      B  @BASEBOARD_FAB2_LIB.BASEBOARD_FAB2(SCH_1):VR_PVCCIN_CPU0_PH4_PHASE
    1  VR_PVCCIN_CPU0_PH4_BOOT      A  @BASEBOARD_FAB2_LIB.BASEBOARD_FAB2(SCH_1):VR_PVCCIN_CPU0_PH4_BOOT

CAP_0402  I53  C4D10  [CAP_0402-1.0UF,16V,10%,X6S,D97A]
    1  VR_FET_SW_P12V_STBY_PVCCIN_CPU0      A  @BASEBOARD_FAB2_LIB.BASEBOARD_FAB2(SCH_1):VR_FET_SW_P12V_STBY_PVCCIN_CPU0
    2  GND                B  @BASEBOARD_FAB2_LIB.BASEBOARD_FAB2(SCH_1):GND

CAP_A  I52  C4D11  [CAP_A_0402V-0.1UF,16V,10%,X7R,A]
    1  VR_FET_SW_P12V_STBY_PVCCIN_CPU0      A  @BASEBOARD_FAB2_LIB.BASEBOARD_FAB2(SCH_1):VR_FET_SW_P12V_STBY_PVCCIN_CPU0
    2  GND                B  @BASEBOARD_FAB2_LIB.BASEBOARD_FAB2(SCH_1):GND

CAP_A  I9   C4D12  [CAP_A_0603V-22.0UF,4V,20%,X6S,A]
    1  PVCCIN_CPU0        A  @BASEBOARD_FAB2_LIB.BASEBOARD_FAB2(SCH_1):PVCCIN_CPU0
    2  GND                B  @BASEBOARD_FAB2_LIB.BASEBOARD_FAB2(SCH_1):GND

CAP_0402  I40  C4D13  [CAP_0402-0.22UF,16V,10%,X7R,A3A]
    1  P5V_STBY           A  @BASEBOARD_FAB2_LIB.BASEBOARD_FAB2(SCH_1):P5V_STBY
    2  GND                B  @BASEBOARD_FAB2_LIB.BASEBOARD_FAB2(SCH_1):GND

CAP_A  I41  C4D14  [CAP_A_0402V-1.0UF,6.3V,10%,X6SA]
    1  P5V_STBY           A  @BASEBOARD_FAB2_LIB.BASEBOARD_FAB2(SCH_1):P5V_STBY
    2  GND                B  @BASEBOARD_FAB2_LIB.BASEBOARD_FAB2(SCH_1):GND

CAP_A  I37  C4D15  [CAP_A_0402V-1.0UF,6.3V,10%,X6SA]
    1  VR_PVCCIN_CPU0_VDD      A  @BASEBOARD_FAB2_LIB.BASEBOARD_FAB2(SCH_1):VR_PVCCIN_CPU0_VDD
    2  GND                B  @BASEBOARD_FAB2_LIB.BASEBOARD_FAB2(SCH_1):GND

CAP_0402  I45  C4D16  [CAP_0402-1.0UF,16V,10%,X6S,D97A]
    1  VR_PVCCIN_CPU0_PH3_VCIN      A  @BASEBOARD_FAB2_LIB.BASEBOARD_FAB2(SCH_1):VR_PVCCIN_CPU0_PH3_VCIN
    2  GND                B  @BASEBOARD_FAB2_LIB.BASEBOARD_FAB2(SCH_1):GND

CAP  I66  C4D17  [CAP_0402LF-220PF,50V,10%,X7R,AA]
    2  GND                B  @BASEBOARD_FAB2_LIB.BASEBOARD_FAB2(SCH_1):GND
    1  A_TSENSE_PVCCIN_CPU0      A  @BASEBOARD_FAB2_LIB.BASEBOARD_FAB2(SCH_1):A_TSENSE_PVCCIN_CPU0

CAP  I68  C4D18  [CAP_0402LF-220PF,50V,10%,X7R,AA]
    2  GND                B  @BASEBOARD_FAB2_LIB.BASEBOARD_FAB2(SCH_1):GND
    1  A_TSENSE_PVSA_CPU0      A  @BASEBOARD_FAB2_LIB.BASEBOARD_FAB2(SCH_1):A_TSENSE_PVSA_CPU0

CAP_A  I39  C4D19  [CAP_A_0402V-0.1UF,16V,10%,X7R,A]
    1  VR_PVCCIN_CPU0_VDD      A  @BASEBOARD_FAB2_LIB.BASEBOARD_FAB2(SCH_1):VR_PVCCIN_CPU0_VDD
    2  GND                B  @BASEBOARD_FAB2_LIB.BASEBOARD_FAB2(SCH_1):GND

CAP  I60  C4D20  [CAP_0402LF-1000PF,50V,10%,X7R,A]
    1  VR_PVCCIN_CPU0_AVINSEN      A  @BASEBOARD_FAB2_LIB.BASEBOARD_FAB2(SCH_1):VR_PVCCIN_CPU0_AVINSEN
    2  GND                B  @BASEBOARD_FAB2_LIB.BASEBOARD_FAB2(SCH_1):GND

CAP_A  I28  C4D22  [CAP_A_0402V-0.1UF,16V,10%,X7R,A]
    1  P3V3_DB1200_R      A  @BASEBOARD_FAB2_LIB.BASEBOARD_FAB2(SCH_1):P3V3_DB1200_R
    2  GND                B  @BASEBOARD_FAB2_LIB.BASEBOARD_FAB2(SCH_1):GND

CAP_A  I19  C4D23  [CAP_A_0402V-1.0UF,6.3V,10%,X6SA]
    1  P3V3_DB1200_A      A  @BASEBOARD_FAB2_LIB.BASEBOARD_FAB2(SCH_1):P3V3_DB1200_A
    2  GND                B  @BASEBOARD_FAB2_LIB.BASEBOARD_FAB2(SCH_1):GND

CAP_A  I18  C4D24  [CAP_A_0402V-0.1UF,16V,10%,X7R,A]
    1  P3V3_DB1200_A      A  @BASEBOARD_FAB2_LIB.BASEBOARD_FAB2(SCH_1):P3V3_DB1200_A
    2  GND                B  @BASEBOARD_FAB2_LIB.BASEBOARD_FAB2(SCH_1):GND

CAP_A  I30  C4D25  [CAP_A_0402V-1.0UF,6.3V,10%,X6SA]
    1  VR_PVCCIN_CPU0_VD12      A  @BASEBOARD_FAB2_LIB.BASEBOARD_FAB2(SCH_1):VR_PVCCIN_CPU0_VD12
    2  GND                B  @BASEBOARD_FAB2_LIB.BASEBOARD_FAB2(SCH_1):GND

CAP_A  I32  C4D26  [CAP_A_0402V-0.1UF,16V,10%,X7R,A]
    1  VR_PVCCIN_CPU0_VD12      A  @BASEBOARD_FAB2_LIB.BASEBOARD_FAB2(SCH_1):VR_PVCCIN_CPU0_VD12
    2  GND                B  @BASEBOARD_FAB2_LIB.BASEBOARD_FAB2(SCH_1):GND

CAP_A  I30  C4D27  [CAP_A_0402V-1.0UF,6.3V,10%,X6SA]
    1  P3V3_DB1200_R      A  @BASEBOARD_FAB2_LIB.BASEBOARD_FAB2(SCH_1):P3V3_DB1200_R
    2  GND                B  @BASEBOARD_FAB2_LIB.BASEBOARD_FAB2(SCH_1):GND

CAP_0402  I42  C4D28  [CAP_0402-0.220UF,16V,10%,X7R,AA]
    2  VR_PVCCIN_CPU0_PH3_PHASE      B  @BASEBOARD_FAB2_LIB.BASEBOARD_FAB2(SCH_1):VR_PVCCIN_CPU0_PH3_PHASE
    1  VR_PVCCIN_CPU0_PH3_BOOT      A  @BASEBOARD_FAB2_LIB.BASEBOARD_FAB2(SCH_1):VR_PVCCIN_CPU0_PH3_BOOT

CAP  I64  C4D29  [CAP_0402LF-220PF,50V,10%,X7R,AA]
    2  VSENSE_PVSA_CPU0_N      B  @BASEBOARD_FAB2_LIB.BASEBOARD_FAB2(SCH_1):VSENSE_PVSA_CPU0_N
    1  VSENSE_PVSA_CPU0_BVSP      A  @BASEBOARD_FAB2_LIB.BASEBOARD_FAB2(SCH_1):VSENSE_PVSA_CPU0_BVSP

CAP_0402  I47  C4D30  [CAP_0402-1.0UF,16V,10%,X6S,D97A]
    1  VR_FET_SW_P12V_STBY_PVCCIN_CPU0      A  @BASEBOARD_FAB2_LIB.BASEBOARD_FAB2(SCH_1):VR_FET_SW_P12V_STBY_PVCCIN_CPU0
    2  GND                B  @BASEBOARD_FAB2_LIB.BASEBOARD_FAB2(SCH_1):GND

CAP_A  I9   C4D31  [CAP_A_0402V-1.0UF,6.3V,10%,X6SA]
    1  VR_PVCCIO_CPU1_VD12      A  @BASEBOARD_FAB2_LIB.BASEBOARD_FAB2(SCH_1):VR_PVCCIO_CPU1_VD12
    2  GND                B  @BASEBOARD_FAB2_LIB.BASEBOARD_FAB2(SCH_1):GND

CAP_A  I11  C4D32  [CAP_A_0402V-0.1UF,16V,10%,X7R,A]
    1  VR_PVCCIO_CPU1_VD12      A  @BASEBOARD_FAB2_LIB.BASEBOARD_FAB2(SCH_1):VR_PVCCIO_CPU1_VD12
    2  GND                B  @BASEBOARD_FAB2_LIB.BASEBOARD_FAB2(SCH_1):GND

CAP  I73  C4D33  [CAP_0402LF-1000PF,50V,10%,X7R,A]
    1  PWRGD_PVCCIO_CPU1_R      A  @BASEBOARD_FAB2_LIB.BASEBOARD_FAB2(SCH_1):PWRGD_PVCCIO_CPU1_R
    2  GND                B  @BASEBOARD_FAB2_LIB.BASEBOARD_FAB2(SCH_1):GND

CAP_A  I68  C4D34  [CAP_A_0603V-22.0UF,4V,20%,X6S,A]
    1  PVCCIN_CPU0        A  @BASEBOARD_FAB2_LIB.BASEBOARD_FAB2(SCH_1):PVCCIN_CPU0
    2  GND                B  @BASEBOARD_FAB2_LIB.BASEBOARD_FAB2(SCH_1):GND

CAP_A  I46  C4D35  [CAP_A_0402V-0.1UF,16V,10%,X7R,A]
    1  VR_FET_SW_P12V_STBY_PVCCIN_CPU0      A  @BASEBOARD_FAB2_LIB.BASEBOARD_FAB2(SCH_1):VR_FET_SW_P12V_STBY_PVCCIN_CPU0
    2  GND                B  @BASEBOARD_FAB2_LIB.BASEBOARD_FAB2(SCH_1):GND

CAP_A  I17  C4D36  [CAP_A_0402V-1.0UF,6.3V,10%,X6SA]
    1  VR_PVCCIO_CPU1_VDD      A  @BASEBOARD_FAB2_LIB.BASEBOARD_FAB2(SCH_1):VR_PVCCIO_CPU1_VDD
    2  GND                B  @BASEBOARD_FAB2_LIB.BASEBOARD_FAB2(SCH_1):GND

CAP_A  I35  C4D38  [CAP_A_0402V-0.1UF,16V,10%,X7R,A]
    1  VR_PVCCIO_CPU1_VDD      A  @BASEBOARD_FAB2_LIB.BASEBOARD_FAB2(SCH_1):VR_PVCCIO_CPU1_VDD
    2  GND                B  @BASEBOARD_FAB2_LIB.BASEBOARD_FAB2(SCH_1):GND

CAP  I33  C4D40  [CAP_0402LF-1000PF,50V,10%,X7R,A]
    1  VR_PVCCIO_CPU1_VINSEN      A  @BASEBOARD_FAB2_LIB.BASEBOARD_FAB2(SCH_1):VR_PVCCIO_CPU1_VINSEN
    2  GND                B  @BASEBOARD_FAB2_LIB.BASEBOARD_FAB2(SCH_1):GND

CAP  I125  C4D42  [CAP_0402LF-1000PF,50V,10%,X7R,A]
    1  VR_VRRDY_PVCCIN_CPU0      A  @BASEBOARD_FAB2_LIB.BASEBOARD_FAB2(SCH_1):VR_VRRDY_PVCCIN_CPU0
    2  GND                B  @BASEBOARD_FAB2_LIB.BASEBOARD_FAB2(SCH_1):GND

CAP  I83  C4D44  [CAP_0402LF-220PF,50V,10%,X7R,AA]
    2  VSENSE_PVCCIO_CPU1_AVSN      B  @BASEBOARD_FAB2_LIB.BASEBOARD_FAB2(SCH_1):VSENSE_PVCCIO_CPU1_AVSN
    1  VR_PVCCIO_CPU1_AVSP      A  @BASEBOARD_FAB2_LIB.BASEBOARD_FAB2(SCH_1):VR_PVCCIO_CPU1_AVSP

CAP  I70  C4D45  [CAP_0402LF-220PF,50V,10%,X7R,AA]
    2  VSENSE_PVCCIN_CPU0_N      B  @BASEBOARD_FAB2_LIB.BASEBOARD_FAB2(SCH_1):VSENSE_PVCCIN_CPU0_N
    1  VSENSE_PVCCIN_CPU0_AVSP      A  @BASEBOARD_FAB2_LIB.BASEBOARD_FAB2(SCH_1):VSENSE_PVCCIN_CPU0_AVSP

CAP_0402  I34  C4D46  [CAP_0402-1.0UF,16V,10%,X6S,D97A]
    1  VR_PVCCIN_CPU0_PH5_VCIN      A  @BASEBOARD_FAB2_LIB.BASEBOARD_FAB2(SCH_1):VR_PVCCIN_CPU0_PH5_VCIN
    2  GND                B  @BASEBOARD_FAB2_LIB.BASEBOARD_FAB2(SCH_1):GND

CAP_0402  I18  C4D47  [CAP_0402-0.22UF,16V,10%,X7R,A3A]
    1  P5V_STBY           A  @BASEBOARD_FAB2_LIB.BASEBOARD_FAB2(SCH_1):P5V_STBY
    2  GND                B  @BASEBOARD_FAB2_LIB.BASEBOARD_FAB2(SCH_1):GND

CAP_0402  I47  C4D48  [CAP_0402-1.0UF,16V,10%,X6S,D97A]
    1  VR_FET_SW_P12V_STBY_PVCCIN_CPU0      A  @BASEBOARD_FAB2_LIB.BASEBOARD_FAB2(SCH_1):VR_FET_SW_P12V_STBY_PVCCIN_CPU0
    2  GND                B  @BASEBOARD_FAB2_LIB.BASEBOARD_FAB2(SCH_1):GND

CAP_A  I46  C4D49  [CAP_A_0402V-0.1UF,16V,10%,X7R,A]
    1  VR_FET_SW_P12V_STBY_PVCCIN_CPU0      A  @BASEBOARD_FAB2_LIB.BASEBOARD_FAB2(SCH_1):VR_FET_SW_P12V_STBY_PVCCIN_CPU0
    2  GND                B  @BASEBOARD_FAB2_LIB.BASEBOARD_FAB2(SCH_1):GND

CAP_0402  I32  C4D50  [CAP_0402-0.220UF,16V,10%,X7R,AA]
    2  VR_PVCCIN_CPU0_PH2_PHASE      B  @BASEBOARD_FAB2_LIB.BASEBOARD_FAB2(SCH_1):VR_PVCCIN_CPU0_PH2_PHASE
    1  VR_PVCCIN_CPU0_PH2_BOOT      A  @BASEBOARD_FAB2_LIB.BASEBOARD_FAB2(SCH_1):VR_PVCCIN_CPU0_PH2_BOOT

CAP_A  I61  C4E3   [CAP_A_0603V-22.0UF,4V,20%,X6S,A]
    1  PVCCIN_CPU0        A  @BASEBOARD_FAB2_LIB.BASEBOARD_FAB2(SCH_1):PVCCIN_CPU0
    2  GND                B  @BASEBOARD_FAB2_LIB.BASEBOARD_FAB2(SCH_1):GND

CAP_0402  I18  C4E5   [CAP_0402-0.22UF,16V,10%,X7R,A3A]
    1  P5V_STBY           A  @BASEBOARD_FAB2_LIB.BASEBOARD_FAB2(SCH_1):P5V_STBY
    2  GND                B  @BASEBOARD_FAB2_LIB.BASEBOARD_FAB2(SCH_1):GND

CAP_A  I19  C4E6   [CAP_A_0402V-1.0UF,6.3V,10%,X6SA]
    1  P5V_STBY           A  @BASEBOARD_FAB2_LIB.BASEBOARD_FAB2(SCH_1):P5V_STBY
    2  GND                B  @BASEBOARD_FAB2_LIB.BASEBOARD_FAB2(SCH_1):GND

CAPP  I20  C4E7   [CAPP_3018-470UF,2.5V,20%,ALUM,A]
    1  PVCCIO_CPU1        A  @BASEBOARD_FAB2_LIB.BASEBOARD_FAB2(SCH_1):PVCCIO_CPU1
    2  GND                B  @BASEBOARD_FAB2_LIB.BASEBOARD_FAB2(SCH_1):GND

CAP  I29  C4E8   [CAP_1210-100UF,16V,20%,X5R,644A]
    1  VR_FET_SW_P12V_STBY_PVCCIN_CPU0      A  @BASEBOARD_FAB2_LIB.BASEBOARD_FAB2(SCH_1):VR_FET_SW_P12V_STBY_PVCCIN_CPU0
    2  GND                B  @BASEBOARD_FAB2_LIB.BASEBOARD_FAB2(SCH_1):GND

CAP  I8   C4E9   [CAP_1210-100UF,16V,20%,X5R,644A]
    1  VR_FET_SW_P12V_STBY_PVCCIN_CPU0      A  @BASEBOARD_FAB2_LIB.BASEBOARD_FAB2(SCH_1):VR_FET_SW_P12V_STBY_PVCCIN_CPU0
    2  GND                B  @BASEBOARD_FAB2_LIB.BASEBOARD_FAB2(SCH_1):GND

CAP_0402  I34  C4E10  [CAP_0402-1.0UF,16V,10%,X6S,D97A]
    1  VR_PVCCIN_CPU0_PH1_VCIN      A  @BASEBOARD_FAB2_LIB.BASEBOARD_FAB2(SCH_1):VR_PVCCIN_CPU0_PH1_VCIN
    2  GND                B  @BASEBOARD_FAB2_LIB.BASEBOARD_FAB2(SCH_1):GND

CAP_A  I27  C4E11  [CAP_A_0603V-22.0UF,4V,20%,X6S,A]
    1  PVCCIN_CPU0        A  @BASEBOARD_FAB2_LIB.BASEBOARD_FAB2(SCH_1):PVCCIN_CPU0
    2  GND                B  @BASEBOARD_FAB2_LIB.BASEBOARD_FAB2(SCH_1):GND

CAP_A  I77  C4E13  [CAP_A_0402V-0.1UF,16V,10%,X7R,A]
    1  VR_FET_SW_P12V_STBY_PVCCIN_CPU0      A  @BASEBOARD_FAB2_LIB.BASEBOARD_FAB2(SCH_1):VR_FET_SW_P12V_STBY_PVCCIN_CPU0
    2  GND                B  @BASEBOARD_FAB2_LIB.BASEBOARD_FAB2(SCH_1):GND

CAP  I31  C4E14  [CAP_1210-100UF,16V,20%,X5R,644A]
    1  VR_FET_SW_P12V_STBY_PVCCIN_CPU0      A  @BASEBOARD_FAB2_LIB.BASEBOARD_FAB2(SCH_1):VR_FET_SW_P12V_STBY_PVCCIN_CPU0
    2  GND                B  @BASEBOARD_FAB2_LIB.BASEBOARD_FAB2(SCH_1):GND

CAP_0402  I79  C4E15  [CAP_0402-1.0UF,16V,10%,X6S,D97A]
    1  VR_FET_SW_P12V_STBY_PVCCIN_CPU0      A  @BASEBOARD_FAB2_LIB.BASEBOARD_FAB2(SCH_1):VR_FET_SW_P12V_STBY_PVCCIN_CPU0
    2  GND                B  @BASEBOARD_FAB2_LIB.BASEBOARD_FAB2(SCH_1):GND

CAPP  I50  C4E16  [CAPP_2626-270UF,16V,20%,OSCON,A]
    1  VR_FET_SW_P12V_STBY_PVCCIN_CPU0      A  @BASEBOARD_FAB2_LIB.BASEBOARD_FAB2(SCH_1):VR_FET_SW_P12V_STBY_PVCCIN_CPU0
    2  GND                B  @BASEBOARD_FAB2_LIB.BASEBOARD_FAB2(SCH_1):GND

CAP_0402  I22  C4E17  [CAP_0402-0.220UF,16V,10%,X7R,AA]
    2  VR_PVCCIN_CPU0_PH1_PHASE      B  @BASEBOARD_FAB2_LIB.BASEBOARD_FAB2(SCH_1):VR_PVCCIN_CPU0_PH1_PHASE
    1  VR_PVCCIN_CPU0_PH1_BOOT      A  @BASEBOARD_FAB2_LIB.BASEBOARD_FAB2(SCH_1):VR_PVCCIN_CPU0_PH1_BOOT

CAP_0402  I78  C4E18  [CAP_0402-0.220UF,16V,10%,X7R,AA]
    2  VR_PVCCIO_CPU1_PH1_PHASE      B  @BASEBOARD_FAB2_LIB.BASEBOARD_FAB2(SCH_1):VR_PVCCIO_CPU1_PH1_PHASE
    1  VR_PVCCIO_CPU1_PH1_BOOT      A  @BASEBOARD_FAB2_LIB.BASEBOARD_FAB2(SCH_1):VR_PVCCIO_CPU1_PH1_BOOT

CAP_0402  I36  C4E19  [CAP_0402-1.0UF,16V,10%,X6S,D97A]
    1  VR_FET_SW_P12V_STBY_PVCCIN_CPU0      A  @BASEBOARD_FAB2_LIB.BASEBOARD_FAB2(SCH_1):VR_FET_SW_P12V_STBY_PVCCIN_CPU0
    2  GND                B  @BASEBOARD_FAB2_LIB.BASEBOARD_FAB2(SCH_1):GND

CAP_A  I35  C4E20  [CAP_A_0402V-0.1UF,16V,10%,X7R,A]
    1  VR_FET_SW_P12V_STBY_PVCCIN_CPU0      A  @BASEBOARD_FAB2_LIB.BASEBOARD_FAB2(SCH_1):VR_FET_SW_P12V_STBY_PVCCIN_CPU0
    2  GND                B  @BASEBOARD_FAB2_LIB.BASEBOARD_FAB2(SCH_1):GND

CAP_0402  I76  C4E22  [CAP_0402-1.0UF,16V,10%,X6S,D97A]
    1  VR_PVCCIO_CPU1_PH1_VCIN      A  @BASEBOARD_FAB2_LIB.BASEBOARD_FAB2(SCH_1):VR_PVCCIO_CPU1_PH1_VCIN
    2  GND                B  @BASEBOARD_FAB2_LIB.BASEBOARD_FAB2(SCH_1):GND

CAP_0402  I73  C4E23  [CAP_0402-0.22UF,16V,10%,X7R,A3A]
    1  P5V_STBY           A  @BASEBOARD_FAB2_LIB.BASEBOARD_FAB2(SCH_1):P5V_STBY
    2  GND                B  @BASEBOARD_FAB2_LIB.BASEBOARD_FAB2(SCH_1):GND

CAPP  I61  C4E24  [CAPP_3018-470UF,2.5V,20%,ALUM,A]
    1  PVCCMCP_CPU1       A  @BASEBOARD_FAB2_LIB.BASEBOARD_FAB2(SCH_1):PVCCMCP_CPU1
    2  GND                B  @BASEBOARD_FAB2_LIB.BASEBOARD_FAB2(SCH_1):GND

CAP_A  I25  C4E25  [CAP_A_0402V-1.0UF,6.3V,10%,X6SA]
    1  P5V_STBY           A  @BASEBOARD_FAB2_LIB.BASEBOARD_FAB2(SCH_1):P5V_STBY
    2  GND                B  @BASEBOARD_FAB2_LIB.BASEBOARD_FAB2(SCH_1):GND

CAP_0402  I45  C4E26  [CAP_0402-1.0UF,16V,10%,X6S,D97A]
    1  VR_PVCCIN_CPU0_PH2_VCIN      A  @BASEBOARD_FAB2_LIB.BASEBOARD_FAB2(SCH_1):VR_PVCCIN_CPU0_PH2_VCIN
    2  GND                B  @BASEBOARD_FAB2_LIB.BASEBOARD_FAB2(SCH_1):GND

CAP_0402  I24  C4E27  [CAP_0402-0.22UF,16V,10%,X7R,A3A]
    1  P5V_STBY           A  @BASEBOARD_FAB2_LIB.BASEBOARD_FAB2(SCH_1):P5V_STBY
    2  GND                B  @BASEBOARD_FAB2_LIB.BASEBOARD_FAB2(SCH_1):GND

CAP_A  I74  C4E28  [CAP_A_0402V-1.0UF,6.3V,10%,X6SA]
    1  P5V_STBY           A  @BASEBOARD_FAB2_LIB.BASEBOARD_FAB2(SCH_1):P5V_STBY
    2  GND                B  @BASEBOARD_FAB2_LIB.BASEBOARD_FAB2(SCH_1):GND

CAP_A  I68  C4F1   [CAP_A_0402V-1.0UF,6.3V,10%,X6SA]
    1  P1V8_MCP_CPU1      A  @BASEBOARD_FAB2_LIB.BASEBOARD_FAB2(SCH_1):P1V8_MCP_CPU1
    2  GND                B  @BASEBOARD_FAB2_LIB.BASEBOARD_FAB2(SCH_1):GND

CAP_A  I141  C4F2   [CAP_A_0603V-47UF,4V,20%,X5R,60A]
    1  P1V8_MCP_CPU1      A  @BASEBOARD_FAB2_LIB.BASEBOARD_FAB2(SCH_1):P1V8_MCP_CPU1
    2  GND                B  @BASEBOARD_FAB2_LIB.BASEBOARD_FAB2(SCH_1):GND

CAP_A  I70  C4F3   [CAP_A_0402V-1.0UF,6.3V,10%,X6SA]
    1  P1V8_MCP_CPU1      A  @BASEBOARD_FAB2_LIB.BASEBOARD_FAB2(SCH_1):P1V8_MCP_CPU1
    2  GND                B  @BASEBOARD_FAB2_LIB.BASEBOARD_FAB2(SCH_1):GND

CAPP  I112  C4F4   [CAPP_3018-68UF,16V,20%,TANT,72A]
    1  P12V_STBY          A  @BASEBOARD_FAB2_LIB.BASEBOARD_FAB2(SCH_1):P12V_STBY
    2  GND                B  @BASEBOARD_FAB2_LIB.BASEBOARD_FAB2(SCH_1):GND

CAPP  I96  C4F5   [CAPP_3018-68UF,16V,20%,TANT,72A]
    1  P12V_STBY          A  @BASEBOARD_FAB2_LIB.BASEBOARD_FAB2(SCH_1):P12V_STBY
    2  GND                B  @BASEBOARD_FAB2_LIB.BASEBOARD_FAB2(SCH_1):GND

CAPP  I82  C4F6   [CAPP_4040LF-470UF,16V,20%,ALUMA]
    1  P12V_STBY          A  @BASEBOARD_FAB2_LIB.BASEBOARD_FAB2(SCH_1):P12V_STBY
    2  GND                B  @BASEBOARD_FAB2_LIB.BASEBOARD_FAB2(SCH_1):GND

CAPP  I217  C4F7   [CAPP_7343LF-330UF,6.3V,20%,POSA]
    1  PVPP_GHJ           A  @BASEBOARD_FAB2_LIB.BASEBOARD_FAB2(SCH_1):PVPP_GHJ
    2  GND                B  @BASEBOARD_FAB2_LIB.BASEBOARD_FAB2(SCH_1):GND

CAP_A  I7   C4F9   [CAP_A_0402V-0.01UF,25V,10%,X7RA]
    1  M_A_CPU_VREF       A  @BASEBOARD_FAB2_LIB.BASEBOARD_FAB2(SCH_1):M_A_CPU_VREF
    2  GND                B  @BASEBOARD_FAB2_LIB.BASEBOARD_FAB2(SCH_1):GND

CAP_A  I272  C4F10  [CAP_A_0402V-0.01UF,25V,10%,X7RA]
    1  M_A_VREF           A  @BASEBOARD_FAB2_LIB.BASEBOARD_FAB2(SCH_1):M_A_VREF
    2  GND                B  @BASEBOARD_FAB2_LIB.BASEBOARD_FAB2(SCH_1):GND

CAPP  I256  C4F11  [CAPP_7343-220UF,4V,20%,POSCAP,A]
    1  PVPP_GHJ           A  @BASEBOARD_FAB2_LIB.BASEBOARD_FAB2(SCH_1):PVPP_GHJ
    2  GND                B  @BASEBOARD_FAB2_LIB.BASEBOARD_FAB2(SCH_1):GND

CAP  I209  C4F12  [CAP_0402LF-3300PF,50V,10%,EMPTA]
    2  VR_PVPP_GHJ_SNUB      B  @BASEBOARD_FAB2_LIB.BASEBOARD_FAB2(SCH_1):VR_PVPP_GHJ_SNUB
    1  VR_PVPP_GHJ_PHASE      A  @BASEBOARD_FAB2_LIB.BASEBOARD_FAB2(SCH_1):VR_PVPP_GHJ_PHASE

CAP_A  I43  C4G1   [CAP_A_0402V-0.01UF,25V,10%,X7RA]
    1  M_B_CPU_VREF       A  @BASEBOARD_FAB2_LIB.BASEBOARD_FAB2(SCH_1):M_B_CPU_VREF
    2  GND                B  @BASEBOARD_FAB2_LIB.BASEBOARD_FAB2(SCH_1):GND

CAP  I253  C4G2   [CAP_0805-10UF,16V,10%,X6S,C953A]
    1  VR_FET_SW_P12V_STBY_PVPP_GHJ      A  @BASEBOARD_FAB2_LIB.BASEBOARD_FAB2(SCH_1):VR_FET_SW_P12V_STBY_PVPP_GHJ
    2  GND                B  @BASEBOARD_FAB2_LIB.BASEBOARD_FAB2(SCH_1):GND

CAP_A  I179  C4G3   [CAP_A_0402V-0.01UF,25V,10%,X7RA]
    1  M_B_VREF           A  @BASEBOARD_FAB2_LIB.BASEBOARD_FAB2(SCH_1):M_B_VREF
    2  GND                B  @BASEBOARD_FAB2_LIB.BASEBOARD_FAB2(SCH_1):GND

CAP_0402  I196  C4G4   [CAP_0402-1.0UF,16V,10%,X6S,D97A]
    1  VR_FET_SW_P12V_STBY_PVPP_GHJ      A  @BASEBOARD_FAB2_LIB.BASEBOARD_FAB2(SCH_1):VR_FET_SW_P12V_STBY_PVPP_GHJ
    2  GND                B  @BASEBOARD_FAB2_LIB.BASEBOARD_FAB2(SCH_1):GND

CAP  I189  C4G5   [CAP_1210-47UF,16V,20%,X6S,D384A]
    1  VR_FET_SW_P12V_STBY_PVPP_GHJ      A  @BASEBOARD_FAB2_LIB.BASEBOARD_FAB2(SCH_1):VR_FET_SW_P12V_STBY_PVPP_GHJ
    2  GND                B  @BASEBOARD_FAB2_LIB.BASEBOARD_FAB2(SCH_1):GND

CAP  I273  C4G6   [CAP_0402LF-100.0PF,50V,5%,COG,A]
    1  VR_FB_PVPP_GHJ      A  @BASEBOARD_FAB2_LIB.BASEBOARD_FAB2(SCH_1):VR_FB_PVPP_GHJ
    2  VR_COMP_PVPP_GHJ_3      B  @BASEBOARD_FAB2_LIB.BASEBOARD_FAB2(SCH_1):VR_COMP_PVPP_GHJ_3

CAP  I183  C4G7   [CAP_0402LF-1000PF,50V,10%,EMPTA]
    1  FM_PVPP_CPU1_EN      A  @BASEBOARD_FAB2_LIB.BASEBOARD_FAB2(SCH_1):FM_PVPP_CPU1_EN
    2  AGND_PVPP_GHJ      B  @BASEBOARD_FAB2_LIB.BASEBOARD_FAB2(SCH_1):AGND_PVPP_GHJ

CAP_0402  I194  C4G8   [CAP_0402-0.027UF,16V,10%,X7R,AA]
    1  VR_PVPP_GHJ_SS      A  @BASEBOARD_FAB2_LIB.BASEBOARD_FAB2(SCH_1):VR_PVPP_GHJ_SS
    2  AGND_PVPP_GHJ      B  @BASEBOARD_FAB2_LIB.BASEBOARD_FAB2(SCH_1):AGND_PVPP_GHJ

CAP  I201  C4G9   [CAP_0402LF-1000PF,50V,10%,X7R,A]
    1  PWRGD_PVPP_GHJ_R      A  @BASEBOARD_FAB2_LIB.BASEBOARD_FAB2(SCH_1):PWRGD_PVPP_GHJ_R
    2  GND                B  @BASEBOARD_FAB2_LIB.BASEBOARD_FAB2(SCH_1):GND

CAP  I274  C4G10  [CAP_0402LF-2200PF,50V,10%,X7R,A]
    1  VR_COMP_RC_PVPP_GHJ      A  @BASEBOARD_FAB2_LIB.BASEBOARD_FAB2(SCH_1):VR_COMP_RC_PVPP_GHJ
    2  VR_COMP_PVPP_GHJ_3      B  @BASEBOARD_FAB2_LIB.BASEBOARD_FAB2(SCH_1):VR_COMP_PVPP_GHJ_3

CAP  I267  C4G11  [CAP_0402LF-2200PF,50V,10%,X7R,A]
    2  VR_FB_PVPP_GHJ      B  @BASEBOARD_FAB2_LIB.BASEBOARD_FAB2(SCH_1):VR_FB_PVPP_GHJ
    1  VR_COMP_PVPP_GHJ      A  @BASEBOARD_FAB2_LIB.BASEBOARD_FAB2(SCH_1):VR_COMP_PVPP_GHJ

CAP  I36  C4G12  [CAP_0402LF-1000PF,50V,10%,EMPTA]
    2  GND                B  @BASEBOARD_FAB2_LIB.BASEBOARD_FAB2(SCH_1):GND
    1  FM_PVTT_GHJ_EN_R      A  @BASEBOARD_FAB2_LIB.BASEBOARD_FAB2(SCH_1):FM_PVTT_GHJ_EN_R

CAP  I15  C4G13  [CAP_0402LF-1000PF,50V,10%,X7R,A]
    1  PWRGD_PVTT_GHJ_CPU1_R      A  @BASEBOARD_FAB2_LIB.BASEBOARD_FAB2(SCH_1):PWRGD_PVTT_GHJ_CPU1_R
    2  GND                B  @BASEBOARD_FAB2_LIB.BASEBOARD_FAB2(SCH_1):GND

CAP  I15  C4G14  [CAP_0402LF-1000PF,50V,10%,X7R,A]
    1  PWRGD_PVTT_ABC_CPU0_R      A  @BASEBOARD_FAB2_LIB.BASEBOARD_FAB2(SCH_1):PWRGD_PVTT_ABC_CPU0_R
    2  GND                B  @BASEBOARD_FAB2_LIB.BASEBOARD_FAB2(SCH_1):GND

CAP_0402  I24  C4G15  [CAP_0402-1.0UF,16V,10%,X6S,D97A]
    1  VR_PVTT_ABC_BIAS      A  @BASEBOARD_FAB2_LIB.BASEBOARD_FAB2(SCH_1):VR_PVTT_ABC_BIAS
    2  GND                B  @BASEBOARD_FAB2_LIB.BASEBOARD_FAB2(SCH_1):GND

CAP_0402  I34  C4G16  [CAP_0402-1.0UF,16V,10%,X6S,D97A]
    1  VR_PVTT_ABC_VREF      A  @BASEBOARD_FAB2_LIB.BASEBOARD_FAB2(SCH_1):VR_PVTT_ABC_VREF
    2  GND                B  @BASEBOARD_FAB2_LIB.BASEBOARD_FAB2(SCH_1):GND

CAP_A  I51  C4G17  [CAP_A_0402V-0.01UF,25V,10%,X7RA]
    1  M_C_CPU_VREF       A  @BASEBOARD_FAB2_LIB.BASEBOARD_FAB2(SCH_1):M_C_CPU_VREF
    2  GND                B  @BASEBOARD_FAB2_LIB.BASEBOARD_FAB2(SCH_1):GND

CAP_0402  I27  C4G18  [CAP_0402-1.0UF,16V,10%,X6S,D97A]
    1  VR_PVTT_GHJ_BIAS      A  @BASEBOARD_FAB2_LIB.BASEBOARD_FAB2(SCH_1):VR_PVTT_GHJ_BIAS
    2  GND                B  @BASEBOARD_FAB2_LIB.BASEBOARD_FAB2(SCH_1):GND

CAP_A  I188  C4G19  [CAP_A_0402V-0.01UF,25V,10%,X7RA]
    1  M_C_VREF           A  @BASEBOARD_FAB2_LIB.BASEBOARD_FAB2(SCH_1):M_C_VREF
    2  GND                B  @BASEBOARD_FAB2_LIB.BASEBOARD_FAB2(SCH_1):GND

CAP  I17  C4G20  [CAP_0805LF-22UF,4V,20%,X6S,C95A]
    1  PVTT_GHJ           A  @BASEBOARD_FAB2_LIB.BASEBOARD_FAB2(SCH_1):PVTT_GHJ
    2  GND                B  @BASEBOARD_FAB2_LIB.BASEBOARD_FAB2(SCH_1):GND

CAP_0402  I21  C4G21  [CAP_0402-1.0UF,16V,10%,X6S,D97A]
    1  VR_PVTT_GHJ_VREF      A  @BASEBOARD_FAB2_LIB.BASEBOARD_FAB2(SCH_1):VR_PVTT_GHJ_VREF
    2  GND                B  @BASEBOARD_FAB2_LIB.BASEBOARD_FAB2(SCH_1):GND

CAP_A  I27  C4G22  [CAP_A_0402V-0.1UF,16V,10%,X7R,A]
    1  PVCCIO_CPU1        A  @BASEBOARD_FAB2_LIB.BASEBOARD_FAB2(SCH_1):PVCCIO_CPU1
    2  GND                B  @BASEBOARD_FAB2_LIB.BASEBOARD_FAB2(SCH_1):GND

CAP  I39  C4G23  [CAP_0402LF-1000PF,50V,10%,EMPTA]
    2  GND                B  @BASEBOARD_FAB2_LIB.BASEBOARD_FAB2(SCH_1):GND
    1  FM_PVTT_ABC_EN_R      A  @BASEBOARD_FAB2_LIB.BASEBOARD_FAB2(SCH_1):FM_PVTT_ABC_EN_R

CAP  I20  C4G24  [CAP_0805LF-22UF,4V,20%,X6S,C95A]
    1  PVTT_ABC           A  @BASEBOARD_FAB2_LIB.BASEBOARD_FAB2(SCH_1):PVTT_ABC
    2  GND                B  @BASEBOARD_FAB2_LIB.BASEBOARD_FAB2(SCH_1):GND

CAP_A  I41  C4G25  [CAP_A_0402V-0.1UF,16V,10%,X7R,A]
    1  PVPP_GHJ           A  @BASEBOARD_FAB2_LIB.BASEBOARD_FAB2(SCH_1):PVPP_GHJ
    2  GND                B  @BASEBOARD_FAB2_LIB.BASEBOARD_FAB2(SCH_1):GND

CAP  I224  C4G26  [CAP_0603LF-0.1UF,25V,10%,X7R,6A]
    1  VR_PVPP_GHJ_PHASE      A  @BASEBOARD_FAB2_LIB.BASEBOARD_FAB2(SCH_1):VR_PVPP_GHJ_PHASE
    2  VR_PVPP_GHJ_BOOT_R      B  @BASEBOARD_FAB2_LIB.BASEBOARD_FAB2(SCH_1):VR_PVPP_GHJ_BOOT_R

CAP  I129  C4L1   [CAP_0603LF-10UF,4V,20%,X6S,E15A]
    1  PVPP_DEF           A  @BASEBOARD_FAB2_LIB.BASEBOARD_FAB2(SCH_1):PVPP_DEF
    2  GND                B  @BASEBOARD_FAB2_LIB.BASEBOARD_FAB2(SCH_1):GND

CAP  I102  C4L2   [CAP_0603LF-10UF,4V,20%,X6S,E15A]
    1  PVPP_DEF           A  @BASEBOARD_FAB2_LIB.BASEBOARD_FAB2(SCH_1):PVPP_DEF
    2  GND                B  @BASEBOARD_FAB2_LIB.BASEBOARD_FAB2(SCH_1):GND

CAP  I106  C4L3   [CAP_0603LF-10UF,4V,20%,X6S,E15A]
    1  PVPP_DEF           A  @BASEBOARD_FAB2_LIB.BASEBOARD_FAB2(SCH_1):PVPP_DEF
    2  GND                B  @BASEBOARD_FAB2_LIB.BASEBOARD_FAB2(SCH_1):GND

CAP  I108  C4L4   [CAP_0603LF-10UF,4V,20%,X6S,E15A]
    1  PVPP_DEF           A  @BASEBOARD_FAB2_LIB.BASEBOARD_FAB2(SCH_1):PVPP_DEF
    2  GND                B  @BASEBOARD_FAB2_LIB.BASEBOARD_FAB2(SCH_1):GND

CAPP  I78  C4L5   [CAPP_3018-470UF,2.5V,20%,ALUM,A]
    1  PVDDQ_DEF          A  @BASEBOARD_FAB2_LIB.BASEBOARD_FAB2(SCH_1):PVDDQ_DEF
    2  GND                B  @BASEBOARD_FAB2_LIB.BASEBOARD_FAB2(SCH_1):GND

CAPP  I267  C4M1   [CAPP_7343-220UF,4V,20%,POSCAP,A]
    1  PVPP_DEF           A  @BASEBOARD_FAB2_LIB.BASEBOARD_FAB2(SCH_1):PVPP_DEF
    2  GND                B  @BASEBOARD_FAB2_LIB.BASEBOARD_FAB2(SCH_1):GND

CAP_A  I222  C4M2   [CAP_A_0603V-22.0UF,4V,20%,X6S,A]
    1  PVDDQ_DEF          A  @BASEBOARD_FAB2_LIB.BASEBOARD_FAB2(SCH_1):PVDDQ_DEF
    2  GND                B  @BASEBOARD_FAB2_LIB.BASEBOARD_FAB2(SCH_1):GND

CAP  I111  C4M3   [CAP_0603LF-10UF,4V,20%,X6S,E15A]
    1  PVPP_DEF           A  @BASEBOARD_FAB2_LIB.BASEBOARD_FAB2(SCH_1):PVPP_DEF
    2  GND                B  @BASEBOARD_FAB2_LIB.BASEBOARD_FAB2(SCH_1):GND

CAP  I125  C4M4   [CAP_0603LF-10UF,4V,20%,X6S,E15A]
    1  PVPP_DEF           A  @BASEBOARD_FAB2_LIB.BASEBOARD_FAB2(SCH_1):PVPP_DEF
    2  GND                B  @BASEBOARD_FAB2_LIB.BASEBOARD_FAB2(SCH_1):GND

CAP_A  I196  C4M5   [CAP_A_0603V-47UF,4V,20%,X5R,60A]
    1  PVDDQ_DEF          A  @BASEBOARD_FAB2_LIB.BASEBOARD_FAB2(SCH_1):PVDDQ_DEF
    2  GND                B  @BASEBOARD_FAB2_LIB.BASEBOARD_FAB2(SCH_1):GND

CAPP  I102  C4M6   [CAPP_3018-68UF,16V,20%,TANT,72A]
    1  P12V_STBY          A  @BASEBOARD_FAB2_LIB.BASEBOARD_FAB2(SCH_1):P12V_STBY
    2  GND                B  @BASEBOARD_FAB2_LIB.BASEBOARD_FAB2(SCH_1):GND

CAPP  I105  C4M7   [CAPP_3018-68UF,16V,20%,TANT,72A]
    1  P12V_STBY          A  @BASEBOARD_FAB2_LIB.BASEBOARD_FAB2(SCH_1):P12V_STBY
    2  GND                B  @BASEBOARD_FAB2_LIB.BASEBOARD_FAB2(SCH_1):GND

CAP  I10  C4P1   [CAP_0805-47UF,4V,20%,X6S,C9533A]
    1  PVCCIO_CPU0        A  @BASEBOARD_FAB2_LIB.BASEBOARD_FAB2(SCH_1):PVCCIO_CPU0
    2  GND                B  @BASEBOARD_FAB2_LIB.BASEBOARD_FAB2(SCH_1):GND

CAP  I163  C4P2   [CAP_0805-47UF,4V,20%,X6S,C9533A]
    1  PVCCMCP_CPU0       A  @BASEBOARD_FAB2_LIB.BASEBOARD_FAB2(SCH_1):PVCCMCP_CPU0
    2  GND                B  @BASEBOARD_FAB2_LIB.BASEBOARD_FAB2(SCH_1):GND

CAP  I8   C4P3   [CAP_0805-47UF,4V,20%,X6S,C9533A]
    1  PVCCMCP_CPU0       A  @BASEBOARD_FAB2_LIB.BASEBOARD_FAB2(SCH_1):PVCCMCP_CPU0
    2  GND                B  @BASEBOARD_FAB2_LIB.BASEBOARD_FAB2(SCH_1):GND

CAP  I14  C4P4   [CAP_0805-47UF,4V,20%,X6S,C9533A]
    1  PVCCMCP_CPU0       A  @BASEBOARD_FAB2_LIB.BASEBOARD_FAB2(SCH_1):PVCCMCP_CPU0
    2  GND                B  @BASEBOARD_FAB2_LIB.BASEBOARD_FAB2(SCH_1):GND

CAP  I172  C4P5   [CAP_0805-47UF,4V,20%,X6S,C9533A]
    1  PVCCMCP_CPU0       A  @BASEBOARD_FAB2_LIB.BASEBOARD_FAB2(SCH_1):PVCCMCP_CPU0
    2  GND                B  @BASEBOARD_FAB2_LIB.BASEBOARD_FAB2(SCH_1):GND

CAP_A  I164  C4P6   [CAP_A_0603V-22.0UF,4V,20%,X6S,A]
    1  PVCCIO_CPU0        A  @BASEBOARD_FAB2_LIB.BASEBOARD_FAB2(SCH_1):PVCCIO_CPU0
    2  GND                B  @BASEBOARD_FAB2_LIB.BASEBOARD_FAB2(SCH_1):GND

CAP  I9   C4P7   [CAP_0805-47UF,4V,20%,X6S,C9533A]
    1  PVCCMCP_CPU0       A  @BASEBOARD_FAB2_LIB.BASEBOARD_FAB2(SCH_1):PVCCMCP_CPU0
    2  GND                B  @BASEBOARD_FAB2_LIB.BASEBOARD_FAB2(SCH_1):GND

CAP_A  I178  C4P8   [CAP_A_0603V-22.0UF,4V,20%,X6S,A]
    1  PVCCIO_CPU0        A  @BASEBOARD_FAB2_LIB.BASEBOARD_FAB2(SCH_1):PVCCIO_CPU0
    2  GND                B  @BASEBOARD_FAB2_LIB.BASEBOARD_FAB2(SCH_1):GND

CAP  I12  C4P9   [CAP_0805-47UF,4V,20%,X6S,C9533A]
    1  PVCCIO_CPU0        A  @BASEBOARD_FAB2_LIB.BASEBOARD_FAB2(SCH_1):PVCCIO_CPU0
    2  GND                B  @BASEBOARD_FAB2_LIB.BASEBOARD_FAB2(SCH_1):GND

CAP  I17  C4P10  [CAP_0805-47UF,4V,20%,X6S,C9533A]
    1  PVCCIO_CPU0        A  @BASEBOARD_FAB2_LIB.BASEBOARD_FAB2(SCH_1):PVCCIO_CPU0
    2  GND                B  @BASEBOARD_FAB2_LIB.BASEBOARD_FAB2(SCH_1):GND

CAPP  I29  C4R1   [CAPP_3018-470UF,2.5V,20%,ALUM,A]
    1  PVCCMCP_CPU0       A  @BASEBOARD_FAB2_LIB.BASEBOARD_FAB2(SCH_1):PVCCMCP_CPU0
    2  GND                B  @BASEBOARD_FAB2_LIB.BASEBOARD_FAB2(SCH_1):GND

CAP_A  I246  C4R2   [CAP_A_0402V-0.1UF,16V,10%,X7R,A]
    1  JTAG_MCP_CPU0_TDI_R      A  @BASEBOARD_FAB2_LIB.BASEBOARD_FAB2(SCH_1):JTAG_MCP_CPU0_TDI_R
    2  GND                B  @BASEBOARD_FAB2_LIB.BASEBOARD_FAB2(SCH_1):GND

CAP_A  I16  C4T1   [CAP_A_0402V-1.0UF,6.3V,10%,X6SA]
    1  P1V8_MCP_CPU0      A  @BASEBOARD_FAB2_LIB.BASEBOARD_FAB2(SCH_1):P1V8_MCP_CPU0
    2  GND                B  @BASEBOARD_FAB2_LIB.BASEBOARD_FAB2(SCH_1):GND

CAP_A  I9   C4T2   [CAP_A_0402V-1.0UF,6.3V,10%,X6SA]
    1  P1V8_MCP_CPU0      A  @BASEBOARD_FAB2_LIB.BASEBOARD_FAB2(SCH_1):P1V8_MCP_CPU0
    2  GND                B  @BASEBOARD_FAB2_LIB.BASEBOARD_FAB2(SCH_1):GND

CAPP  I217  C4T3   [CAPP_7343-220UF,4V,20%,POSCAP,A]
    1  PVPP_ABC           A  @BASEBOARD_FAB2_LIB.BASEBOARD_FAB2(SCH_1):PVPP_ABC
    2  GND                B  @BASEBOARD_FAB2_LIB.BASEBOARD_FAB2(SCH_1):GND

CAP  I91  C4T4   [CAP_0805-100UF,4V,20%,X5R,6024A]
    1  PVDDQ_ABC          A  @BASEBOARD_FAB2_LIB.BASEBOARD_FAB2(SCH_1):PVDDQ_ABC
    2  GND                B  @BASEBOARD_FAB2_LIB.BASEBOARD_FAB2(SCH_1):GND

CAP  I125  C4T5   [CAP_0603LF-10UF,4V,20%,X6S,E15A]
    1  PVPP_ABC           A  @BASEBOARD_FAB2_LIB.BASEBOARD_FAB2(SCH_1):PVPP_ABC
    2  GND                B  @BASEBOARD_FAB2_LIB.BASEBOARD_FAB2(SCH_1):GND

CAP  I124  C4T6   [CAP_0603LF-10UF,4V,20%,X6S,E15A]
    1  PVPP_ABC           A  @BASEBOARD_FAB2_LIB.BASEBOARD_FAB2(SCH_1):PVPP_ABC
    2  GND                B  @BASEBOARD_FAB2_LIB.BASEBOARD_FAB2(SCH_1):GND

CAP  I130  C4U1   [CAP_0603LF-10UF,4V,20%,X6S,E15A]
    1  PVPP_ABC           A  @BASEBOARD_FAB2_LIB.BASEBOARD_FAB2(SCH_1):PVPP_ABC
    2  GND                B  @BASEBOARD_FAB2_LIB.BASEBOARD_FAB2(SCH_1):GND

CAP  I129  C4U2   [CAP_0603LF-10UF,4V,20%,X6S,E15A]
    1  PVPP_ABC           A  @BASEBOARD_FAB2_LIB.BASEBOARD_FAB2(SCH_1):PVPP_ABC
    2  GND                B  @BASEBOARD_FAB2_LIB.BASEBOARD_FAB2(SCH_1):GND

CAP  I148  C4U3   [CAP_0603LF-10UF,4V,20%,X6S,E15A]
    1  PVPP_ABC           A  @BASEBOARD_FAB2_LIB.BASEBOARD_FAB2(SCH_1):PVPP_ABC
    2  GND                B  @BASEBOARD_FAB2_LIB.BASEBOARD_FAB2(SCH_1):GND

CAP  I146  C4U4   [CAP_0603LF-10UF,4V,20%,X6S,E15A]
    1  PVPP_ABC           A  @BASEBOARD_FAB2_LIB.BASEBOARD_FAB2(SCH_1):PVPP_ABC
    2  GND                B  @BASEBOARD_FAB2_LIB.BASEBOARD_FAB2(SCH_1):GND

CAP_A  I219  C5A1   [CAP_A_0603V-22.0UF,4V,20%,X6S,A]
    1  PVDDQ_DEF          A  @BASEBOARD_FAB2_LIB.BASEBOARD_FAB2(SCH_1):PVDDQ_DEF
    2  GND                B  @BASEBOARD_FAB2_LIB.BASEBOARD_FAB2(SCH_1):GND

CAP_A  I214  C5A2   [CAP_A_0603V-22.0UF,4V,20%,X6S,A]
    1  PVDDQ_DEF          A  @BASEBOARD_FAB2_LIB.BASEBOARD_FAB2(SCH_1):PVDDQ_DEF
    2  GND                B  @BASEBOARD_FAB2_LIB.BASEBOARD_FAB2(SCH_1):GND

CAP_A  I210  C5A3   [CAP_A_0603V-22.0UF,4V,20%,X6S,A]
    1  PVDDQ_DEF          A  @BASEBOARD_FAB2_LIB.BASEBOARD_FAB2(SCH_1):PVDDQ_DEF
    2  GND                B  @BASEBOARD_FAB2_LIB.BASEBOARD_FAB2(SCH_1):GND

CAP_A  I206  C5A4   [CAP_A_0603V-22.0UF,4V,20%,X6S,A]
    1  PVDDQ_DEF          A  @BASEBOARD_FAB2_LIB.BASEBOARD_FAB2(SCH_1):PVDDQ_DEF
    2  GND                B  @BASEBOARD_FAB2_LIB.BASEBOARD_FAB2(SCH_1):GND

CAP_A  I193  C5A5   [CAP_A_0603V-47UF,4V,20%,X5R,60A]
    1  PVDDQ_DEF          A  @BASEBOARD_FAB2_LIB.BASEBOARD_FAB2(SCH_1):PVDDQ_DEF
    2  GND                B  @BASEBOARD_FAB2_LIB.BASEBOARD_FAB2(SCH_1):GND

CAP_A  I212  C5A6   [CAP_A_0603V-22.0UF,4V,20%,X6S,A]
    1  PVDDQ_DEF          A  @BASEBOARD_FAB2_LIB.BASEBOARD_FAB2(SCH_1):PVDDQ_DEF
    2  GND                B  @BASEBOARD_FAB2_LIB.BASEBOARD_FAB2(SCH_1):GND

CAP_A  I211  C5A7   [CAP_A_0603V-22.0UF,4V,20%,X6S,A]
    1  PVDDQ_DEF          A  @BASEBOARD_FAB2_LIB.BASEBOARD_FAB2(SCH_1):PVDDQ_DEF
    2  GND                B  @BASEBOARD_FAB2_LIB.BASEBOARD_FAB2(SCH_1):GND

CAP_A  I209  C5A8   [CAP_A_0603V-22.0UF,4V,20%,X6S,A]
    1  PVDDQ_DEF          A  @BASEBOARD_FAB2_LIB.BASEBOARD_FAB2(SCH_1):PVDDQ_DEF
    2  GND                B  @BASEBOARD_FAB2_LIB.BASEBOARD_FAB2(SCH_1):GND

CAP_A  I208  C5A9   [CAP_A_0603V-22.0UF,4V,20%,X6S,A]
    1  PVDDQ_DEF          A  @BASEBOARD_FAB2_LIB.BASEBOARD_FAB2(SCH_1):PVDDQ_DEF
    2  GND                B  @BASEBOARD_FAB2_LIB.BASEBOARD_FAB2(SCH_1):GND

CAP  I110  C5A10  [CAP_0805-100UF,4V,20%,X5R,6024A]
    1  PVDDQ_DEF          A  @BASEBOARD_FAB2_LIB.BASEBOARD_FAB2(SCH_1):PVDDQ_DEF
    2  GND                B  @BASEBOARD_FAB2_LIB.BASEBOARD_FAB2(SCH_1):GND

CAP_A  I221  C5A11  [CAP_A_0603V-22.0UF,4V,20%,X6S,A]
    1  PVDDQ_DEF          A  @BASEBOARD_FAB2_LIB.BASEBOARD_FAB2(SCH_1):PVDDQ_DEF
    2  GND                B  @BASEBOARD_FAB2_LIB.BASEBOARD_FAB2(SCH_1):GND

CAP_A  I216  C5A12  [CAP_A_0603V-22.0UF,4V,20%,X6S,A]
    1  PVDDQ_DEF          A  @BASEBOARD_FAB2_LIB.BASEBOARD_FAB2(SCH_1):PVDDQ_DEF
    2  GND                B  @BASEBOARD_FAB2_LIB.BASEBOARD_FAB2(SCH_1):GND

CAP_A  I215  C5A13  [CAP_A_0603V-22.0UF,4V,20%,X6S,A]
    1  PVDDQ_DEF          A  @BASEBOARD_FAB2_LIB.BASEBOARD_FAB2(SCH_1):PVDDQ_DEF
    2  GND                B  @BASEBOARD_FAB2_LIB.BASEBOARD_FAB2(SCH_1):GND

CAP_A  I213  C5A14  [CAP_A_0603V-22.0UF,4V,20%,X6S,A]
    1  PVDDQ_DEF          A  @BASEBOARD_FAB2_LIB.BASEBOARD_FAB2(SCH_1):PVDDQ_DEF
    2  GND                B  @BASEBOARD_FAB2_LIB.BASEBOARD_FAB2(SCH_1):GND

CAP_A  I217  C5A15  [CAP_A_0603V-22.0UF,4V,20%,X6S,A]
    1  PVDDQ_DEF          A  @BASEBOARD_FAB2_LIB.BASEBOARD_FAB2(SCH_1):PVDDQ_DEF
    2  GND                B  @BASEBOARD_FAB2_LIB.BASEBOARD_FAB2(SCH_1):GND

CAP_A  I207  C5A16  [CAP_A_0603V-22.0UF,4V,20%,X6S,A]
    1  PVDDQ_DEF          A  @BASEBOARD_FAB2_LIB.BASEBOARD_FAB2(SCH_1):PVDDQ_DEF
    2  GND                B  @BASEBOARD_FAB2_LIB.BASEBOARD_FAB2(SCH_1):GND

CAP_A  I205  C5A17  [CAP_A_0603V-22.0UF,4V,20%,X6S,A]
    1  PVDDQ_DEF          A  @BASEBOARD_FAB2_LIB.BASEBOARD_FAB2(SCH_1):PVDDQ_DEF
    2  GND                B  @BASEBOARD_FAB2_LIB.BASEBOARD_FAB2(SCH_1):GND

CAP_A  I204  C5A18  [CAP_A_0603V-22.0UF,4V,20%,X6S,A]
    1  PVDDQ_DEF          A  @BASEBOARD_FAB2_LIB.BASEBOARD_FAB2(SCH_1):PVDDQ_DEF
    2  GND                B  @BASEBOARD_FAB2_LIB.BASEBOARD_FAB2(SCH_1):GND

CAP_A  I203  C5A19  [CAP_A_0603V-22.0UF,4V,20%,X6S,A]
    1  PVDDQ_DEF          A  @BASEBOARD_FAB2_LIB.BASEBOARD_FAB2(SCH_1):PVDDQ_DEF
    2  GND                B  @BASEBOARD_FAB2_LIB.BASEBOARD_FAB2(SCH_1):GND

CAP  I92  C5A20  [CAP_0805-100UF,4V,20%,X5R,6024A]
    1  PVDDQ_DEF          A  @BASEBOARD_FAB2_LIB.BASEBOARD_FAB2(SCH_1):PVDDQ_DEF
    2  GND                B  @BASEBOARD_FAB2_LIB.BASEBOARD_FAB2(SCH_1):GND

CAP_A  I194  C5B1   [CAP_A_0603V-47UF,4V,20%,X5R,60A]
    1  PVDDQ_DEF          A  @BASEBOARD_FAB2_LIB.BASEBOARD_FAB2(SCH_1):PVDDQ_DEF
    2  GND                B  @BASEBOARD_FAB2_LIB.BASEBOARD_FAB2(SCH_1):GND

CAP_A  I197  C5B2   [CAP_A_0603V-47UF,4V,20%,X5R,60A]
    1  PVDDQ_DEF          A  @BASEBOARD_FAB2_LIB.BASEBOARD_FAB2(SCH_1):PVDDQ_DEF
    2  GND                B  @BASEBOARD_FAB2_LIB.BASEBOARD_FAB2(SCH_1):GND

CAP_A  I126  C5D1   [CAP_A_0603V-22.0UF,4V,20%,X6S,A]
    1  PVCCIN_CPU0        A  @BASEBOARD_FAB2_LIB.BASEBOARD_FAB2(SCH_1):PVCCIN_CPU0
    2  GND                B  @BASEBOARD_FAB2_LIB.BASEBOARD_FAB2(SCH_1):GND

CAP_A  I136  C5D2   [CAP_A_0603V-22.0UF,4V,20%,X6S,A]
    1  PVCCIN_CPU0        A  @BASEBOARD_FAB2_LIB.BASEBOARD_FAB2(SCH_1):PVCCIN_CPU0
    2  GND                B  @BASEBOARD_FAB2_LIB.BASEBOARD_FAB2(SCH_1):GND

CAP_A  I130  C5D3   [CAP_A_0603V-22.0UF,4V,20%,X6S,A]
    1  PVCCIN_CPU0        A  @BASEBOARD_FAB2_LIB.BASEBOARD_FAB2(SCH_1):PVCCIN_CPU0
    2  GND                B  @BASEBOARD_FAB2_LIB.BASEBOARD_FAB2(SCH_1):GND

CAP_A  I127  C5D4   [CAP_A_0603V-22.0UF,4V,20%,X6S,A]
    1  PVCCIN_CPU0        A  @BASEBOARD_FAB2_LIB.BASEBOARD_FAB2(SCH_1):PVCCIN_CPU0
    2  GND                B  @BASEBOARD_FAB2_LIB.BASEBOARD_FAB2(SCH_1):GND

CAP_A  I125  C5D5   [CAP_A_0603V-22.0UF,4V,20%,X6S,A]
    1  PVCCIN_CPU0        A  @BASEBOARD_FAB2_LIB.BASEBOARD_FAB2(SCH_1):PVCCIN_CPU0
    2  GND                B  @BASEBOARD_FAB2_LIB.BASEBOARD_FAB2(SCH_1):GND

CAP  I182  C5D6   [CAP_0603LF-10UF,4V,20%,X6S,E15A]
    1  PVDDQ_DEF          A  @BASEBOARD_FAB2_LIB.BASEBOARD_FAB2(SCH_1):PVDDQ_DEF
    2  GND                B  @BASEBOARD_FAB2_LIB.BASEBOARD_FAB2(SCH_1):GND

CAP  I183  C5D7   [CAP_0603LF-10UF,4V,20%,X6S,E15A]
    1  PVDDQ_DEF          A  @BASEBOARD_FAB2_LIB.BASEBOARD_FAB2(SCH_1):PVDDQ_DEF
    2  GND                B  @BASEBOARD_FAB2_LIB.BASEBOARD_FAB2(SCH_1):GND

CAP  I184  C5D8   [CAP_0603LF-10UF,4V,20%,X6S,E15A]
    1  PVDDQ_DEF          A  @BASEBOARD_FAB2_LIB.BASEBOARD_FAB2(SCH_1):PVDDQ_DEF
    2  GND                B  @BASEBOARD_FAB2_LIB.BASEBOARD_FAB2(SCH_1):GND

CAP  I180  C5D9   [CAP_0603LF-10UF,4V,20%,X6S,E15A]
    1  PVDDQ_DEF          A  @BASEBOARD_FAB2_LIB.BASEBOARD_FAB2(SCH_1):PVDDQ_DEF
    2  GND                B  @BASEBOARD_FAB2_LIB.BASEBOARD_FAB2(SCH_1):GND

CAP  I108  C5D10  [CAP_0603LF-10UF,4V,20%,X6S,E15A]
    1  PVSA_CPU0          A  @BASEBOARD_FAB2_LIB.BASEBOARD_FAB2(SCH_1):PVSA_CPU0
    2  GND                B  @BASEBOARD_FAB2_LIB.BASEBOARD_FAB2(SCH_1):GND

CAP  I93  C5D11  [CAP_0603LF-10UF,4V,20%,X6S,E15A]
    1  PVSA_CPU0          A  @BASEBOARD_FAB2_LIB.BASEBOARD_FAB2(SCH_1):PVSA_CPU0
    2  GND                B  @BASEBOARD_FAB2_LIB.BASEBOARD_FAB2(SCH_1):GND

CAP  I94  C5D12  [CAP_0603LF-10UF,4V,20%,X6S,E15A]
    1  PVSA_CPU0          A  @BASEBOARD_FAB2_LIB.BASEBOARD_FAB2(SCH_1):PVSA_CPU0
    2  GND                B  @BASEBOARD_FAB2_LIB.BASEBOARD_FAB2(SCH_1):GND

CAP  I91  C5D13  [CAP_0603LF-10UF,4V,20%,X6S,E15A]
    1  PVSA_CPU0          A  @BASEBOARD_FAB2_LIB.BASEBOARD_FAB2(SCH_1):PVSA_CPU0
    2  GND                B  @BASEBOARD_FAB2_LIB.BASEBOARD_FAB2(SCH_1):GND

CAP_A  I117  C5D14  [CAP_A_0603V-22.0UF,4V,20%,X6S,A]
    1  PVCCIN_CPU0        A  @BASEBOARD_FAB2_LIB.BASEBOARD_FAB2(SCH_1):PVCCIN_CPU0
    2  GND                B  @BASEBOARD_FAB2_LIB.BASEBOARD_FAB2(SCH_1):GND

CAP_A  I132  C5D15  [CAP_A_0603V-22.0UF,4V,20%,X6S,A]
    1  PVCCIN_CPU0        A  @BASEBOARD_FAB2_LIB.BASEBOARD_FAB2(SCH_1):PVCCIN_CPU0
    2  GND                B  @BASEBOARD_FAB2_LIB.BASEBOARD_FAB2(SCH_1):GND

CAP_A  I123  C5D16  [CAP_A_0603V-22.0UF,4V,20%,X6S,A]
    1  PVCCIN_CPU0        A  @BASEBOARD_FAB2_LIB.BASEBOARD_FAB2(SCH_1):PVCCIN_CPU0
    2  GND                B  @BASEBOARD_FAB2_LIB.BASEBOARD_FAB2(SCH_1):GND

CAP_A  I118  C5D17  [CAP_A_0603V-22.0UF,4V,20%,X6S,A]
    1  PVCCIN_CPU0        A  @BASEBOARD_FAB2_LIB.BASEBOARD_FAB2(SCH_1):PVCCIN_CPU0
    2  GND                B  @BASEBOARD_FAB2_LIB.BASEBOARD_FAB2(SCH_1):GND

CAP_A  I134  C5D18  [CAP_A_0603V-22.0UF,4V,20%,X6S,A]
    1  PVCCIN_CPU0        A  @BASEBOARD_FAB2_LIB.BASEBOARD_FAB2(SCH_1):PVCCIN_CPU0
    2  GND                B  @BASEBOARD_FAB2_LIB.BASEBOARD_FAB2(SCH_1):GND

CAP_A  I128  C5D19  [CAP_A_0603V-22.0UF,4V,20%,X6S,A]
    1  PVCCIN_CPU0        A  @BASEBOARD_FAB2_LIB.BASEBOARD_FAB2(SCH_1):PVCCIN_CPU0
    2  GND                B  @BASEBOARD_FAB2_LIB.BASEBOARD_FAB2(SCH_1):GND

CAP_A  I173  C5D20  [CAP_A_0603V-22.0UF,4V,20%,X6S,A]
    1  PVCCMCP_CPU0       A  @BASEBOARD_FAB2_LIB.BASEBOARD_FAB2(SCH_1):PVCCMCP_CPU0
    2  GND                B  @BASEBOARD_FAB2_LIB.BASEBOARD_FAB2(SCH_1):GND

CAP_A  I88  C5D21  [CAP_A_0603V-22.0UF,4V,20%,X6S,A]
    1  PVCCMCP_CPU0       A  @BASEBOARD_FAB2_LIB.BASEBOARD_FAB2(SCH_1):PVCCMCP_CPU0
    2  GND                B  @BASEBOARD_FAB2_LIB.BASEBOARD_FAB2(SCH_1):GND

CAP_A  I153  C5D22  [CAP_A_0603V-22.0UF,4V,20%,X6S,A]
    1  PVCCMCP_CPU0       A  @BASEBOARD_FAB2_LIB.BASEBOARD_FAB2(SCH_1):PVCCMCP_CPU0
    2  GND                B  @BASEBOARD_FAB2_LIB.BASEBOARD_FAB2(SCH_1):GND

CAP_A  I98  C5D23  [CAP_A_0603V-22.0UF,4V,20%,X6S,A]
    1  PVCCMCP_CPU0       A  @BASEBOARD_FAB2_LIB.BASEBOARD_FAB2(SCH_1):PVCCMCP_CPU0
    2  GND                B  @BASEBOARD_FAB2_LIB.BASEBOARD_FAB2(SCH_1):GND

CAP_A  I138  C5D24  [CAP_A_0603V-22.0UF,4V,20%,X6S,A]
    1  PVCCIN_CPU0        A  @BASEBOARD_FAB2_LIB.BASEBOARD_FAB2(SCH_1):PVCCIN_CPU0
    2  GND                B  @BASEBOARD_FAB2_LIB.BASEBOARD_FAB2(SCH_1):GND

CAP_A  I155  C5D25  [CAP_A_0603V-22.0UF,4V,20%,X6S,A]
    1  PVCCIN_CPU0        A  @BASEBOARD_FAB2_LIB.BASEBOARD_FAB2(SCH_1):PVCCIN_CPU0
    2  GND                B  @BASEBOARD_FAB2_LIB.BASEBOARD_FAB2(SCH_1):GND

CAP_A  I154  C5D26  [CAP_A_0603V-22.0UF,4V,20%,X6S,A]
    1  PVCCIN_CPU0        A  @BASEBOARD_FAB2_LIB.BASEBOARD_FAB2(SCH_1):PVCCIN_CPU0
    2  GND                B  @BASEBOARD_FAB2_LIB.BASEBOARD_FAB2(SCH_1):GND

CAP_A  I109  C5D27  [CAP_A_0603V-22.0UF,4V,20%,X6S,A]
    1  PVCCIN_CPU0        A  @BASEBOARD_FAB2_LIB.BASEBOARD_FAB2(SCH_1):PVCCIN_CPU0
    2  GND                B  @BASEBOARD_FAB2_LIB.BASEBOARD_FAB2(SCH_1):GND

CAP_A  I100  C5D28  [CAP_A_0603V-22.0UF,4V,20%,X6S,A]
    1  PVCCIN_CPU0        A  @BASEBOARD_FAB2_LIB.BASEBOARD_FAB2(SCH_1):PVCCIN_CPU0
    2  GND                B  @BASEBOARD_FAB2_LIB.BASEBOARD_FAB2(SCH_1):GND

CAP_A  I102  C5D29  [CAP_A_0603V-22.0UF,4V,20%,X6S,A]
    1  PVCCIN_CPU0        A  @BASEBOARD_FAB2_LIB.BASEBOARD_FAB2(SCH_1):PVCCIN_CPU0
    2  GND                B  @BASEBOARD_FAB2_LIB.BASEBOARD_FAB2(SCH_1):GND

CAP_A  I111  C5D30  [CAP_A_0603V-22.0UF,4V,20%,X6S,A]
    1  PVCCIN_CPU0        A  @BASEBOARD_FAB2_LIB.BASEBOARD_FAB2(SCH_1):PVCCIN_CPU0
    2  GND                B  @BASEBOARD_FAB2_LIB.BASEBOARD_FAB2(SCH_1):GND

CAP_A  I106  C5D31  [CAP_A_0603V-22.0UF,4V,20%,X6S,A]
    1  PVCCIN_CPU0        A  @BASEBOARD_FAB2_LIB.BASEBOARD_FAB2(SCH_1):PVCCIN_CPU0
    2  GND                B  @BASEBOARD_FAB2_LIB.BASEBOARD_FAB2(SCH_1):GND

CAP_A  I103  C5D32  [CAP_A_0603V-22.0UF,4V,20%,X6S,A]
    1  PVCCIN_CPU0        A  @BASEBOARD_FAB2_LIB.BASEBOARD_FAB2(SCH_1):PVCCIN_CPU0
    2  GND                B  @BASEBOARD_FAB2_LIB.BASEBOARD_FAB2(SCH_1):GND

CAP_A  I174  C5D33  [CAP_A_0603V-22.0UF,4V,20%,X6S,A]
    1  PVCCMCP_CPU0       A  @BASEBOARD_FAB2_LIB.BASEBOARD_FAB2(SCH_1):PVCCMCP_CPU0
    2  GND                B  @BASEBOARD_FAB2_LIB.BASEBOARD_FAB2(SCH_1):GND

CAP_A  I175  C5D34  [CAP_A_0603V-22.0UF,4V,20%,X6S,A]
    1  PVCCMCP_CPU0       A  @BASEBOARD_FAB2_LIB.BASEBOARD_FAB2(SCH_1):PVCCMCP_CPU0
    2  GND                B  @BASEBOARD_FAB2_LIB.BASEBOARD_FAB2(SCH_1):GND

CAP_A  I176  C5D35  [CAP_A_0603V-22.0UF,4V,20%,X6S,A]
    1  PVCCMCP_CPU0       A  @BASEBOARD_FAB2_LIB.BASEBOARD_FAB2(SCH_1):PVCCMCP_CPU0
    2  GND                B  @BASEBOARD_FAB2_LIB.BASEBOARD_FAB2(SCH_1):GND

CAP_A  I151  C5D36  [CAP_A_0603V-22.0UF,4V,20%,X6S,A]
    1  PVCCMCP_CPU0       A  @BASEBOARD_FAB2_LIB.BASEBOARD_FAB2(SCH_1):PVCCMCP_CPU0
    2  GND                B  @BASEBOARD_FAB2_LIB.BASEBOARD_FAB2(SCH_1):GND

CAP_A  I70  C5D37  [CAP_A_0603V-22.0UF,4V,20%,X6S,A]
    1  PVCCMCP_CPU0       A  @BASEBOARD_FAB2_LIB.BASEBOARD_FAB2(SCH_1):PVCCMCP_CPU0
    2  GND                B  @BASEBOARD_FAB2_LIB.BASEBOARD_FAB2(SCH_1):GND

CAP_A  I69  C5D38  [CAP_A_0603V-22.0UF,4V,20%,X6S,A]
    1  PVCCMCP_CPU0       A  @BASEBOARD_FAB2_LIB.BASEBOARD_FAB2(SCH_1):PVCCMCP_CPU0
    2  GND                B  @BASEBOARD_FAB2_LIB.BASEBOARD_FAB2(SCH_1):GND

CAP_A  I140  C5D39  [CAP_A_0603V-22.0UF,4V,20%,X6S,A]
    1  PVCCIN_CPU0        A  @BASEBOARD_FAB2_LIB.BASEBOARD_FAB2(SCH_1):PVCCIN_CPU0
    2  GND                B  @BASEBOARD_FAB2_LIB.BASEBOARD_FAB2(SCH_1):GND

CAP_A  I115  C5D40  [CAP_A_0603V-22.0UF,4V,20%,X6S,A]
    1  PVCCIN_CPU0        A  @BASEBOARD_FAB2_LIB.BASEBOARD_FAB2(SCH_1):PVCCIN_CPU0
    2  GND                B  @BASEBOARD_FAB2_LIB.BASEBOARD_FAB2(SCH_1):GND

CAP_A  I114  C5D41  [CAP_A_0603V-22.0UF,4V,20%,X6S,A]
    1  PVCCIN_CPU0        A  @BASEBOARD_FAB2_LIB.BASEBOARD_FAB2(SCH_1):PVCCIN_CPU0
    2  GND                B  @BASEBOARD_FAB2_LIB.BASEBOARD_FAB2(SCH_1):GND

CAP_A  I135  C5D42  [CAP_A_0603V-22.0UF,4V,20%,X6S,A]
    1  PVCCIN_CPU0        A  @BASEBOARD_FAB2_LIB.BASEBOARD_FAB2(SCH_1):PVCCIN_CPU0
    2  GND                B  @BASEBOARD_FAB2_LIB.BASEBOARD_FAB2(SCH_1):GND

CAP_A  I131  C5D43  [CAP_A_0603V-22.0UF,4V,20%,X6S,A]
    1  PVCCIN_CPU0        A  @BASEBOARD_FAB2_LIB.BASEBOARD_FAB2(SCH_1):PVCCIN_CPU0
    2  GND                B  @BASEBOARD_FAB2_LIB.BASEBOARD_FAB2(SCH_1):GND

CAP_A  I142  C5D44  [CAP_A_0603V-22.0UF,4V,20%,X6S,A]
    1  PVCCIN_CPU0        A  @BASEBOARD_FAB2_LIB.BASEBOARD_FAB2(SCH_1):PVCCIN_CPU0
    2  GND                B  @BASEBOARD_FAB2_LIB.BASEBOARD_FAB2(SCH_1):GND

CAP_A  I156  C5D45  [CAP_A_0603V-22.0UF,4V,20%,X6S,A]
    1  PVCCIN_CPU0        A  @BASEBOARD_FAB2_LIB.BASEBOARD_FAB2(SCH_1):PVCCIN_CPU0
    2  GND                B  @BASEBOARD_FAB2_LIB.BASEBOARD_FAB2(SCH_1):GND

CAP_A  I107  C5D46  [CAP_A_0603V-22.0UF,4V,20%,X6S,A]
    1  PVCCIN_CPU0        A  @BASEBOARD_FAB2_LIB.BASEBOARD_FAB2(SCH_1):PVCCIN_CPU0
    2  GND                B  @BASEBOARD_FAB2_LIB.BASEBOARD_FAB2(SCH_1):GND

CAP_A  I104  C5D47  [CAP_A_0603V-22.0UF,4V,20%,X6S,A]
    1  PVCCIN_CPU0        A  @BASEBOARD_FAB2_LIB.BASEBOARD_FAB2(SCH_1):PVCCIN_CPU0
    2  GND                B  @BASEBOARD_FAB2_LIB.BASEBOARD_FAB2(SCH_1):GND

CAP_A  I90  C5D48  [CAP_A_0603V-22.0UF,4V,20%,X6S,A]
    1  PVCCMCP_CPU0       A  @BASEBOARD_FAB2_LIB.BASEBOARD_FAB2(SCH_1):PVCCMCP_CPU0
    2  GND                B  @BASEBOARD_FAB2_LIB.BASEBOARD_FAB2(SCH_1):GND

CAP_A  I152  C5D49  [CAP_A_0603V-22.0UF,4V,20%,X6S,A]
    1  PVCCMCP_CPU0       A  @BASEBOARD_FAB2_LIB.BASEBOARD_FAB2(SCH_1):PVCCMCP_CPU0
    2  GND                B  @BASEBOARD_FAB2_LIB.BASEBOARD_FAB2(SCH_1):GND

CAP_A  I89  C5D50  [CAP_A_0603V-22.0UF,4V,20%,X6S,A]
    1  PVCCMCP_CPU0       A  @BASEBOARD_FAB2_LIB.BASEBOARD_FAB2(SCH_1):PVCCMCP_CPU0
    2  GND                B  @BASEBOARD_FAB2_LIB.BASEBOARD_FAB2(SCH_1):GND

CAP_A  I83  C5D51  [CAP_A_0603V-22.0UF,4V,20%,X6S,A]
    1  PVCCMCP_CPU0       A  @BASEBOARD_FAB2_LIB.BASEBOARD_FAB2(SCH_1):PVCCMCP_CPU0
    2  GND                B  @BASEBOARD_FAB2_LIB.BASEBOARD_FAB2(SCH_1):GND

CAP_A  I180  C5D52  [CAP_A_0603V-22.0UF,4V,20%,X6S,A]
    1  PVCCMCP_CPU0       A  @BASEBOARD_FAB2_LIB.BASEBOARD_FAB2(SCH_1):PVCCMCP_CPU0
    2  GND                B  @BASEBOARD_FAB2_LIB.BASEBOARD_FAB2(SCH_1):GND

CAP_A  I179  C5D53  [CAP_A_0603V-22.0UF,4V,20%,X6S,A]
    1  PVCCMCP_CPU0       A  @BASEBOARD_FAB2_LIB.BASEBOARD_FAB2(SCH_1):PVCCMCP_CPU0
    2  GND                B  @BASEBOARD_FAB2_LIB.BASEBOARD_FAB2(SCH_1):GND

CAP  I190  C5D54  [CAP_0603LF-10UF,4V,20%,X6S,E15A]
    1  PVDDQ_ABC          A  @BASEBOARD_FAB2_LIB.BASEBOARD_FAB2(SCH_1):PVDDQ_ABC
    2  GND                B  @BASEBOARD_FAB2_LIB.BASEBOARD_FAB2(SCH_1):GND

CAP  I189  C5D55  [CAP_0603LF-10UF,4V,20%,X6S,E15A]
    1  PVDDQ_ABC          A  @BASEBOARD_FAB2_LIB.BASEBOARD_FAB2(SCH_1):PVDDQ_ABC
    2  GND                B  @BASEBOARD_FAB2_LIB.BASEBOARD_FAB2(SCH_1):GND

CAP  I188  C5D56  [CAP_0603LF-10UF,4V,20%,X6S,E15A]
    1  PVDDQ_ABC          A  @BASEBOARD_FAB2_LIB.BASEBOARD_FAB2(SCH_1):PVDDQ_ABC
    2  GND                B  @BASEBOARD_FAB2_LIB.BASEBOARD_FAB2(SCH_1):GND

CAP  I186  C5D57  [CAP_0603LF-10UF,4V,20%,X6S,E15A]
    1  PVDDQ_ABC          A  @BASEBOARD_FAB2_LIB.BASEBOARD_FAB2(SCH_1):PVDDQ_ABC
    2  GND                B  @BASEBOARD_FAB2_LIB.BASEBOARD_FAB2(SCH_1):GND

CAP_A  I120  C5D58  [CAP_A_0603V-22.0UF,4V,20%,X6S,A]
    1  PVCCIN_CPU0        A  @BASEBOARD_FAB2_LIB.BASEBOARD_FAB2(SCH_1):PVCCIN_CPU0
    2  GND                B  @BASEBOARD_FAB2_LIB.BASEBOARD_FAB2(SCH_1):GND

CAP_A  I129  C5D59  [CAP_A_0603V-22.0UF,4V,20%,X6S,A]
    1  PVCCIN_CPU0        A  @BASEBOARD_FAB2_LIB.BASEBOARD_FAB2(SCH_1):PVCCIN_CPU0
    2  GND                B  @BASEBOARD_FAB2_LIB.BASEBOARD_FAB2(SCH_1):GND

CAP_A  I112  C5D60  [CAP_A_0603V-22.0UF,4V,20%,X6S,A]
    1  PVCCIN_CPU0        A  @BASEBOARD_FAB2_LIB.BASEBOARD_FAB2(SCH_1):PVCCIN_CPU0
    2  GND                B  @BASEBOARD_FAB2_LIB.BASEBOARD_FAB2(SCH_1):GND

CAP_A  I113  C5D61  [CAP_A_0603V-22.0UF,4V,20%,X6S,A]
    1  PVCCIN_CPU0        A  @BASEBOARD_FAB2_LIB.BASEBOARD_FAB2(SCH_1):PVCCIN_CPU0
    2  GND                B  @BASEBOARD_FAB2_LIB.BASEBOARD_FAB2(SCH_1):GND

CAP_A  I206  C5F1   [CAP_A_0603V-47UF,4V,20%,X5R,60A]
    1  PVDDQ_ABC          A  @BASEBOARD_FAB2_LIB.BASEBOARD_FAB2(SCH_1):PVDDQ_ABC
    2  GND                B  @BASEBOARD_FAB2_LIB.BASEBOARD_FAB2(SCH_1):GND

CAP_A  I205  C5F2   [CAP_A_0603V-47UF,4V,20%,X5R,60A]
    1  PVDDQ_ABC          A  @BASEBOARD_FAB2_LIB.BASEBOARD_FAB2(SCH_1):PVDDQ_ABC
    2  GND                B  @BASEBOARD_FAB2_LIB.BASEBOARD_FAB2(SCH_1):GND

CAP_A  I231  C5G1   [CAP_A_0603V-22.0UF,4V,20%,X6S,A]
    1  PVDDQ_ABC          A  @BASEBOARD_FAB2_LIB.BASEBOARD_FAB2(SCH_1):PVDDQ_ABC
    2  GND                B  @BASEBOARD_FAB2_LIB.BASEBOARD_FAB2(SCH_1):GND

CAP_A  I245  C5G2   [CAP_A_0603V-22.0UF,4V,20%,X6S,A]
    1  PVDDQ_ABC          A  @BASEBOARD_FAB2_LIB.BASEBOARD_FAB2(SCH_1):PVDDQ_ABC
    2  GND                B  @BASEBOARD_FAB2_LIB.BASEBOARD_FAB2(SCH_1):GND

CAP_A  I217  C5G3   [CAP_A_0603V-22.0UF,4V,20%,X6S,A]
    1  PVDDQ_ABC          A  @BASEBOARD_FAB2_LIB.BASEBOARD_FAB2(SCH_1):PVDDQ_ABC
    2  GND                B  @BASEBOARD_FAB2_LIB.BASEBOARD_FAB2(SCH_1):GND

CAP_A  I241  C5G4   [CAP_A_0603V-22.0UF,4V,20%,X6S,A]
    1  PVDDQ_ABC          A  @BASEBOARD_FAB2_LIB.BASEBOARD_FAB2(SCH_1):PVDDQ_ABC
    2  GND                B  @BASEBOARD_FAB2_LIB.BASEBOARD_FAB2(SCH_1):GND

CAP_A  I235  C5G5   [CAP_A_0603V-22.0UF,4V,20%,X6S,A]
    1  PVDDQ_ABC          A  @BASEBOARD_FAB2_LIB.BASEBOARD_FAB2(SCH_1):PVDDQ_ABC
    2  GND                B  @BASEBOARD_FAB2_LIB.BASEBOARD_FAB2(SCH_1):GND

CAP_A  I237  C5G6   [CAP_A_0603V-22.0UF,4V,20%,X6S,A]
    1  PVDDQ_ABC          A  @BASEBOARD_FAB2_LIB.BASEBOARD_FAB2(SCH_1):PVDDQ_ABC
    2  GND                B  @BASEBOARD_FAB2_LIB.BASEBOARD_FAB2(SCH_1):GND

CAP_A  I234  C5G7   [CAP_A_0603V-22.0UF,4V,20%,X6S,A]
    1  PVDDQ_ABC          A  @BASEBOARD_FAB2_LIB.BASEBOARD_FAB2(SCH_1):PVDDQ_ABC
    2  GND                B  @BASEBOARD_FAB2_LIB.BASEBOARD_FAB2(SCH_1):GND

CAP_A  I230  C5G8   [CAP_A_0603V-22.0UF,4V,20%,X6S,A]
    1  PVDDQ_ABC          A  @BASEBOARD_FAB2_LIB.BASEBOARD_FAB2(SCH_1):PVDDQ_ABC
    2  GND                B  @BASEBOARD_FAB2_LIB.BASEBOARD_FAB2(SCH_1):GND

CAP  I92  C5G9   [CAP_0805-100UF,4V,20%,X5R,6024A]
    1  PVDDQ_ABC          A  @BASEBOARD_FAB2_LIB.BASEBOARD_FAB2(SCH_1):PVDDQ_ABC
    2  GND                B  @BASEBOARD_FAB2_LIB.BASEBOARD_FAB2(SCH_1):GND

CAP_A  I207  C5G10  [CAP_A_0603V-47UF,4V,20%,X5R,60A]
    1  PVDDQ_ABC          A  @BASEBOARD_FAB2_LIB.BASEBOARD_FAB2(SCH_1):PVDDQ_ABC
    2  GND                B  @BASEBOARD_FAB2_LIB.BASEBOARD_FAB2(SCH_1):GND

CAP_A  I250  C5G11  [CAP_A_0603V-22.0UF,4V,20%,X6S,A]
    1  PVDDQ_ABC          A  @BASEBOARD_FAB2_LIB.BASEBOARD_FAB2(SCH_1):PVDDQ_ABC
    2  GND                B  @BASEBOARD_FAB2_LIB.BASEBOARD_FAB2(SCH_1):GND

CAP_A  I246  C5G12  [CAP_A_0603V-22.0UF,4V,20%,X6S,A]
    1  PVDDQ_ABC          A  @BASEBOARD_FAB2_LIB.BASEBOARD_FAB2(SCH_1):PVDDQ_ABC
    2  GND                B  @BASEBOARD_FAB2_LIB.BASEBOARD_FAB2(SCH_1):GND

CAP_A  I240  C5G13  [CAP_A_0603V-22.0UF,4V,20%,X6S,A]
    1  PVDDQ_ABC          A  @BASEBOARD_FAB2_LIB.BASEBOARD_FAB2(SCH_1):PVDDQ_ABC
    2  GND                B  @BASEBOARD_FAB2_LIB.BASEBOARD_FAB2(SCH_1):GND

CAP_A  I223  C5G14  [CAP_A_0603V-22.0UF,4V,20%,X6S,A]
    1  PVDDQ_ABC          A  @BASEBOARD_FAB2_LIB.BASEBOARD_FAB2(SCH_1):PVDDQ_ABC
    2  GND                B  @BASEBOARD_FAB2_LIB.BASEBOARD_FAB2(SCH_1):GND

CAP_A  I220  C5G15  [CAP_A_0603V-22.0UF,4V,20%,X6S,A]
    1  PVDDQ_ABC          A  @BASEBOARD_FAB2_LIB.BASEBOARD_FAB2(SCH_1):PVDDQ_ABC
    2  GND                B  @BASEBOARD_FAB2_LIB.BASEBOARD_FAB2(SCH_1):GND

CAP_A  I221  C5G16  [CAP_A_0603V-22.0UF,4V,20%,X6S,A]
    1  PVDDQ_ABC          A  @BASEBOARD_FAB2_LIB.BASEBOARD_FAB2(SCH_1):PVDDQ_ABC
    2  GND                B  @BASEBOARD_FAB2_LIB.BASEBOARD_FAB2(SCH_1):GND

CAP_A  I226  C5G17  [CAP_A_0603V-22.0UF,4V,20%,X6S,A]
    1  PVDDQ_ABC          A  @BASEBOARD_FAB2_LIB.BASEBOARD_FAB2(SCH_1):PVDDQ_ABC
    2  GND                B  @BASEBOARD_FAB2_LIB.BASEBOARD_FAB2(SCH_1):GND

CAP_A  I227  C5G18  [CAP_A_0603V-22.0UF,4V,20%,X6S,A]
    1  PVDDQ_ABC          A  @BASEBOARD_FAB2_LIB.BASEBOARD_FAB2(SCH_1):PVDDQ_ABC
    2  GND                B  @BASEBOARD_FAB2_LIB.BASEBOARD_FAB2(SCH_1):GND

CAP_A  I213  C5G19  [CAP_A_0603V-47UF,4V,20%,X5R,60A]
    1  PVDDQ_ABC          A  @BASEBOARD_FAB2_LIB.BASEBOARD_FAB2(SCH_1):PVDDQ_ABC
    2  GND                B  @BASEBOARD_FAB2_LIB.BASEBOARD_FAB2(SCH_1):GND

CAP  I110  C5G20  [CAP_0805-100UF,4V,20%,X5R,6024A]
    1  PVDDQ_ABC          A  @BASEBOARD_FAB2_LIB.BASEBOARD_FAB2(SCH_1):PVDDQ_ABC
    2  GND                B  @BASEBOARD_FAB2_LIB.BASEBOARD_FAB2(SCH_1):GND

CAP  I11  C5G21  [CAP_0805-100UF,4V,20%,X5R,6024A]
    1  PVDDQ_ABC          A  @BASEBOARD_FAB2_LIB.BASEBOARD_FAB2(SCH_1):PVDDQ_ABC
    2  GND                B  @BASEBOARD_FAB2_LIB.BASEBOARD_FAB2(SCH_1):GND

CAP  I15  C5G22  [CAP_0805-100UF,4V,20%,X5R,6024A]
    1  PVDDQ_ABC          A  @BASEBOARD_FAB2_LIB.BASEBOARD_FAB2(SCH_1):PVDDQ_ABC
    2  GND                B  @BASEBOARD_FAB2_LIB.BASEBOARD_FAB2(SCH_1):GND

CAP_A  I53  C5G41  [CAP_A_0603V-22.0UF,4V,20%,X6S,A]
    1  PVDDQ_ABC          A  @BASEBOARD_FAB2_LIB.BASEBOARD_FAB2(SCH_1):PVDDQ_ABC
    2  GND                B  @BASEBOARD_FAB2_LIB.BASEBOARD_FAB2(SCH_1):GND

CAP_A  I54  C5G42  [CAP_A_0603V-22.0UF,4V,20%,X6S,A]
    1  PVDDQ_ABC          A  @BASEBOARD_FAB2_LIB.BASEBOARD_FAB2(SCH_1):PVDDQ_ABC
    2  GND                B  @BASEBOARD_FAB2_LIB.BASEBOARD_FAB2(SCH_1):GND

CAP_A  I56  C5G43  [CAP_A_0603V-22.0UF,4V,20%,X6S,A]
    1  PVDDQ_ABC          A  @BASEBOARD_FAB2_LIB.BASEBOARD_FAB2(SCH_1):PVDDQ_ABC
    2  GND                B  @BASEBOARD_FAB2_LIB.BASEBOARD_FAB2(SCH_1):GND

CAP_A  I55  C5G44  [CAP_A_0603V-22.0UF,4V,20%,X6S,A]
    1  PVDDQ_ABC          A  @BASEBOARD_FAB2_LIB.BASEBOARD_FAB2(SCH_1):PVDDQ_ABC
    2  GND                B  @BASEBOARD_FAB2_LIB.BASEBOARD_FAB2(SCH_1):GND

CAP_A  I60  C5G45  [CAP_A_0603V-22.0UF,4V,20%,X6S,A]
    1  PVDDQ_ABC          A  @BASEBOARD_FAB2_LIB.BASEBOARD_FAB2(SCH_1):PVDDQ_ABC
    2  GND                B  @BASEBOARD_FAB2_LIB.BASEBOARD_FAB2(SCH_1):GND

CAP_A  I59  C5G46  [CAP_A_0603V-22.0UF,4V,20%,X6S,A]
    1  PVDDQ_ABC          A  @BASEBOARD_FAB2_LIB.BASEBOARD_FAB2(SCH_1):PVDDQ_ABC
    2  GND                B  @BASEBOARD_FAB2_LIB.BASEBOARD_FAB2(SCH_1):GND

CAP_A  I58  C5G47  [CAP_A_0603V-22.0UF,4V,20%,X6S,A]
    1  PVDDQ_ABC          A  @BASEBOARD_FAB2_LIB.BASEBOARD_FAB2(SCH_1):PVDDQ_ABC
    2  GND                B  @BASEBOARD_FAB2_LIB.BASEBOARD_FAB2(SCH_1):GND

CAP_A  I57  C5G48  [CAP_A_0603V-22.0UF,4V,20%,X6S,A]
    1  PVDDQ_ABC          A  @BASEBOARD_FAB2_LIB.BASEBOARD_FAB2(SCH_1):PVDDQ_ABC
    2  GND                B  @BASEBOARD_FAB2_LIB.BASEBOARD_FAB2(SCH_1):GND

CAP_A  I61  C5G49  [CAP_A_0603V-22.0UF,4V,20%,X6S,A]
    1  PVDDQ_ABC          A  @BASEBOARD_FAB2_LIB.BASEBOARD_FAB2(SCH_1):PVDDQ_ABC
    2  GND                B  @BASEBOARD_FAB2_LIB.BASEBOARD_FAB2(SCH_1):GND

CAP_A  I70  C5G50  [CAP_A_0603V-22.0UF,4V,20%,X6S,A]
    1  PVDDQ_ABC          A  @BASEBOARD_FAB2_LIB.BASEBOARD_FAB2(SCH_1):PVDDQ_ABC
    2  GND                B  @BASEBOARD_FAB2_LIB.BASEBOARD_FAB2(SCH_1):GND

CAP_A  I69  C5G51  [CAP_A_0603V-22.0UF,4V,20%,X6S,A]
    1  PVDDQ_ABC          A  @BASEBOARD_FAB2_LIB.BASEBOARD_FAB2(SCH_1):PVDDQ_ABC
    2  GND                B  @BASEBOARD_FAB2_LIB.BASEBOARD_FAB2(SCH_1):GND

CAP_A  I68  C5G52  [CAP_A_0603V-22.0UF,4V,20%,X6S,A]
    1  PVDDQ_ABC          A  @BASEBOARD_FAB2_LIB.BASEBOARD_FAB2(SCH_1):PVDDQ_ABC
    2  GND                B  @BASEBOARD_FAB2_LIB.BASEBOARD_FAB2(SCH_1):GND

CAP_A  I67  C5G53  [CAP_A_0603V-22.0UF,4V,20%,X6S,A]
    1  PVDDQ_ABC          A  @BASEBOARD_FAB2_LIB.BASEBOARD_FAB2(SCH_1):PVDDQ_ABC
    2  GND                B  @BASEBOARD_FAB2_LIB.BASEBOARD_FAB2(SCH_1):GND

CAP_A  I62  C5G54  [CAP_A_0603V-22.0UF,4V,20%,X6S,A]
    1  PVDDQ_ABC          A  @BASEBOARD_FAB2_LIB.BASEBOARD_FAB2(SCH_1):PVDDQ_ABC
    2  GND                B  @BASEBOARD_FAB2_LIB.BASEBOARD_FAB2(SCH_1):GND

CAP_A  I66  C5G55  [CAP_A_0603V-22.0UF,4V,20%,X6S,A]
    1  PVDDQ_ABC          A  @BASEBOARD_FAB2_LIB.BASEBOARD_FAB2(SCH_1):PVDDQ_ABC
    2  GND                B  @BASEBOARD_FAB2_LIB.BASEBOARD_FAB2(SCH_1):GND

CAP_A  I65  C5G56  [CAP_A_0603V-22.0UF,4V,20%,X6S,A]
    1  PVDDQ_ABC          A  @BASEBOARD_FAB2_LIB.BASEBOARD_FAB2(SCH_1):PVDDQ_ABC
    2  GND                B  @BASEBOARD_FAB2_LIB.BASEBOARD_FAB2(SCH_1):GND

CAP_A  I64  C5G57  [CAP_A_0603V-22.0UF,4V,20%,X6S,A]
    1  PVDDQ_ABC          A  @BASEBOARD_FAB2_LIB.BASEBOARD_FAB2(SCH_1):PVDDQ_ABC
    2  GND                B  @BASEBOARD_FAB2_LIB.BASEBOARD_FAB2(SCH_1):GND

CAP_A  I63  C5G58  [CAP_A_0603V-22.0UF,4V,20%,X6S,A]
    1  PVDDQ_ABC          A  @BASEBOARD_FAB2_LIB.BASEBOARD_FAB2(SCH_1):PVDDQ_ABC
    2  GND                B  @BASEBOARD_FAB2_LIB.BASEBOARD_FAB2(SCH_1):GND

CAP_A  I79  C5G59  [CAP_A_0603V-22.0UF,4V,20%,X6S,A]
    1  PVDDQ_DEF          A  @BASEBOARD_FAB2_LIB.BASEBOARD_FAB2(SCH_1):PVDDQ_DEF
    2  GND                B  @BASEBOARD_FAB2_LIB.BASEBOARD_FAB2(SCH_1):GND

CAP_A  I78  C5G60  [CAP_A_0603V-22.0UF,4V,20%,X6S,A]
    1  PVDDQ_DEF          A  @BASEBOARD_FAB2_LIB.BASEBOARD_FAB2(SCH_1):PVDDQ_DEF
    2  GND                B  @BASEBOARD_FAB2_LIB.BASEBOARD_FAB2(SCH_1):GND

CAP_A  I77  C5G61  [CAP_A_0603V-22.0UF,4V,20%,X6S,A]
    1  PVDDQ_DEF          A  @BASEBOARD_FAB2_LIB.BASEBOARD_FAB2(SCH_1):PVDDQ_DEF
    2  GND                B  @BASEBOARD_FAB2_LIB.BASEBOARD_FAB2(SCH_1):GND

CAP_A  I76  C5G62  [CAP_A_0603V-22.0UF,4V,20%,X6S,A]
    1  PVDDQ_DEF          A  @BASEBOARD_FAB2_LIB.BASEBOARD_FAB2(SCH_1):PVDDQ_DEF
    2  GND                B  @BASEBOARD_FAB2_LIB.BASEBOARD_FAB2(SCH_1):GND

CAP_A  I75  C5G63  [CAP_A_0603V-22.0UF,4V,20%,X6S,A]
    1  PVDDQ_DEF          A  @BASEBOARD_FAB2_LIB.BASEBOARD_FAB2(SCH_1):PVDDQ_DEF
    2  GND                B  @BASEBOARD_FAB2_LIB.BASEBOARD_FAB2(SCH_1):GND

CAP_A  I74  C5G64  [CAP_A_0603V-22.0UF,4V,20%,X6S,A]
    1  PVDDQ_DEF          A  @BASEBOARD_FAB2_LIB.BASEBOARD_FAB2(SCH_1):PVDDQ_DEF
    2  GND                B  @BASEBOARD_FAB2_LIB.BASEBOARD_FAB2(SCH_1):GND

CAP_A  I73  C5G65  [CAP_A_0603V-22.0UF,4V,20%,X6S,A]
    1  PVDDQ_DEF          A  @BASEBOARD_FAB2_LIB.BASEBOARD_FAB2(SCH_1):PVDDQ_DEF
    2  GND                B  @BASEBOARD_FAB2_LIB.BASEBOARD_FAB2(SCH_1):GND

CAP_A  I72  C5G66  [CAP_A_0603V-22.0UF,4V,20%,X6S,A]
    1  PVDDQ_DEF          A  @BASEBOARD_FAB2_LIB.BASEBOARD_FAB2(SCH_1):PVDDQ_DEF
    2  GND                B  @BASEBOARD_FAB2_LIB.BASEBOARD_FAB2(SCH_1):GND

CAP_A  I71  C5G67  [CAP_A_0603V-22.0UF,4V,20%,X6S,A]
    1  PVDDQ_DEF          A  @BASEBOARD_FAB2_LIB.BASEBOARD_FAB2(SCH_1):PVDDQ_DEF
    2  GND                B  @BASEBOARD_FAB2_LIB.BASEBOARD_FAB2(SCH_1):GND

CAP_A  I88  C5G68  [CAP_A_0603V-22.0UF,4V,20%,X6S,A]
    1  PVDDQ_DEF          A  @BASEBOARD_FAB2_LIB.BASEBOARD_FAB2(SCH_1):PVDDQ_DEF
    2  GND                B  @BASEBOARD_FAB2_LIB.BASEBOARD_FAB2(SCH_1):GND

CAP_A  I87  C5G69  [CAP_A_0603V-22.0UF,4V,20%,X6S,A]
    1  PVDDQ_DEF          A  @BASEBOARD_FAB2_LIB.BASEBOARD_FAB2(SCH_1):PVDDQ_DEF
    2  GND                B  @BASEBOARD_FAB2_LIB.BASEBOARD_FAB2(SCH_1):GND

CAP_A  I86  C5G70  [CAP_A_0603V-22.0UF,4V,20%,X6S,A]
    1  PVDDQ_DEF          A  @BASEBOARD_FAB2_LIB.BASEBOARD_FAB2(SCH_1):PVDDQ_DEF
    2  GND                B  @BASEBOARD_FAB2_LIB.BASEBOARD_FAB2(SCH_1):GND

CAP_A  I85  C5G71  [CAP_A_0603V-22.0UF,4V,20%,X6S,A]
    1  PVDDQ_DEF          A  @BASEBOARD_FAB2_LIB.BASEBOARD_FAB2(SCH_1):PVDDQ_DEF
    2  GND                B  @BASEBOARD_FAB2_LIB.BASEBOARD_FAB2(SCH_1):GND

CAP_A  I84  C5G72  [CAP_A_0603V-22.0UF,4V,20%,X6S,A]
    1  PVDDQ_DEF          A  @BASEBOARD_FAB2_LIB.BASEBOARD_FAB2(SCH_1):PVDDQ_DEF
    2  GND                B  @BASEBOARD_FAB2_LIB.BASEBOARD_FAB2(SCH_1):GND

CAP_A  I83  C5G73  [CAP_A_0603V-22.0UF,4V,20%,X6S,A]
    1  PVDDQ_DEF          A  @BASEBOARD_FAB2_LIB.BASEBOARD_FAB2(SCH_1):PVDDQ_DEF
    2  GND                B  @BASEBOARD_FAB2_LIB.BASEBOARD_FAB2(SCH_1):GND

CAP_A  I82  C5G74  [CAP_A_0603V-22.0UF,4V,20%,X6S,A]
    1  PVDDQ_DEF          A  @BASEBOARD_FAB2_LIB.BASEBOARD_FAB2(SCH_1):PVDDQ_DEF
    2  GND                B  @BASEBOARD_FAB2_LIB.BASEBOARD_FAB2(SCH_1):GND

CAP_A  I81  C5G75  [CAP_A_0603V-22.0UF,4V,20%,X6S,A]
    1  PVDDQ_DEF          A  @BASEBOARD_FAB2_LIB.BASEBOARD_FAB2(SCH_1):PVDDQ_DEF
    2  GND                B  @BASEBOARD_FAB2_LIB.BASEBOARD_FAB2(SCH_1):GND

CAP_A  I80  C5G76  [CAP_A_0603V-22.0UF,4V,20%,X6S,A]
    1  PVDDQ_DEF          A  @BASEBOARD_FAB2_LIB.BASEBOARD_FAB2(SCH_1):PVDDQ_DEF
    2  GND                B  @BASEBOARD_FAB2_LIB.BASEBOARD_FAB2(SCH_1):GND

CAP  I37  C5G77  [CAP_0805-100UF,4V,20%,X5R,6024A]
    1  PVDDQ_DEF          A  @BASEBOARD_FAB2_LIB.BASEBOARD_FAB2(SCH_1):PVDDQ_DEF
    2  GND                B  @BASEBOARD_FAB2_LIB.BASEBOARD_FAB2(SCH_1):GND

CAP  I41  C5G78  [CAP_0805-100UF,4V,20%,X5R,6024A]
    1  PVDDQ_DEF          A  @BASEBOARD_FAB2_LIB.BASEBOARD_FAB2(SCH_1):PVDDQ_DEF
    2  GND                B  @BASEBOARD_FAB2_LIB.BASEBOARD_FAB2(SCH_1):GND

CAP_A  I53  C5G79  [CAP_A_0603V-22.0UF,4V,20%,X6S,A]
    1  PVDDQ_GHJ          A  @BASEBOARD_FAB2_LIB.BASEBOARD_FAB2(SCH_1):PVDDQ_GHJ
    2  GND                B  @BASEBOARD_FAB2_LIB.BASEBOARD_FAB2(SCH_1):GND

CAP_A  I61  C5G80  [CAP_A_0603V-22.0UF,4V,20%,X6S,A]
    1  PVDDQ_GHJ          A  @BASEBOARD_FAB2_LIB.BASEBOARD_FAB2(SCH_1):PVDDQ_GHJ
    2  GND                B  @BASEBOARD_FAB2_LIB.BASEBOARD_FAB2(SCH_1):GND

CAP_A  I60  C5G81  [CAP_A_0603V-22.0UF,4V,20%,X6S,A]
    1  PVDDQ_GHJ          A  @BASEBOARD_FAB2_LIB.BASEBOARD_FAB2(SCH_1):PVDDQ_GHJ
    2  GND                B  @BASEBOARD_FAB2_LIB.BASEBOARD_FAB2(SCH_1):GND

CAP_A  I59  C5G82  [CAP_A_0603V-22.0UF,4V,20%,X6S,A]
    1  PVDDQ_GHJ          A  @BASEBOARD_FAB2_LIB.BASEBOARD_FAB2(SCH_1):PVDDQ_GHJ
    2  GND                B  @BASEBOARD_FAB2_LIB.BASEBOARD_FAB2(SCH_1):GND

CAP_A  I58  C5G83  [CAP_A_0603V-22.0UF,4V,20%,X6S,A]
    1  PVDDQ_GHJ          A  @BASEBOARD_FAB2_LIB.BASEBOARD_FAB2(SCH_1):PVDDQ_GHJ
    2  GND                B  @BASEBOARD_FAB2_LIB.BASEBOARD_FAB2(SCH_1):GND

CAP_A  I57  C5G84  [CAP_A_0603V-22.0UF,4V,20%,X6S,A]
    1  PVDDQ_GHJ          A  @BASEBOARD_FAB2_LIB.BASEBOARD_FAB2(SCH_1):PVDDQ_GHJ
    2  GND                B  @BASEBOARD_FAB2_LIB.BASEBOARD_FAB2(SCH_1):GND

CAP_A  I56  C5G85  [CAP_A_0603V-22.0UF,4V,20%,X6S,A]
    1  PVDDQ_GHJ          A  @BASEBOARD_FAB2_LIB.BASEBOARD_FAB2(SCH_1):PVDDQ_GHJ
    2  GND                B  @BASEBOARD_FAB2_LIB.BASEBOARD_FAB2(SCH_1):GND

CAP_A  I55  C5G86  [CAP_A_0603V-22.0UF,4V,20%,X6S,A]
    1  PVDDQ_GHJ          A  @BASEBOARD_FAB2_LIB.BASEBOARD_FAB2(SCH_1):PVDDQ_GHJ
    2  GND                B  @BASEBOARD_FAB2_LIB.BASEBOARD_FAB2(SCH_1):GND

CAP_A  I54  C5G87  [CAP_A_0603V-22.0UF,4V,20%,X6S,A]
    1  PVDDQ_GHJ          A  @BASEBOARD_FAB2_LIB.BASEBOARD_FAB2(SCH_1):PVDDQ_GHJ
    2  GND                B  @BASEBOARD_FAB2_LIB.BASEBOARD_FAB2(SCH_1):GND

CAP_A  I70  C5G88  [CAP_A_0603V-22.0UF,4V,20%,X6S,A]
    1  PVDDQ_GHJ          A  @BASEBOARD_FAB2_LIB.BASEBOARD_FAB2(SCH_1):PVDDQ_GHJ
    2  GND                B  @BASEBOARD_FAB2_LIB.BASEBOARD_FAB2(SCH_1):GND

CAP_A  I69  C5G89  [CAP_A_0603V-22.0UF,4V,20%,X6S,A]
    1  PVDDQ_GHJ          A  @BASEBOARD_FAB2_LIB.BASEBOARD_FAB2(SCH_1):PVDDQ_GHJ
    2  GND                B  @BASEBOARD_FAB2_LIB.BASEBOARD_FAB2(SCH_1):GND

CAP_A  I68  C5G90  [CAP_A_0603V-22.0UF,4V,20%,X6S,A]
    1  PVDDQ_GHJ          A  @BASEBOARD_FAB2_LIB.BASEBOARD_FAB2(SCH_1):PVDDQ_GHJ
    2  GND                B  @BASEBOARD_FAB2_LIB.BASEBOARD_FAB2(SCH_1):GND

CAP_A  I67  C5G91  [CAP_A_0603V-22.0UF,4V,20%,X6S,A]
    1  PVDDQ_GHJ          A  @BASEBOARD_FAB2_LIB.BASEBOARD_FAB2(SCH_1):PVDDQ_GHJ
    2  GND                B  @BASEBOARD_FAB2_LIB.BASEBOARD_FAB2(SCH_1):GND

CAP_A  I66  C5G92  [CAP_A_0603V-22.0UF,4V,20%,X6S,A]
    1  PVDDQ_GHJ          A  @BASEBOARD_FAB2_LIB.BASEBOARD_FAB2(SCH_1):PVDDQ_GHJ
    2  GND                B  @BASEBOARD_FAB2_LIB.BASEBOARD_FAB2(SCH_1):GND

CAP_A  I65  C5G93  [CAP_A_0603V-22.0UF,4V,20%,X6S,A]
    1  PVDDQ_GHJ          A  @BASEBOARD_FAB2_LIB.BASEBOARD_FAB2(SCH_1):PVDDQ_GHJ
    2  GND                B  @BASEBOARD_FAB2_LIB.BASEBOARD_FAB2(SCH_1):GND

CAP_A  I64  C5G94  [CAP_A_0603V-22.0UF,4V,20%,X6S,A]
    1  PVDDQ_GHJ          A  @BASEBOARD_FAB2_LIB.BASEBOARD_FAB2(SCH_1):PVDDQ_GHJ
    2  GND                B  @BASEBOARD_FAB2_LIB.BASEBOARD_FAB2(SCH_1):GND

CAP_A  I63  C5G95  [CAP_A_0603V-22.0UF,4V,20%,X6S,A]
    1  PVDDQ_GHJ          A  @BASEBOARD_FAB2_LIB.BASEBOARD_FAB2(SCH_1):PVDDQ_GHJ
    2  GND                B  @BASEBOARD_FAB2_LIB.BASEBOARD_FAB2(SCH_1):GND

CAP_A  I62  C5G96  [CAP_A_0603V-22.0UF,4V,20%,X6S,A]
    1  PVDDQ_GHJ          A  @BASEBOARD_FAB2_LIB.BASEBOARD_FAB2(SCH_1):PVDDQ_GHJ
    2  GND                B  @BASEBOARD_FAB2_LIB.BASEBOARD_FAB2(SCH_1):GND

CAP_A  I79  C5G97  [CAP_A_0603V-22.0UF,4V,20%,X6S,A]
    1  PVDDQ_KLM          A  @BASEBOARD_FAB2_LIB.BASEBOARD_FAB2(SCH_1):PVDDQ_KLM
    2  GND                B  @BASEBOARD_FAB2_LIB.BASEBOARD_FAB2(SCH_1):GND

CAP_A  I78  C5G98  [CAP_A_0603V-22.0UF,4V,20%,X6S,A]
    1  PVDDQ_KLM          A  @BASEBOARD_FAB2_LIB.BASEBOARD_FAB2(SCH_1):PVDDQ_KLM
    2  GND                B  @BASEBOARD_FAB2_LIB.BASEBOARD_FAB2(SCH_1):GND

CAP_A  I77  C5G99  [CAP_A_0603V-22.0UF,4V,20%,X6S,A]
    1  PVDDQ_KLM          A  @BASEBOARD_FAB2_LIB.BASEBOARD_FAB2(SCH_1):PVDDQ_KLM
    2  GND                B  @BASEBOARD_FAB2_LIB.BASEBOARD_FAB2(SCH_1):GND

CAP_A  I76  C5G100  [CAP_A_0603V-22.0UF,4V,20%,X6S,A]
    1  PVDDQ_KLM          A  @BASEBOARD_FAB2_LIB.BASEBOARD_FAB2(SCH_1):PVDDQ_KLM
    2  GND                B  @BASEBOARD_FAB2_LIB.BASEBOARD_FAB2(SCH_1):GND

CAP_A  I75  C5G101  [CAP_A_0603V-22.0UF,4V,20%,X6S,A]
    1  PVDDQ_KLM          A  @BASEBOARD_FAB2_LIB.BASEBOARD_FAB2(SCH_1):PVDDQ_KLM
    2  GND                B  @BASEBOARD_FAB2_LIB.BASEBOARD_FAB2(SCH_1):GND

CAP_A  I74  C5G102  [CAP_A_0603V-22.0UF,4V,20%,X6S,A]
    1  PVDDQ_KLM          A  @BASEBOARD_FAB2_LIB.BASEBOARD_FAB2(SCH_1):PVDDQ_KLM
    2  GND                B  @BASEBOARD_FAB2_LIB.BASEBOARD_FAB2(SCH_1):GND

CAP_A  I71  C5G103  [CAP_A_0603V-22.0UF,4V,20%,X6S,A]
    1  PVDDQ_KLM          A  @BASEBOARD_FAB2_LIB.BASEBOARD_FAB2(SCH_1):PVDDQ_KLM
    2  GND                B  @BASEBOARD_FAB2_LIB.BASEBOARD_FAB2(SCH_1):GND

CAP_A  I72  C5G104  [CAP_A_0603V-22.0UF,4V,20%,X6S,A]
    1  PVDDQ_KLM          A  @BASEBOARD_FAB2_LIB.BASEBOARD_FAB2(SCH_1):PVDDQ_KLM
    2  GND                B  @BASEBOARD_FAB2_LIB.BASEBOARD_FAB2(SCH_1):GND

CAP_A  I73  C5G105  [CAP_A_0603V-22.0UF,4V,20%,X6S,A]
    1  PVDDQ_KLM          A  @BASEBOARD_FAB2_LIB.BASEBOARD_FAB2(SCH_1):PVDDQ_KLM
    2  GND                B  @BASEBOARD_FAB2_LIB.BASEBOARD_FAB2(SCH_1):GND

CAP_A  I88  C5G106  [CAP_A_0603V-22.0UF,4V,20%,X6S,A]
    1  PVDDQ_KLM          A  @BASEBOARD_FAB2_LIB.BASEBOARD_FAB2(SCH_1):PVDDQ_KLM
    2  GND                B  @BASEBOARD_FAB2_LIB.BASEBOARD_FAB2(SCH_1):GND

CAP_A  I87  C5G107  [CAP_A_0603V-22.0UF,4V,20%,X6S,A]
    1  PVDDQ_KLM          A  @BASEBOARD_FAB2_LIB.BASEBOARD_FAB2(SCH_1):PVDDQ_KLM
    2  GND                B  @BASEBOARD_FAB2_LIB.BASEBOARD_FAB2(SCH_1):GND

CAP_A  I86  C5G108  [CAP_A_0603V-22.0UF,4V,20%,X6S,A]
    1  PVDDQ_KLM          A  @BASEBOARD_FAB2_LIB.BASEBOARD_FAB2(SCH_1):PVDDQ_KLM
    2  GND                B  @BASEBOARD_FAB2_LIB.BASEBOARD_FAB2(SCH_1):GND

CAP_A  I85  C5G109  [CAP_A_0603V-22.0UF,4V,20%,X6S,A]
    1  PVDDQ_KLM          A  @BASEBOARD_FAB2_LIB.BASEBOARD_FAB2(SCH_1):PVDDQ_KLM
    2  GND                B  @BASEBOARD_FAB2_LIB.BASEBOARD_FAB2(SCH_1):GND

CAP_A  I84  C5G110  [CAP_A_0603V-22.0UF,4V,20%,X6S,A]
    1  PVDDQ_KLM          A  @BASEBOARD_FAB2_LIB.BASEBOARD_FAB2(SCH_1):PVDDQ_KLM
    2  GND                B  @BASEBOARD_FAB2_LIB.BASEBOARD_FAB2(SCH_1):GND

CAP_A  I83  C5G111  [CAP_A_0603V-22.0UF,4V,20%,X6S,A]
    1  PVDDQ_KLM          A  @BASEBOARD_FAB2_LIB.BASEBOARD_FAB2(SCH_1):PVDDQ_KLM
    2  GND                B  @BASEBOARD_FAB2_LIB.BASEBOARD_FAB2(SCH_1):GND

CAP_A  I82  C5G112  [CAP_A_0603V-22.0UF,4V,20%,X6S,A]
    1  PVDDQ_KLM          A  @BASEBOARD_FAB2_LIB.BASEBOARD_FAB2(SCH_1):PVDDQ_KLM
    2  GND                B  @BASEBOARD_FAB2_LIB.BASEBOARD_FAB2(SCH_1):GND

CAP_A  I81  C5G113  [CAP_A_0603V-22.0UF,4V,20%,X6S,A]
    1  PVDDQ_KLM          A  @BASEBOARD_FAB2_LIB.BASEBOARD_FAB2(SCH_1):PVDDQ_KLM
    2  GND                B  @BASEBOARD_FAB2_LIB.BASEBOARD_FAB2(SCH_1):GND

CAP_A  I80  C5G114  [CAP_A_0603V-22.0UF,4V,20%,X6S,A]
    1  PVDDQ_KLM          A  @BASEBOARD_FAB2_LIB.BASEBOARD_FAB2(SCH_1):PVDDQ_KLM
    2  GND                B  @BASEBOARD_FAB2_LIB.BASEBOARD_FAB2(SCH_1):GND

CAP  I39  C5G115  [CAP_0805-100UF,4V,20%,X5R,6024A]
    1  PVDDQ_KLM          A  @BASEBOARD_FAB2_LIB.BASEBOARD_FAB2(SCH_1):PVDDQ_KLM
    2  GND                B  @BASEBOARD_FAB2_LIB.BASEBOARD_FAB2(SCH_1):GND

CAP  I43  C5G116  [CAP_0805-100UF,4V,20%,X5R,6024A]
    1  PVDDQ_KLM          A  @BASEBOARD_FAB2_LIB.BASEBOARD_FAB2(SCH_1):PVDDQ_KLM
    2  GND                B  @BASEBOARD_FAB2_LIB.BASEBOARD_FAB2(SCH_1):GND

CAP  I12  C5G117  [CAP_0805-100UF,4V,20%,X5R,6024A]
    1  PVDDQ_GHJ          A  @BASEBOARD_FAB2_LIB.BASEBOARD_FAB2(SCH_1):PVDDQ_GHJ
    2  GND                B  @BASEBOARD_FAB2_LIB.BASEBOARD_FAB2(SCH_1):GND

CAP  I13  C5G118  [CAP_0805-100UF,4V,20%,X5R,6024A]
    1  PVDDQ_GHJ          A  @BASEBOARD_FAB2_LIB.BASEBOARD_FAB2(SCH_1):PVDDQ_GHJ
    2  GND                B  @BASEBOARD_FAB2_LIB.BASEBOARD_FAB2(SCH_1):GND

CAP  I91  C5L1   [CAP_0805-100UF,4V,20%,X5R,6024A]
    1  PVDDQ_DEF          A  @BASEBOARD_FAB2_LIB.BASEBOARD_FAB2(SCH_1):PVDDQ_DEF
    2  GND                B  @BASEBOARD_FAB2_LIB.BASEBOARD_FAB2(SCH_1):GND

CAP  I90  C5L2   [CAP_0805-100UF,4V,20%,X5R,6024A]
    1  PVDDQ_DEF          A  @BASEBOARD_FAB2_LIB.BASEBOARD_FAB2(SCH_1):PVDDQ_DEF
    2  GND                B  @BASEBOARD_FAB2_LIB.BASEBOARD_FAB2(SCH_1):GND

CAP  I89  C5L3   [CAP_0805-100UF,4V,20%,X5R,6024A]
    1  PVDDQ_DEF          A  @BASEBOARD_FAB2_LIB.BASEBOARD_FAB2(SCH_1):PVDDQ_DEF
    2  GND                B  @BASEBOARD_FAB2_LIB.BASEBOARD_FAB2(SCH_1):GND

CAP_A  I47  C5L4   [CAP_A_0603V-47UF,4V,20%,X5R,60A]
    1  PVTT_DEF           A  @BASEBOARD_FAB2_LIB.BASEBOARD_FAB2(SCH_1):PVTT_DEF
    2  GND                B  @BASEBOARD_FAB2_LIB.BASEBOARD_FAB2(SCH_1):GND

CAP_A  I49  C5L5   [CAP_A_0603V-47UF,4V,20%,X5R,60A]
    1  PVTT_DEF           A  @BASEBOARD_FAB2_LIB.BASEBOARD_FAB2(SCH_1):PVTT_DEF
    2  GND                B  @BASEBOARD_FAB2_LIB.BASEBOARD_FAB2(SCH_1):GND

CAP_A  I237  C5L6   [CAP_A_0603V-22.0UF,4V,20%,X6S,A]
    1  PVDDQ_DEF          A  @BASEBOARD_FAB2_LIB.BASEBOARD_FAB2(SCH_1):PVDDQ_DEF
    2  GND                B  @BASEBOARD_FAB2_LIB.BASEBOARD_FAB2(SCH_1):GND

CAP_A  I236  C5L7   [CAP_A_0603V-22.0UF,4V,20%,X6S,A]
    1  PVDDQ_DEF          A  @BASEBOARD_FAB2_LIB.BASEBOARD_FAB2(SCH_1):PVDDQ_DEF
    2  GND                B  @BASEBOARD_FAB2_LIB.BASEBOARD_FAB2(SCH_1):GND

CAP_A  I234  C5L8   [CAP_A_0603V-22.0UF,4V,20%,X6S,A]
    1  PVDDQ_DEF          A  @BASEBOARD_FAB2_LIB.BASEBOARD_FAB2(SCH_1):PVDDQ_DEF
    2  GND                B  @BASEBOARD_FAB2_LIB.BASEBOARD_FAB2(SCH_1):GND

CAP_A  I233  C5L9   [CAP_A_0603V-22.0UF,4V,20%,X6S,A]
    1  PVDDQ_DEF          A  @BASEBOARD_FAB2_LIB.BASEBOARD_FAB2(SCH_1):PVDDQ_DEF
    2  GND                B  @BASEBOARD_FAB2_LIB.BASEBOARD_FAB2(SCH_1):GND

CAP_A  I232  C5L10  [CAP_A_0603V-22.0UF,4V,20%,X6S,A]
    1  PVDDQ_DEF          A  @BASEBOARD_FAB2_LIB.BASEBOARD_FAB2(SCH_1):PVDDQ_DEF
    2  GND                B  @BASEBOARD_FAB2_LIB.BASEBOARD_FAB2(SCH_1):GND

CAP_A  I231  C5L11  [CAP_A_0603V-22.0UF,4V,20%,X6S,A]
    1  PVDDQ_DEF          A  @BASEBOARD_FAB2_LIB.BASEBOARD_FAB2(SCH_1):PVDDQ_DEF
    2  GND                B  @BASEBOARD_FAB2_LIB.BASEBOARD_FAB2(SCH_1):GND

CAP_A  I230  C5L12  [CAP_A_0603V-22.0UF,4V,20%,X6S,A]
    1  PVDDQ_DEF          A  @BASEBOARD_FAB2_LIB.BASEBOARD_FAB2(SCH_1):PVDDQ_DEF
    2  GND                B  @BASEBOARD_FAB2_LIB.BASEBOARD_FAB2(SCH_1):GND

CAP_A  I229  C5L13  [CAP_A_0603V-22.0UF,4V,20%,X6S,A]
    1  PVDDQ_DEF          A  @BASEBOARD_FAB2_LIB.BASEBOARD_FAB2(SCH_1):PVDDQ_DEF
    2  GND                B  @BASEBOARD_FAB2_LIB.BASEBOARD_FAB2(SCH_1):GND

CAP  I83  C5L14  [CAP_0805-100UF,4V,20%,X5R,6024A]
    1  PVDDQ_DEF          A  @BASEBOARD_FAB2_LIB.BASEBOARD_FAB2(SCH_1):PVDDQ_DEF
    2  GND                B  @BASEBOARD_FAB2_LIB.BASEBOARD_FAB2(SCH_1):GND

CAP_A  I192  C5L15  [CAP_A_0603V-47UF,4V,20%,X5R,60A]
    1  PVDDQ_DEF          A  @BASEBOARD_FAB2_LIB.BASEBOARD_FAB2(SCH_1):PVDDQ_DEF
    2  GND                B  @BASEBOARD_FAB2_LIB.BASEBOARD_FAB2(SCH_1):GND

CAP_A  I223  C5M1   [CAP_A_0603V-22.0UF,4V,20%,X6S,A]
    1  PVDDQ_DEF          A  @BASEBOARD_FAB2_LIB.BASEBOARD_FAB2(SCH_1):PVDDQ_DEF
    2  GND                B  @BASEBOARD_FAB2_LIB.BASEBOARD_FAB2(SCH_1):GND

CAP_A  I224  C5M2   [CAP_A_0603V-22.0UF,4V,20%,X6S,A]
    1  PVDDQ_DEF          A  @BASEBOARD_FAB2_LIB.BASEBOARD_FAB2(SCH_1):PVDDQ_DEF
    2  GND                B  @BASEBOARD_FAB2_LIB.BASEBOARD_FAB2(SCH_1):GND

CAP_A  I199  C5M3   [CAP_A_0603V-47UF,4V,20%,X5R,60A]
    1  PVDDQ_DEF          A  @BASEBOARD_FAB2_LIB.BASEBOARD_FAB2(SCH_1):PVDDQ_DEF
    2  GND                B  @BASEBOARD_FAB2_LIB.BASEBOARD_FAB2(SCH_1):GND

CAP_A  I225  C5M4   [CAP_A_0603V-22.0UF,4V,20%,X6S,A]
    1  PVDDQ_DEF          A  @BASEBOARD_FAB2_LIB.BASEBOARD_FAB2(SCH_1):PVDDQ_DEF
    2  GND                B  @BASEBOARD_FAB2_LIB.BASEBOARD_FAB2(SCH_1):GND

CAP_A  I226  C5M5   [CAP_A_0603V-22.0UF,4V,20%,X6S,A]
    1  PVDDQ_DEF          A  @BASEBOARD_FAB2_LIB.BASEBOARD_FAB2(SCH_1):PVDDQ_DEF
    2  GND                B  @BASEBOARD_FAB2_LIB.BASEBOARD_FAB2(SCH_1):GND

CAP_A  I227  C5M6   [CAP_A_0603V-22.0UF,4V,20%,X6S,A]
    1  PVDDQ_DEF          A  @BASEBOARD_FAB2_LIB.BASEBOARD_FAB2(SCH_1):PVDDQ_DEF
    2  GND                B  @BASEBOARD_FAB2_LIB.BASEBOARD_FAB2(SCH_1):GND

CAP_A  I228  C5M7   [CAP_A_0603V-22.0UF,4V,20%,X6S,A]
    1  PVDDQ_DEF          A  @BASEBOARD_FAB2_LIB.BASEBOARD_FAB2(SCH_1):PVDDQ_DEF
    2  GND                B  @BASEBOARD_FAB2_LIB.BASEBOARD_FAB2(SCH_1):GND

CAP  I82  C5M8   [CAP_0805-100UF,4V,20%,X5R,6024A]
    1  PVDDQ_DEF          A  @BASEBOARD_FAB2_LIB.BASEBOARD_FAB2(SCH_1):PVDDQ_DEF
    2  GND                B  @BASEBOARD_FAB2_LIB.BASEBOARD_FAB2(SCH_1):GND

CAP_A  I195  C5M9   [CAP_A_0603V-47UF,4V,20%,X5R,60A]
    1  PVDDQ_DEF          A  @BASEBOARD_FAB2_LIB.BASEBOARD_FAB2(SCH_1):PVDDQ_DEF
    2  GND                B  @BASEBOARD_FAB2_LIB.BASEBOARD_FAB2(SCH_1):GND

CAP_A  I198  C5M10  [CAP_A_0603V-47UF,4V,20%,X5R,60A]
    1  PVDDQ_DEF          A  @BASEBOARD_FAB2_LIB.BASEBOARD_FAB2(SCH_1):PVDDQ_DEF
    2  GND                B  @BASEBOARD_FAB2_LIB.BASEBOARD_FAB2(SCH_1):GND

CAP_A  I200  C5M11  [CAP_A_0603V-47UF,4V,20%,X5R,60A]
    1  PVDDQ_DEF          A  @BASEBOARD_FAB2_LIB.BASEBOARD_FAB2(SCH_1):PVDDQ_DEF
    2  GND                B  @BASEBOARD_FAB2_LIB.BASEBOARD_FAB2(SCH_1):GND

CAP  I88  C5M12  [CAP_0805-100UF,4V,20%,X5R,6024A]
    1  PVDDQ_DEF          A  @BASEBOARD_FAB2_LIB.BASEBOARD_FAB2(SCH_1):PVDDQ_DEF
    2  GND                B  @BASEBOARD_FAB2_LIB.BASEBOARD_FAB2(SCH_1):GND

CAP_A  I48  C5M13  [CAP_A_0603V-47UF,4V,20%,X5R,60A]
    1  PVTT_DEF           A  @BASEBOARD_FAB2_LIB.BASEBOARD_FAB2(SCH_1):PVTT_DEF
    2  GND                B  @BASEBOARD_FAB2_LIB.BASEBOARD_FAB2(SCH_1):GND

CAP  I179  C5P1   [CAP_0805LF-22UF,4V,20%,X6S,C95A]
    1  PVDDQ_DEF          A  @BASEBOARD_FAB2_LIB.BASEBOARD_FAB2(SCH_1):PVDDQ_DEF
    2  GND                B  @BASEBOARD_FAB2_LIB.BASEBOARD_FAB2(SCH_1):GND

CAP  I177  C5P2   [CAP_0805LF-22UF,4V,20%,X6S,C95A]
    1  PVDDQ_DEF          A  @BASEBOARD_FAB2_LIB.BASEBOARD_FAB2(SCH_1):PVDDQ_DEF
    2  GND                B  @BASEBOARD_FAB2_LIB.BASEBOARD_FAB2(SCH_1):GND

CAP  I189  C5P3   [CAP_0805-47UF,4V,20%,X6S,C9533A]
    1  PVCCIN_CPU0        A  @BASEBOARD_FAB2_LIB.BASEBOARD_FAB2(SCH_1):PVCCIN_CPU0
    2  GND                B  @BASEBOARD_FAB2_LIB.BASEBOARD_FAB2(SCH_1):GND

CAP  I27  C5P4   [CAP_0805-47UF,4V,20%,X6S,C9533A]
    1  PVCCIN_CPU0        A  @BASEBOARD_FAB2_LIB.BASEBOARD_FAB2(SCH_1):PVCCIN_CPU0
    2  GND                B  @BASEBOARD_FAB2_LIB.BASEBOARD_FAB2(SCH_1):GND

CAP  I42  C5P5   [CAP_0805-47UF,4V,20%,X6S,C9533A]
    1  PVCCIN_CPU0        A  @BASEBOARD_FAB2_LIB.BASEBOARD_FAB2(SCH_1):PVCCIN_CPU0
    2  GND                B  @BASEBOARD_FAB2_LIB.BASEBOARD_FAB2(SCH_1):GND

CAP  I38  C5P6   [CAP_0805-47UF,4V,20%,X6S,C9533A]
    1  PVCCIN_CPU0        A  @BASEBOARD_FAB2_LIB.BASEBOARD_FAB2(SCH_1):PVCCIN_CPU0
    2  GND                B  @BASEBOARD_FAB2_LIB.BASEBOARD_FAB2(SCH_1):GND

CAP  I25  C5P7   [CAP_0805LF-22UF,4V,20%,X6S,C95A]
    1  PVSA_CPU0          A  @BASEBOARD_FAB2_LIB.BASEBOARD_FAB2(SCH_1):PVSA_CPU0
    2  GND                B  @BASEBOARD_FAB2_LIB.BASEBOARD_FAB2(SCH_1):GND

CAP  I19  C5P8   [CAP_0805LF-22UF,4V,20%,X6S,C95A]
    1  PVSA_CPU0          A  @BASEBOARD_FAB2_LIB.BASEBOARD_FAB2(SCH_1):PVSA_CPU0
    2  GND                B  @BASEBOARD_FAB2_LIB.BASEBOARD_FAB2(SCH_1):GND

CAP  I18  C5P9   [CAP_0805LF-22UF,4V,20%,X6S,C95A]
    1  PVSA_CPU0          A  @BASEBOARD_FAB2_LIB.BASEBOARD_FAB2(SCH_1):PVSA_CPU0
    2  GND                B  @BASEBOARD_FAB2_LIB.BASEBOARD_FAB2(SCH_1):GND

CAP  I6   C5P10  [CAP_0805-47UF,4V,20%,X6S,C9533A]
    1  PVCCMCP_CPU0       A  @BASEBOARD_FAB2_LIB.BASEBOARD_FAB2(SCH_1):PVCCMCP_CPU0
    2  GND                B  @BASEBOARD_FAB2_LIB.BASEBOARD_FAB2(SCH_1):GND

CAP  I4   C5P11  [CAP_0805-47UF,4V,20%,X6S,C9533A]
    1  PVCCMCP_CPU0       A  @BASEBOARD_FAB2_LIB.BASEBOARD_FAB2(SCH_1):PVCCMCP_CPU0
    2  GND                B  @BASEBOARD_FAB2_LIB.BASEBOARD_FAB2(SCH_1):GND

CAP  I183  C5P12  [CAP_0805-47UF,4V,20%,X6S,C9533A]
    1  PVCCMCP_CPU0       A  @BASEBOARD_FAB2_LIB.BASEBOARD_FAB2(SCH_1):PVCCMCP_CPU0
    2  GND                B  @BASEBOARD_FAB2_LIB.BASEBOARD_FAB2(SCH_1):GND

CAP  I186  C5P13  [CAP_0805-47UF,4V,20%,X6S,C9533A]
    1  PVCCMCP_CPU0       A  @BASEBOARD_FAB2_LIB.BASEBOARD_FAB2(SCH_1):PVCCMCP_CPU0
    2  GND                B  @BASEBOARD_FAB2_LIB.BASEBOARD_FAB2(SCH_1):GND

CAP  I41  C5P14  [CAP_0805-47UF,4V,20%,X6S,C9533A]
    1  PVCCIN_CPU0        A  @BASEBOARD_FAB2_LIB.BASEBOARD_FAB2(SCH_1):PVCCIN_CPU0
    2  GND                B  @BASEBOARD_FAB2_LIB.BASEBOARD_FAB2(SCH_1):GND

CAP  I187  C5P15  [CAP_0805-47UF,4V,20%,X6S,C9533A]
    1  PVCCIN_CPU0        A  @BASEBOARD_FAB2_LIB.BASEBOARD_FAB2(SCH_1):PVCCIN_CPU0
    2  GND                B  @BASEBOARD_FAB2_LIB.BASEBOARD_FAB2(SCH_1):GND

CAP  I188  C5P16  [CAP_0805-47UF,4V,20%,X6S,C9533A]
    1  PVCCIN_CPU0        A  @BASEBOARD_FAB2_LIB.BASEBOARD_FAB2(SCH_1):PVCCIN_CPU0
    2  GND                B  @BASEBOARD_FAB2_LIB.BASEBOARD_FAB2(SCH_1):GND

CAP  I190  C5P17  [CAP_0805-47UF,4V,20%,X6S,C9533A]
    1  PVCCIN_CPU0        A  @BASEBOARD_FAB2_LIB.BASEBOARD_FAB2(SCH_1):PVCCIN_CPU0
    2  GND                B  @BASEBOARD_FAB2_LIB.BASEBOARD_FAB2(SCH_1):GND

CAP  I2   C5P18  [CAP_0805-47UF,4V,20%,X6S,C9533A]
    1  PVCCMCP_CPU0       A  @BASEBOARD_FAB2_LIB.BASEBOARD_FAB2(SCH_1):PVCCMCP_CPU0
    2  GND                B  @BASEBOARD_FAB2_LIB.BASEBOARD_FAB2(SCH_1):GND

CAP  I13  C5P19  [CAP_0805-47UF,4V,20%,X6S,C9533A]
    1  PVCCMCP_CPU0       A  @BASEBOARD_FAB2_LIB.BASEBOARD_FAB2(SCH_1):PVCCMCP_CPU0
    2  GND                B  @BASEBOARD_FAB2_LIB.BASEBOARD_FAB2(SCH_1):GND

CAP  I185  C5P20  [CAP_0805-47UF,4V,20%,X6S,C9533A]
    1  PVCCMCP_CPU0       A  @BASEBOARD_FAB2_LIB.BASEBOARD_FAB2(SCH_1):PVCCMCP_CPU0
    2  GND                B  @BASEBOARD_FAB2_LIB.BASEBOARD_FAB2(SCH_1):GND

CAP  I184  C5P21  [CAP_0805-47UF,4V,20%,X6S,C9533A]
    1  PVCCMCP_CPU0       A  @BASEBOARD_FAB2_LIB.BASEBOARD_FAB2(SCH_1):PVCCMCP_CPU0
    2  GND                B  @BASEBOARD_FAB2_LIB.BASEBOARD_FAB2(SCH_1):GND

CAP  I55  C5P22  [CAP_0805-47UF,4V,20%,X6S,C9533A]
    1  PVCCIN_CPU0        A  @BASEBOARD_FAB2_LIB.BASEBOARD_FAB2(SCH_1):PVCCIN_CPU0
    2  GND                B  @BASEBOARD_FAB2_LIB.BASEBOARD_FAB2(SCH_1):GND

CAP  I28  C5P23  [CAP_0805-47UF,4V,20%,X6S,C9533A]
    1  PVCCIN_CPU0        A  @BASEBOARD_FAB2_LIB.BASEBOARD_FAB2(SCH_1):PVCCIN_CPU0
    2  GND                B  @BASEBOARD_FAB2_LIB.BASEBOARD_FAB2(SCH_1):GND

CAP  I33  C5P24  [CAP_0805-47UF,4V,20%,X6S,C9533A]
    1  PVCCIN_CPU0        A  @BASEBOARD_FAB2_LIB.BASEBOARD_FAB2(SCH_1):PVCCIN_CPU0
    2  GND                B  @BASEBOARD_FAB2_LIB.BASEBOARD_FAB2(SCH_1):GND

CAP  I37  C5P25  [CAP_0805-47UF,4V,20%,X6S,C9533A]
    1  PVCCIN_CPU0        A  @BASEBOARD_FAB2_LIB.BASEBOARD_FAB2(SCH_1):PVCCIN_CPU0
    2  GND                B  @BASEBOARD_FAB2_LIB.BASEBOARD_FAB2(SCH_1):GND

CAP  I56  C5P26  [CAP_0805-47UF,4V,20%,X6S,C9533A]
    1  PVCCIN_CPU0        A  @BASEBOARD_FAB2_LIB.BASEBOARD_FAB2(SCH_1):PVCCIN_CPU0
    2  GND                B  @BASEBOARD_FAB2_LIB.BASEBOARD_FAB2(SCH_1):GND

CAP  I44  C5P27  [CAP_0805-47UF,4V,20%,X6S,C9533A]
    1  PVCCIN_CPU0        A  @BASEBOARD_FAB2_LIB.BASEBOARD_FAB2(SCH_1):PVCCIN_CPU0
    2  GND                B  @BASEBOARD_FAB2_LIB.BASEBOARD_FAB2(SCH_1):GND

CAP  I3   C5P28  [CAP_0805-47UF,4V,20%,X6S,C9533A]
    1  PVCCMCP_CPU0       A  @BASEBOARD_FAB2_LIB.BASEBOARD_FAB2(SCH_1):PVCCMCP_CPU0
    2  GND                B  @BASEBOARD_FAB2_LIB.BASEBOARD_FAB2(SCH_1):GND

CAP  I149  C5P29  [CAP_0805-47UF,4V,20%,X6S,C9533A]
    1  PVCCMCP_CPU0       A  @BASEBOARD_FAB2_LIB.BASEBOARD_FAB2(SCH_1):PVCCMCP_CPU0
    2  GND                B  @BASEBOARD_FAB2_LIB.BASEBOARD_FAB2(SCH_1):GND

CAP  I148  C5P30  [CAP_0805-47UF,4V,20%,X6S,C9533A]
    1  PVCCMCP_CPU0       A  @BASEBOARD_FAB2_LIB.BASEBOARD_FAB2(SCH_1):PVCCMCP_CPU0
    2  GND                B  @BASEBOARD_FAB2_LIB.BASEBOARD_FAB2(SCH_1):GND

CAP  I162  C5P31  [CAP_0805-47UF,4V,20%,X6S,C9533A]
    1  PVCCMCP_CPU0       A  @BASEBOARD_FAB2_LIB.BASEBOARD_FAB2(SCH_1):PVCCMCP_CPU0
    2  GND                B  @BASEBOARD_FAB2_LIB.BASEBOARD_FAB2(SCH_1):GND

CAP  I53  C5P32  [CAP_0805-47UF,4V,20%,X6S,C9533A]
    1  PVCCIN_CPU0        A  @BASEBOARD_FAB2_LIB.BASEBOARD_FAB2(SCH_1):PVCCIN_CPU0
    2  GND                B  @BASEBOARD_FAB2_LIB.BASEBOARD_FAB2(SCH_1):GND

CAP  I50  C5P33  [CAP_0805-47UF,4V,20%,X6S,C9533A]
    1  PVCCIN_CPU0        A  @BASEBOARD_FAB2_LIB.BASEBOARD_FAB2(SCH_1):PVCCIN_CPU0
    2  GND                B  @BASEBOARD_FAB2_LIB.BASEBOARD_FAB2(SCH_1):GND

CAP  I54  C5P34  [CAP_0805-47UF,4V,20%,X6S,C9533A]
    1  PVCCIN_CPU0        A  @BASEBOARD_FAB2_LIB.BASEBOARD_FAB2(SCH_1):PVCCIN_CPU0
    2  GND                B  @BASEBOARD_FAB2_LIB.BASEBOARD_FAB2(SCH_1):GND

CAP  I51  C5P35  [CAP_0805-47UF,4V,20%,X6S,C9533A]
    1  PVCCIN_CPU0        A  @BASEBOARD_FAB2_LIB.BASEBOARD_FAB2(SCH_1):PVCCIN_CPU0
    2  GND                B  @BASEBOARD_FAB2_LIB.BASEBOARD_FAB2(SCH_1):GND

CAP  I65  C5P36  [CAP_0805-47UF,4V,20%,X6S,C9533A]
    1  PVCCIN_CPU0        A  @BASEBOARD_FAB2_LIB.BASEBOARD_FAB2(SCH_1):PVCCIN_CPU0
    2  GND                B  @BASEBOARD_FAB2_LIB.BASEBOARD_FAB2(SCH_1):GND

CAP  I63  C5P37  [CAP_0805-47UF,4V,20%,X6S,C9533A]
    1  PVCCIN_CPU0        A  @BASEBOARD_FAB2_LIB.BASEBOARD_FAB2(SCH_1):PVCCIN_CPU0
    2  GND                B  @BASEBOARD_FAB2_LIB.BASEBOARD_FAB2(SCH_1):GND

CAP  I193  C5P38  [CAP_0805LF-22UF,4V,20%,X6S,C95A]
    1  PVDDQ_ABC          A  @BASEBOARD_FAB2_LIB.BASEBOARD_FAB2(SCH_1):PVDDQ_ABC
    2  GND                B  @BASEBOARD_FAB2_LIB.BASEBOARD_FAB2(SCH_1):GND

CAP  I184  C5P39  [CAP_0805LF-22UF,4V,20%,X6S,C95A]
    1  PVDDQ_ABC          A  @BASEBOARD_FAB2_LIB.BASEBOARD_FAB2(SCH_1):PVDDQ_ABC
    2  GND                B  @BASEBOARD_FAB2_LIB.BASEBOARD_FAB2(SCH_1):GND

CAP  I57  C5P40  [CAP_0805-47UF,4V,20%,X6S,C9533A]
    1  PVCCIN_CPU0        A  @BASEBOARD_FAB2_LIB.BASEBOARD_FAB2(SCH_1):PVCCIN_CPU0
    2  GND                B  @BASEBOARD_FAB2_LIB.BASEBOARD_FAB2(SCH_1):GND

CAP  I40  C5P41  [CAP_0805-47UF,4V,20%,X6S,C9533A]
    1  PVCCIN_CPU0        A  @BASEBOARD_FAB2_LIB.BASEBOARD_FAB2(SCH_1):PVCCIN_CPU0
    2  GND                B  @BASEBOARD_FAB2_LIB.BASEBOARD_FAB2(SCH_1):GND

CAP  I59  C5P42  [CAP_0805-47UF,4V,20%,X6S,C9533A]
    1  PVCCIN_CPU0        A  @BASEBOARD_FAB2_LIB.BASEBOARD_FAB2(SCH_1):PVCCIN_CPU0
    2  GND                B  @BASEBOARD_FAB2_LIB.BASEBOARD_FAB2(SCH_1):GND

CAP  I60  C5P43  [CAP_0805-47UF,4V,20%,X6S,C9533A]
    1  PVCCIN_CPU0        A  @BASEBOARD_FAB2_LIB.BASEBOARD_FAB2(SCH_1):PVCCIN_CPU0
    2  GND                B  @BASEBOARD_FAB2_LIB.BASEBOARD_FAB2(SCH_1):GND

CAP  I61  C5P44  [CAP_0805-47UF,4V,20%,X6S,C9533A]
    1  PVCCIN_CPU0        A  @BASEBOARD_FAB2_LIB.BASEBOARD_FAB2(SCH_1):PVCCIN_CPU0
    2  GND                B  @BASEBOARD_FAB2_LIB.BASEBOARD_FAB2(SCH_1):GND

CAP_A  I212  C5T1   [CAP_A_0603V-47UF,4V,20%,X5R,60A]
    1  PVDDQ_ABC          A  @BASEBOARD_FAB2_LIB.BASEBOARD_FAB2(SCH_1):PVDDQ_ABC
    2  GND                B  @BASEBOARD_FAB2_LIB.BASEBOARD_FAB2(SCH_1):GND

CAP_A  I208  C5T2   [CAP_A_0603V-47UF,4V,20%,X5R,60A]
    1  PVDDQ_ABC          A  @BASEBOARD_FAB2_LIB.BASEBOARD_FAB2(SCH_1):PVDDQ_ABC
    2  GND                B  @BASEBOARD_FAB2_LIB.BASEBOARD_FAB2(SCH_1):GND

CAP_A  I51  C5T3   [CAP_A_0603V-47UF,4V,20%,X5R,60A]
    1  PVTT_ABC           A  @BASEBOARD_FAB2_LIB.BASEBOARD_FAB2(SCH_1):PVTT_ABC
    2  GND                B  @BASEBOARD_FAB2_LIB.BASEBOARD_FAB2(SCH_1):GND

CAP_A  I211  C5T4   [CAP_A_0603V-47UF,4V,20%,X5R,60A]
    1  PVDDQ_ABC          A  @BASEBOARD_FAB2_LIB.BASEBOARD_FAB2(SCH_1):PVDDQ_ABC
    2  GND                B  @BASEBOARD_FAB2_LIB.BASEBOARD_FAB2(SCH_1):GND

CAP_A  I216  C5T5   [CAP_A_0603V-22.0UF,4V,20%,X6S,A]
    1  PVDDQ_ABC          A  @BASEBOARD_FAB2_LIB.BASEBOARD_FAB2(SCH_1):PVDDQ_ABC
    2  GND                B  @BASEBOARD_FAB2_LIB.BASEBOARD_FAB2(SCH_1):GND

CAP_A  I218  C5T6   [CAP_A_0603V-22.0UF,4V,20%,X6S,A]
    1  PVDDQ_ABC          A  @BASEBOARD_FAB2_LIB.BASEBOARD_FAB2(SCH_1):PVDDQ_ABC
    2  GND                B  @BASEBOARD_FAB2_LIB.BASEBOARD_FAB2(SCH_1):GND

CAP_A  I219  C5T7   [CAP_A_0603V-22.0UF,4V,20%,X6S,A]
    1  PVDDQ_ABC          A  @BASEBOARD_FAB2_LIB.BASEBOARD_FAB2(SCH_1):PVDDQ_ABC
    2  GND                B  @BASEBOARD_FAB2_LIB.BASEBOARD_FAB2(SCH_1):GND

CAP_A  I222  C5T8   [CAP_A_0603V-22.0UF,4V,20%,X6S,A]
    1  PVDDQ_ABC          A  @BASEBOARD_FAB2_LIB.BASEBOARD_FAB2(SCH_1):PVDDQ_ABC
    2  GND                B  @BASEBOARD_FAB2_LIB.BASEBOARD_FAB2(SCH_1):GND

CAP_A  I224  C5T9   [CAP_A_0603V-22.0UF,4V,20%,X6S,A]
    1  PVDDQ_ABC          A  @BASEBOARD_FAB2_LIB.BASEBOARD_FAB2(SCH_1):PVDDQ_ABC
    2  GND                B  @BASEBOARD_FAB2_LIB.BASEBOARD_FAB2(SCH_1):GND

CAP_A  I225  C5T10  [CAP_A_0603V-22.0UF,4V,20%,X6S,A]
    1  PVDDQ_ABC          A  @BASEBOARD_FAB2_LIB.BASEBOARD_FAB2(SCH_1):PVDDQ_ABC
    2  GND                B  @BASEBOARD_FAB2_LIB.BASEBOARD_FAB2(SCH_1):GND

CAP_A  I228  C5T11  [CAP_A_0603V-22.0UF,4V,20%,X6S,A]
    1  PVDDQ_ABC          A  @BASEBOARD_FAB2_LIB.BASEBOARD_FAB2(SCH_1):PVDDQ_ABC
    2  GND                B  @BASEBOARD_FAB2_LIB.BASEBOARD_FAB2(SCH_1):GND

CAP_A  I229  C5T12  [CAP_A_0603V-22.0UF,4V,20%,X6S,A]
    1  PVDDQ_ABC          A  @BASEBOARD_FAB2_LIB.BASEBOARD_FAB2(SCH_1):PVDDQ_ABC
    2  GND                B  @BASEBOARD_FAB2_LIB.BASEBOARD_FAB2(SCH_1):GND

CAP_A  I210  C5T13  [CAP_A_0603V-47UF,4V,20%,X5R,60A]
    1  PVDDQ_ABC          A  @BASEBOARD_FAB2_LIB.BASEBOARD_FAB2(SCH_1):PVDDQ_ABC
    2  GND                B  @BASEBOARD_FAB2_LIB.BASEBOARD_FAB2(SCH_1):GND

CAP  I88  C5U1   [CAP_0805-100UF,4V,20%,X5R,6024A]
    1  PVDDQ_ABC          A  @BASEBOARD_FAB2_LIB.BASEBOARD_FAB2(SCH_1):PVDDQ_ABC
    2  GND                B  @BASEBOARD_FAB2_LIB.BASEBOARD_FAB2(SCH_1):GND

CAP_A  I247  C5U2   [CAP_A_0603V-22.0UF,4V,20%,X6S,A]
    1  PVDDQ_ABC          A  @BASEBOARD_FAB2_LIB.BASEBOARD_FAB2(SCH_1):PVDDQ_ABC
    2  GND                B  @BASEBOARD_FAB2_LIB.BASEBOARD_FAB2(SCH_1):GND

CAP_A  I244  C5U3   [CAP_A_0603V-22.0UF,4V,20%,X6S,A]
    1  PVDDQ_ABC          A  @BASEBOARD_FAB2_LIB.BASEBOARD_FAB2(SCH_1):PVDDQ_ABC
    2  GND                B  @BASEBOARD_FAB2_LIB.BASEBOARD_FAB2(SCH_1):GND

CAP_A  I243  C5U4   [CAP_A_0603V-22.0UF,4V,20%,X6S,A]
    1  PVDDQ_ABC          A  @BASEBOARD_FAB2_LIB.BASEBOARD_FAB2(SCH_1):PVDDQ_ABC
    2  GND                B  @BASEBOARD_FAB2_LIB.BASEBOARD_FAB2(SCH_1):GND

CAP_A  I239  C5U5   [CAP_A_0603V-22.0UF,4V,20%,X6S,A]
    1  PVDDQ_ABC          A  @BASEBOARD_FAB2_LIB.BASEBOARD_FAB2(SCH_1):PVDDQ_ABC
    2  GND                B  @BASEBOARD_FAB2_LIB.BASEBOARD_FAB2(SCH_1):GND

CAP_A  I238  C5U6   [CAP_A_0603V-22.0UF,4V,20%,X6S,A]
    1  PVDDQ_ABC          A  @BASEBOARD_FAB2_LIB.BASEBOARD_FAB2(SCH_1):PVDDQ_ABC
    2  GND                B  @BASEBOARD_FAB2_LIB.BASEBOARD_FAB2(SCH_1):GND

CAP_A  I236  C5U7   [CAP_A_0603V-22.0UF,4V,20%,X6S,A]
    1  PVDDQ_ABC          A  @BASEBOARD_FAB2_LIB.BASEBOARD_FAB2(SCH_1):PVDDQ_ABC
    2  GND                B  @BASEBOARD_FAB2_LIB.BASEBOARD_FAB2(SCH_1):GND

CAP_A  I233  C5U8   [CAP_A_0603V-22.0UF,4V,20%,X6S,A]
    1  PVDDQ_ABC          A  @BASEBOARD_FAB2_LIB.BASEBOARD_FAB2(SCH_1):PVDDQ_ABC
    2  GND                B  @BASEBOARD_FAB2_LIB.BASEBOARD_FAB2(SCH_1):GND

CAP_A  I232  C5U9   [CAP_A_0603V-22.0UF,4V,20%,X6S,A]
    1  PVDDQ_ABC          A  @BASEBOARD_FAB2_LIB.BASEBOARD_FAB2(SCH_1):PVDDQ_ABC
    2  GND                B  @BASEBOARD_FAB2_LIB.BASEBOARD_FAB2(SCH_1):GND

CAP  I83  C5U10  [CAP_0805-100UF,4V,20%,X5R,6024A]
    1  PVDDQ_ABC          A  @BASEBOARD_FAB2_LIB.BASEBOARD_FAB2(SCH_1):PVDDQ_ABC
    2  GND                B  @BASEBOARD_FAB2_LIB.BASEBOARD_FAB2(SCH_1):GND

CAP_A  I209  C5U11  [CAP_A_0603V-47UF,4V,20%,X5R,60A]
    1  PVDDQ_ABC          A  @BASEBOARD_FAB2_LIB.BASEBOARD_FAB2(SCH_1):PVDDQ_ABC
    2  GND                B  @BASEBOARD_FAB2_LIB.BASEBOARD_FAB2(SCH_1):GND

CAP_A  I50  C5U12  [CAP_A_0603V-47UF,4V,20%,X5R,60A]
    1  PVTT_ABC           A  @BASEBOARD_FAB2_LIB.BASEBOARD_FAB2(SCH_1):PVTT_ABC
    2  GND                B  @BASEBOARD_FAB2_LIB.BASEBOARD_FAB2(SCH_1):GND

CAP  I82  C5U13  [CAP_0805-100UF,4V,20%,X5R,6024A]
    1  PVDDQ_ABC          A  @BASEBOARD_FAB2_LIB.BASEBOARD_FAB2(SCH_1):PVDDQ_ABC
    2  GND                B  @BASEBOARD_FAB2_LIB.BASEBOARD_FAB2(SCH_1):GND

CAP  I89  C5U14  [CAP_0805-100UF,4V,20%,X5R,6024A]
    1  PVDDQ_ABC          A  @BASEBOARD_FAB2_LIB.BASEBOARD_FAB2(SCH_1):PVDDQ_ABC
    2  GND                B  @BASEBOARD_FAB2_LIB.BASEBOARD_FAB2(SCH_1):GND

CAP  I90  C5U15  [CAP_0805-100UF,4V,20%,X5R,6024A]
    1  PVDDQ_ABC          A  @BASEBOARD_FAB2_LIB.BASEBOARD_FAB2(SCH_1):PVDDQ_ABC
    2  GND                B  @BASEBOARD_FAB2_LIB.BASEBOARD_FAB2(SCH_1):GND

CAP_A  I52  C5U16  [CAP_A_0603V-47UF,4V,20%,X5R,60A]
    1  PVTT_ABC           A  @BASEBOARD_FAB2_LIB.BASEBOARD_FAB2(SCH_1):PVTT_ABC
    2  GND                B  @BASEBOARD_FAB2_LIB.BASEBOARD_FAB2(SCH_1):GND

CAP  I87  C6A1   [CAP_0805LF-22UF,4V,20%,X6S,C95A]
    1  PVDDQ_DEF          A  @BASEBOARD_FAB2_LIB.BASEBOARD_FAB2(SCH_1):PVDDQ_DEF
    2  GND                B  @BASEBOARD_FAB2_LIB.BASEBOARD_FAB2(SCH_1):GND

CAP  I105  C6A2   [CAP_0603LF-10UF,4V,20%,X6S,E15A]
    1  PVPP_DEF           A  @BASEBOARD_FAB2_LIB.BASEBOARD_FAB2(SCH_1):PVPP_DEF
    2  GND                B  @BASEBOARD_FAB2_LIB.BASEBOARD_FAB2(SCH_1):GND

CAP  I104  C6A3   [CAP_0603LF-10UF,4V,20%,X6S,E15A]
    1  PVPP_DEF           A  @BASEBOARD_FAB2_LIB.BASEBOARD_FAB2(SCH_1):PVPP_DEF
    2  GND                B  @BASEBOARD_FAB2_LIB.BASEBOARD_FAB2(SCH_1):GND

CAP  I68  C6A4   [CAP_0805LF-22UF,4V,20%,X6S,C95A]
    1  PVDDQ_DEF          A  @BASEBOARD_FAB2_LIB.BASEBOARD_FAB2(SCH_1):PVDDQ_DEF
    2  GND                B  @BASEBOARD_FAB2_LIB.BASEBOARD_FAB2(SCH_1):GND

CAPP  I77  C6A5   [CAPP_3018-470UF,2.5V,20%,ALUM,A]
    1  PVDDQ_DEF          A  @BASEBOARD_FAB2_LIB.BASEBOARD_FAB2(SCH_1):PVDDQ_DEF
    2  GND                B  @BASEBOARD_FAB2_LIB.BASEBOARD_FAB2(SCH_1):GND

CAP  I110  C6A6   [CAP_0603LF-10UF,4V,20%,X6S,E15A]
    1  PVPP_DEF           A  @BASEBOARD_FAB2_LIB.BASEBOARD_FAB2(SCH_1):PVPP_DEF
    2  GND                B  @BASEBOARD_FAB2_LIB.BASEBOARD_FAB2(SCH_1):GND

CAP  I109  C6A7   [CAP_0603LF-10UF,4V,20%,X6S,E15A]
    1  PVPP_DEF           A  @BASEBOARD_FAB2_LIB.BASEBOARD_FAB2(SCH_1):PVPP_DEF
    2  GND                B  @BASEBOARD_FAB2_LIB.BASEBOARD_FAB2(SCH_1):GND

CAP  I128  C6B1   [CAP_0603LF-10UF,4V,20%,X6S,E15A]
    1  PVPP_DEF           A  @BASEBOARD_FAB2_LIB.BASEBOARD_FAB2(SCH_1):PVPP_DEF
    2  GND                B  @BASEBOARD_FAB2_LIB.BASEBOARD_FAB2(SCH_1):GND

CAP  I126  C6B2   [CAP_0603LF-10UF,4V,20%,X6S,E15A]
    1  PVPP_DEF           A  @BASEBOARD_FAB2_LIB.BASEBOARD_FAB2(SCH_1):PVPP_DEF
    2  GND                B  @BASEBOARD_FAB2_LIB.BASEBOARD_FAB2(SCH_1):GND

CAP  I236  C6B3   [CAP_0805-47UF,4V,20%,X6S,C9533A]
    1  PVPP_DEF           A  @BASEBOARD_FAB2_LIB.BASEBOARD_FAB2(SCH_1):PVPP_DEF
    2  GND                B  @BASEBOARD_FAB2_LIB.BASEBOARD_FAB2(SCH_1):GND

CAP_0402  I196  C6B4   [CAP_0402-0.22UF,16V,10%,X7R,A3A]
    1  P3E_CPU0_PE1_PCH_TXN<15>      A  @BASEBOARD_FAB2_LIB.BASEBOARD_FAB2(SCH_1):P3E_CPU0_PE1_PCH_TXN<15>
    2  P3E_CPU0_PE1_PCH_C_TXN<15>      B  @BASEBOARD_FAB2_LIB.BASEBOARD_FAB2(SCH_1):P3E_CPU0_PE1_PCH_C_TXN<15>

CAP_0402  I201  C6B5   [CAP_0402-0.22UF,16V,10%,X7R,A3A]
    1  P3E_CPU0_PE1_PCH_TXP<15>      A  @BASEBOARD_FAB2_LIB.BASEBOARD_FAB2(SCH_1):P3E_CPU0_PE1_PCH_TXP<15>
    2  P3E_CPU0_PE1_PCH_C_TXP<15>      B  @BASEBOARD_FAB2_LIB.BASEBOARD_FAB2(SCH_1):P3E_CPU0_PE1_PCH_C_TXP<15>

CAP_0402  I169  C6B6   [CAP_0402-0.22UF,16V,10%,X7R,A3A]
    1  P3E_CPU0_PE1_PCH_TXN<14>      A  @BASEBOARD_FAB2_LIB.BASEBOARD_FAB2(SCH_1):P3E_CPU0_PE1_PCH_TXN<14>
    2  P3E_CPU0_PE1_PCH_C_TXN<14>      B  @BASEBOARD_FAB2_LIB.BASEBOARD_FAB2(SCH_1):P3E_CPU0_PE1_PCH_C_TXN<14>

CAPP  I229  C6B7   [CAPP_7343LF-330UF,6.3V,20%,POSA]
    1  PVPP_DEF           A  @BASEBOARD_FAB2_LIB.BASEBOARD_FAB2(SCH_1):PVPP_DEF
    2  GND                B  @BASEBOARD_FAB2_LIB.BASEBOARD_FAB2(SCH_1):GND

CAP_0402  I198  C6B8   [CAP_0402-0.22UF,16V,10%,X7R,A3A]
    1  P3E_CPU0_PE1_PCH_TXP<14>      A  @BASEBOARD_FAB2_LIB.BASEBOARD_FAB2(SCH_1):P3E_CPU0_PE1_PCH_TXP<14>
    2  P3E_CPU0_PE1_PCH_C_TXP<14>      B  @BASEBOARD_FAB2_LIB.BASEBOARD_FAB2(SCH_1):P3E_CPU0_PE1_PCH_C_TXP<14>

CAP_0402  I185  C6B9   [CAP_0402-0.22UF,16V,10%,X7R,A3A]
    1  P3E_CPU0_PE1_PCH_TXN<13>      A  @BASEBOARD_FAB2_LIB.BASEBOARD_FAB2(SCH_1):P3E_CPU0_PE1_PCH_TXN<13>
    2  P3E_CPU0_PE1_PCH_C_TXN<13>      B  @BASEBOARD_FAB2_LIB.BASEBOARD_FAB2(SCH_1):P3E_CPU0_PE1_PCH_C_TXN<13>

CAP_0402  I193  C6B10  [CAP_0402-0.22UF,16V,10%,X7R,A3A]
    1  P3E_CPU0_PE1_PCH_TXP<13>      A  @BASEBOARD_FAB2_LIB.BASEBOARD_FAB2(SCH_1):P3E_CPU0_PE1_PCH_TXP<13>
    2  P3E_CPU0_PE1_PCH_C_TXP<13>      B  @BASEBOARD_FAB2_LIB.BASEBOARD_FAB2(SCH_1):P3E_CPU0_PE1_PCH_C_TXP<13>

CAP_0402  I166  C6B11  [CAP_0402-0.22UF,16V,10%,X7R,A3A]
    1  P3E_CPU0_PE1_PCH_TXN<12>      A  @BASEBOARD_FAB2_LIB.BASEBOARD_FAB2(SCH_1):P3E_CPU0_PE1_PCH_TXN<12>
    2  P3E_CPU0_PE1_PCH_C_TXN<12>      B  @BASEBOARD_FAB2_LIB.BASEBOARD_FAB2(SCH_1):P3E_CPU0_PE1_PCH_C_TXN<12>

CAP_0402  I187  C6B12  [CAP_0402-0.22UF,16V,10%,X7R,A3A]
    1  P3E_CPU0_PE1_PCH_TXP<12>      A  @BASEBOARD_FAB2_LIB.BASEBOARD_FAB2(SCH_1):P3E_CPU0_PE1_PCH_TXP<12>
    2  P3E_CPU0_PE1_PCH_C_TXP<12>      B  @BASEBOARD_FAB2_LIB.BASEBOARD_FAB2(SCH_1):P3E_CPU0_PE1_PCH_C_TXP<12>

CAP_0402  I189  C6B13  [CAP_0402-0.22UF,16V,10%,X7R,A3A]
    1  P3E_CPU0_PE1_PCH_TXP<11>      A  @BASEBOARD_FAB2_LIB.BASEBOARD_FAB2(SCH_1):P3E_CPU0_PE1_PCH_TXP<11>
    2  P3E_CPU0_PE1_PCH_C_TXP<11>      B  @BASEBOARD_FAB2_LIB.BASEBOARD_FAB2(SCH_1):P3E_CPU0_PE1_PCH_C_TXP<11>

CAP_0402  I181  C6B14  [CAP_0402-0.22UF,16V,10%,X7R,A3A]
    1  P3E_CPU0_PE1_PCH_TXN<11>      A  @BASEBOARD_FAB2_LIB.BASEBOARD_FAB2(SCH_1):P3E_CPU0_PE1_PCH_TXN<11>
    2  P3E_CPU0_PE1_PCH_C_TXN<11>      B  @BASEBOARD_FAB2_LIB.BASEBOARD_FAB2(SCH_1):P3E_CPU0_PE1_PCH_C_TXN<11>

CAP_0402  I163  C6B15  [CAP_0402-0.22UF,16V,10%,X7R,A3A]
    1  P3E_CPU0_PE1_PCH_TXN<10>      A  @BASEBOARD_FAB2_LIB.BASEBOARD_FAB2(SCH_1):P3E_CPU0_PE1_PCH_TXN<10>
    2  P3E_CPU0_PE1_PCH_C_TXN<10>      B  @BASEBOARD_FAB2_LIB.BASEBOARD_FAB2(SCH_1):P3E_CPU0_PE1_PCH_C_TXN<10>

CAP_0402  I180  C6B16  [CAP_0402-0.22UF,16V,10%,X7R,A3A]
    1  P3E_CPU0_PE1_PCH_TXP<10>      A  @BASEBOARD_FAB2_LIB.BASEBOARD_FAB2(SCH_1):P3E_CPU0_PE1_PCH_TXP<10>
    2  P3E_CPU0_PE1_PCH_C_TXP<10>      B  @BASEBOARD_FAB2_LIB.BASEBOARD_FAB2(SCH_1):P3E_CPU0_PE1_PCH_C_TXP<10>

CAP_0402  I175  C6B17  [CAP_0402-0.22UF,16V,10%,X7R,A3A]
    1  P3E_CPU0_PE1_PCH_TXN<9>      A  @BASEBOARD_FAB2_LIB.BASEBOARD_FAB2(SCH_1):P3E_CPU0_PE1_PCH_TXN<9>
    2  P3E_CPU0_PE1_PCH_C_TXN<9>      B  @BASEBOARD_FAB2_LIB.BASEBOARD_FAB2(SCH_1):P3E_CPU0_PE1_PCH_C_TXN<9>

CAP_0402  I153  C6B18  [CAP_0402-0.22UF,16V,10%,X7R,A3A]
    1  P3E_CPU0_PE1_PCH_TXP<9>      A  @BASEBOARD_FAB2_LIB.BASEBOARD_FAB2(SCH_1):P3E_CPU0_PE1_PCH_TXP<9>
    2  P3E_CPU0_PE1_PCH_C_TXP<9>      B  @BASEBOARD_FAB2_LIB.BASEBOARD_FAB2(SCH_1):P3E_CPU0_PE1_PCH_C_TXP<9>

CAP_0402  I160  C6B19  [CAP_0402-0.22UF,16V,10%,X7R,A3A]
    1  P3E_CPU0_PE1_PCH_TXN<8>      A  @BASEBOARD_FAB2_LIB.BASEBOARD_FAB2(SCH_1):P3E_CPU0_PE1_PCH_TXN<8>
    2  P3E_CPU0_PE1_PCH_C_TXN<8>      B  @BASEBOARD_FAB2_LIB.BASEBOARD_FAB2(SCH_1):P3E_CPU0_PE1_PCH_C_TXN<8>

CAP_0402  I173  C6B20  [CAP_0402-0.22UF,16V,10%,X7R,A3A]
    1  P3E_CPU0_PE1_PCH_TXP<8>      A  @BASEBOARD_FAB2_LIB.BASEBOARD_FAB2(SCH_1):P3E_CPU0_PE1_PCH_TXP<8>
    2  P3E_CPU0_PE1_PCH_C_TXP<8>      B  @BASEBOARD_FAB2_LIB.BASEBOARD_FAB2(SCH_1):P3E_CPU0_PE1_PCH_C_TXP<8>

CAP  I19  C6D1   [CAP_0603LF-10UF,4V,20%,X6S,E15A]
    1  P1V8_MCP_CPU0      A  @BASEBOARD_FAB2_LIB.BASEBOARD_FAB2(SCH_1):P1V8_MCP_CPU0
    2  GND                B  @BASEBOARD_FAB2_LIB.BASEBOARD_FAB2(SCH_1):GND

CAP_A  I77  C6D2   [CAP_A_0603V-22.0UF,4V,20%,X6S,A]
    1  PVCCMCP_CPU0       A  @BASEBOARD_FAB2_LIB.BASEBOARD_FAB2(SCH_1):PVCCMCP_CPU0
    2  GND                B  @BASEBOARD_FAB2_LIB.BASEBOARD_FAB2(SCH_1):GND

CAP_A  I80  C6D3   [CAP_A_0603V-22.0UF,4V,20%,X6S,A]
    1  PVCCIO_CPU0        A  @BASEBOARD_FAB2_LIB.BASEBOARD_FAB2(SCH_1):PVCCIO_CPU0
    2  GND                B  @BASEBOARD_FAB2_LIB.BASEBOARD_FAB2(SCH_1):GND

CAP_A  I74  C6D4   [CAP_A_0603V-22.0UF,4V,20%,X6S,A]
    1  PVCCIO_CPU0        A  @BASEBOARD_FAB2_LIB.BASEBOARD_FAB2(SCH_1):PVCCIO_CPU0
    2  GND                B  @BASEBOARD_FAB2_LIB.BASEBOARD_FAB2(SCH_1):GND

CAP_A  I75  C6D5   [CAP_A_0603V-22.0UF,4V,20%,X6S,A]
    1  PVCCMCP_CPU0       A  @BASEBOARD_FAB2_LIB.BASEBOARD_FAB2(SCH_1):PVCCMCP_CPU0
    2  GND                B  @BASEBOARD_FAB2_LIB.BASEBOARD_FAB2(SCH_1):GND

CAP_A  I81  C6D6   [CAP_A_0603V-22.0UF,4V,20%,X6S,A]
    1  PVCCIO_CPU0        A  @BASEBOARD_FAB2_LIB.BASEBOARD_FAB2(SCH_1):PVCCIO_CPU0
    2  GND                B  @BASEBOARD_FAB2_LIB.BASEBOARD_FAB2(SCH_1):GND

CAP_A  I72  C6D7   [CAP_A_0603V-22.0UF,4V,20%,X6S,A]
    1  PVCCIO_CPU0        A  @BASEBOARD_FAB2_LIB.BASEBOARD_FAB2(SCH_1):PVCCIO_CPU0
    2  GND                B  @BASEBOARD_FAB2_LIB.BASEBOARD_FAB2(SCH_1):GND

CAP_A  I68  C6D8   [CAP_A_0603V-22.0UF,4V,20%,X6S,A]
    1  PVCCMCP_CPU0       A  @BASEBOARD_FAB2_LIB.BASEBOARD_FAB2(SCH_1):PVCCMCP_CPU0
    2  GND                B  @BASEBOARD_FAB2_LIB.BASEBOARD_FAB2(SCH_1):GND

CAP_A  I145  C6D9   [CAP_A_0603V-22.0UF,4V,20%,X6S,A]
    1  PVCCIO_CPU0        A  @BASEBOARD_FAB2_LIB.BASEBOARD_FAB2(SCH_1):PVCCIO_CPU0
    2  GND                B  @BASEBOARD_FAB2_LIB.BASEBOARD_FAB2(SCH_1):GND

CAP_A  I147  C6D10  [CAP_A_0603V-22.0UF,4V,20%,X6S,A]
    1  PVCCIO_CPU0        A  @BASEBOARD_FAB2_LIB.BASEBOARD_FAB2(SCH_1):PVCCIO_CPU0
    2  GND                B  @BASEBOARD_FAB2_LIB.BASEBOARD_FAB2(SCH_1):GND

CAP_A  I25  C6F1   [CAP_A_0402V-0.1UF,16V,10%,X7R,A]
    1  P3V3               A  @BASEBOARD_FAB2_LIB.BASEBOARD_FAB2(SCH_1):P3V3
    2  GND                B  @BASEBOARD_FAB2_LIB.BASEBOARD_FAB2(SCH_1):GND

CAP_A  I2   C6F2   [CAP_A_0402V-0.1UF,16V,10%,X7R,A]
    1  PVCCIO_CPU0        A  @BASEBOARD_FAB2_LIB.BASEBOARD_FAB2(SCH_1):PVCCIO_CPU0
    2  GND                B  @BASEBOARD_FAB2_LIB.BASEBOARD_FAB2(SCH_1):GND

CAP_A  I7   C6F3   [CAP_A_0402V-0.1UF,16V,10%,X7R,A]
    1  PVPP_ABC           A  @BASEBOARD_FAB2_LIB.BASEBOARD_FAB2(SCH_1):PVPP_ABC
    2  GND                B  @BASEBOARD_FAB2_LIB.BASEBOARD_FAB2(SCH_1):GND

CAPP  I180  C6F4   [CAPP_7343LF-330UF,6.3V,20%,POSA]
    1  PVPP_ABC           A  @BASEBOARD_FAB2_LIB.BASEBOARD_FAB2(SCH_1):PVPP_ABC
    2  GND                B  @BASEBOARD_FAB2_LIB.BASEBOARD_FAB2(SCH_1):GND

CAP  I149  C6F5   [CAP_0603LF-10UF,4V,20%,X6S,E15A]
    1  PVPP_ABC           A  @BASEBOARD_FAB2_LIB.BASEBOARD_FAB2(SCH_1):PVPP_ABC
    2  GND                B  @BASEBOARD_FAB2_LIB.BASEBOARD_FAB2(SCH_1):GND

CAP  I122  C6F6   [CAP_0603LF-10UF,4V,20%,X6S,E15A]
    1  PVPP_ABC           A  @BASEBOARD_FAB2_LIB.BASEBOARD_FAB2(SCH_1):PVPP_ABC
    2  GND                B  @BASEBOARD_FAB2_LIB.BASEBOARD_FAB2(SCH_1):GND

CAP  I126  C6G1   [CAP_0603LF-10UF,4V,20%,X6S,E15A]
    1  PVPP_ABC           A  @BASEBOARD_FAB2_LIB.BASEBOARD_FAB2(SCH_1):PVPP_ABC
    2  GND                B  @BASEBOARD_FAB2_LIB.BASEBOARD_FAB2(SCH_1):GND

CAP  I128  C6G2   [CAP_0603LF-10UF,4V,20%,X6S,E15A]
    1  PVPP_ABC           A  @BASEBOARD_FAB2_LIB.BASEBOARD_FAB2(SCH_1):PVPP_ABC
    2  GND                B  @BASEBOARD_FAB2_LIB.BASEBOARD_FAB2(SCH_1):GND

CAP  I6   C6G3   [CAP_0805LF-22UF,4V,20%,X6S,C95A]
    1  PVDDQ_ABC          A  @BASEBOARD_FAB2_LIB.BASEBOARD_FAB2(SCH_1):PVDDQ_ABC
    2  GND                B  @BASEBOARD_FAB2_LIB.BASEBOARD_FAB2(SCH_1):GND

CAP  I131  C6G4   [CAP_0603LF-10UF,4V,20%,X6S,E15A]
    1  PVPP_ABC           A  @BASEBOARD_FAB2_LIB.BASEBOARD_FAB2(SCH_1):PVPP_ABC
    2  GND                B  @BASEBOARD_FAB2_LIB.BASEBOARD_FAB2(SCH_1):GND

CAP  I145  C6G5   [CAP_0603LF-10UF,4V,20%,X6S,E15A]
    1  PVPP_ABC           A  @BASEBOARD_FAB2_LIB.BASEBOARD_FAB2(SCH_1):PVPP_ABC
    2  GND                B  @BASEBOARD_FAB2_LIB.BASEBOARD_FAB2(SCH_1):GND

CAP_A  I178  C6L1   [CAP_A_0402V-0.01UF,25V,10%,X7RA]
    1  M_F_VREF           A  @BASEBOARD_FAB2_LIB.BASEBOARD_FAB2(SCH_1):M_F_VREF
    2  GND                B  @BASEBOARD_FAB2_LIB.BASEBOARD_FAB2(SCH_1):GND

CAP_A  I67  C6L2   [CAP_A_0402V-0.01UF,25V,10%,X7RA]
    1  M_F_CPU_VREF       A  @BASEBOARD_FAB2_LIB.BASEBOARD_FAB2(SCH_1):M_F_CPU_VREF
    2  GND                B  @BASEBOARD_FAB2_LIB.BASEBOARD_FAB2(SCH_1):GND

CAP  I24  C6L3   [CAP_0603LF-10UF,4V,20%,X6S,E15A]
    1  PVDDQ_DEF          A  @BASEBOARD_FAB2_LIB.BASEBOARD_FAB2(SCH_1):PVDDQ_DEF
    2  GND                B  @BASEBOARD_FAB2_LIB.BASEBOARD_FAB2(SCH_1):GND

CAP  I26  C6L4   [CAP_0603LF-10UF,4V,20%,X6S,E15A]
    1  PVDDQ_DEF          A  @BASEBOARD_FAB2_LIB.BASEBOARD_FAB2(SCH_1):PVDDQ_DEF
    2  GND                B  @BASEBOARD_FAB2_LIB.BASEBOARD_FAB2(SCH_1):GND

CAP  I26  C6L5   [CAP_0603LF-10UF,4V,20%,X6S,E15A]
    1  PVDDQ_KLM          A  @BASEBOARD_FAB2_LIB.BASEBOARD_FAB2(SCH_1):PVDDQ_KLM
    2  GND                B  @BASEBOARD_FAB2_LIB.BASEBOARD_FAB2(SCH_1):GND

CAP_A  I175  C6L6   [CAP_A_0402V-0.01UF,25V,10%,X7RA]
    1  M_E_VREF           A  @BASEBOARD_FAB2_LIB.BASEBOARD_FAB2(SCH_1):M_E_VREF
    2  GND                B  @BASEBOARD_FAB2_LIB.BASEBOARD_FAB2(SCH_1):GND

CAP_A  I59  C6L7   [CAP_A_0402V-0.01UF,25V,10%,X7RA]
    1  M_E_CPU_VREF       A  @BASEBOARD_FAB2_LIB.BASEBOARD_FAB2(SCH_1):M_E_CPU_VREF
    2  GND                B  @BASEBOARD_FAB2_LIB.BASEBOARD_FAB2(SCH_1):GND

CAPP  I210  C6L8   [CAPP_7343-220UF,4V,20%,POSCAP,A]
    1  PVPP_KLM           A  @BASEBOARD_FAB2_LIB.BASEBOARD_FAB2(SCH_1):PVPP_KLM
    2  GND                B  @BASEBOARD_FAB2_LIB.BASEBOARD_FAB2(SCH_1):GND

CAP  I202  C6L10  [CAP_0805-10UF,16V,10%,X6S,C953A]
    1  VR_FET_SW_P12V_STBY_PVPP_KLM      A  @BASEBOARD_FAB2_LIB.BASEBOARD_FAB2(SCH_1):VR_FET_SW_P12V_STBY_PVPP_KLM
    2  GND                B  @BASEBOARD_FAB2_LIB.BASEBOARD_FAB2(SCH_1):GND

CAP_0402  I152  C6L11  [CAP_0402-1.0UF,16V,10%,X6S,D97A]
    1  VR_FET_SW_P12V_STBY_PVPP_KLM      A  @BASEBOARD_FAB2_LIB.BASEBOARD_FAB2(SCH_1):VR_FET_SW_P12V_STBY_PVPP_KLM
    2  GND                B  @BASEBOARD_FAB2_LIB.BASEBOARD_FAB2(SCH_1):GND

CAP  I144  C6L12  [CAP_0603-4.7UF,6.3V,10%,X6S,E1A]
    1  VR_VB_PVPP_KLM      A  @BASEBOARD_FAB2_LIB.BASEBOARD_FAB2(SCH_1):VR_VB_PVPP_KLM
    2  AGND_PVPP_KLM      B  @BASEBOARD_FAB2_LIB.BASEBOARD_FAB2(SCH_1):AGND_PVPP_KLM

CAP_A  I177  C6M1   [CAP_A_0402V-0.01UF,25V,10%,X7RA]
    1  M_D_VREF           A  @BASEBOARD_FAB2_LIB.BASEBOARD_FAB2(SCH_1):M_D_VREF
    2  GND                B  @BASEBOARD_FAB2_LIB.BASEBOARD_FAB2(SCH_1):GND

CAP_A  I33  C6M2   [CAP_A_0402V-0.01UF,25V,10%,X7RA]
    1  M_D_CPU_VREF       A  @BASEBOARD_FAB2_LIB.BASEBOARD_FAB2(SCH_1):M_D_CPU_VREF
    2  GND                B  @BASEBOARD_FAB2_LIB.BASEBOARD_FAB2(SCH_1):GND

CAP  I203  C6M3   [CAP_0805-10UF,16V,10%,X6S,C953A]
    1  VR_FET_SW_P12V_STBY_PVPP_KLM      A  @BASEBOARD_FAB2_LIB.BASEBOARD_FAB2(SCH_1):VR_FET_SW_P12V_STBY_PVPP_KLM
    2  GND                B  @BASEBOARD_FAB2_LIB.BASEBOARD_FAB2(SCH_1):GND

CAP  I204  C6M5   [CAP_0805-10UF,16V,10%,X6S,C953A]
    1  VR_FET_SW_P12V_STBY_PVPP_KLM      A  @BASEBOARD_FAB2_LIB.BASEBOARD_FAB2(SCH_1):VR_FET_SW_P12V_STBY_PVPP_KLM
    2  GND                B  @BASEBOARD_FAB2_LIB.BASEBOARD_FAB2(SCH_1):GND

CAP_A  I250  C6M6   [CAP_A_0402V-0.1UF,16V,10%,X7R,A]
    1  JTAG_MCP_CPU1_TDI_R      A  @BASEBOARD_FAB2_LIB.BASEBOARD_FAB2(SCH_1):JTAG_MCP_CPU1_TDI_R
    2  GND                B  @BASEBOARD_FAB2_LIB.BASEBOARD_FAB2(SCH_1):GND

CAPP  I12  C6N1   [CAPP_3018-470UF,2.5V,20%,ALUM,A]
    1  PVSA_CPU0          A  @BASEBOARD_FAB2_LIB.BASEBOARD_FAB2(SCH_1):PVSA_CPU0
    2  GND                B  @BASEBOARD_FAB2_LIB.BASEBOARD_FAB2(SCH_1):GND

CAP  I33  C6N2   [CAP_0805-10UF,16V,10%,X6S,C953A]
    1  VR_FET_SW_P12V_STBY_PVCCIN_CPU0      A  @BASEBOARD_FAB2_LIB.BASEBOARD_FAB2(SCH_1):VR_FET_SW_P12V_STBY_PVCCIN_CPU0
    2  GND                B  @BASEBOARD_FAB2_LIB.BASEBOARD_FAB2(SCH_1):GND

CAP  I34  C6N3   [CAP_0805-10UF,16V,10%,X6S,C953A]
    1  VR_FET_SW_P12V_STBY_PVCCIN_CPU0      A  @BASEBOARD_FAB2_LIB.BASEBOARD_FAB2(SCH_1):VR_FET_SW_P12V_STBY_PVCCIN_CPU0
    2  GND                B  @BASEBOARD_FAB2_LIB.BASEBOARD_FAB2(SCH_1):GND

CAPP  I14  C6N4   [CAPP_3018-470UF,2.5V,20%,ALUM,A]
    1  PVSA_CPU0          A  @BASEBOARD_FAB2_LIB.BASEBOARD_FAB2(SCH_1):PVSA_CPU0
    2  GND                B  @BASEBOARD_FAB2_LIB.BASEBOARD_FAB2(SCH_1):GND

CAPP  I109  C6N5   [CAPP_3018-68UF,16V,20%,TANT,72A]
    1  P12V_STBY          A  @BASEBOARD_FAB2_LIB.BASEBOARD_FAB2(SCH_1):P12V_STBY
    2  GND                B  @BASEBOARD_FAB2_LIB.BASEBOARD_FAB2(SCH_1):GND

CAP  I35  C6N6   [CAP_0805-10UF,16V,10%,X6S,C953A]
    1  VR_FET_SW_P12V_STBY_PVCCIN_CPU0      A  @BASEBOARD_FAB2_LIB.BASEBOARD_FAB2(SCH_1):VR_FET_SW_P12V_STBY_PVCCIN_CPU0
    2  GND                B  @BASEBOARD_FAB2_LIB.BASEBOARD_FAB2(SCH_1):GND

CAP_A  I5   C6N7   [CAP_A_0603V-22.0UF,4V,20%,X6S,A]
    1  PVSA_CPU0          A  @BASEBOARD_FAB2_LIB.BASEBOARD_FAB2(SCH_1):PVSA_CPU0
    2  GND                B  @BASEBOARD_FAB2_LIB.BASEBOARD_FAB2(SCH_1):GND

CAP  I51  C6N8   [CAP_0805-10UF,16V,10%,X6S,C953A]
    1  VR_FET_SW_P12V_STBY_PVCCIN_CPU0      A  @BASEBOARD_FAB2_LIB.BASEBOARD_FAB2(SCH_1):VR_FET_SW_P12V_STBY_PVCCIN_CPU0
    2  GND                B  @BASEBOARD_FAB2_LIB.BASEBOARD_FAB2(SCH_1):GND

CAPP  I34  C6N9   [CAPP_3018-470UF,2.5V,20%,ALUM,A]
    1  PVCCIN_CPU0        A  @BASEBOARD_FAB2_LIB.BASEBOARD_FAB2(SCH_1):PVCCIN_CPU0
    2  GND                B  @BASEBOARD_FAB2_LIB.BASEBOARD_FAB2(SCH_1):GND

CAP  I37  C6N10  [CAP_0805-10UF,16V,10%,X6S,C953A]
    1  VR_FET_SW_P12V_STBY_PVCCIN_CPU0      A  @BASEBOARD_FAB2_LIB.BASEBOARD_FAB2(SCH_1):VR_FET_SW_P12V_STBY_PVCCIN_CPU0
    2  GND                B  @BASEBOARD_FAB2_LIB.BASEBOARD_FAB2(SCH_1):GND

CAP  I42  C6N11  [CAP_0805-10UF,16V,10%,X6S,C953A]
    1  VR_FET_SW_P12V_STBY_PVCCIN_CPU0      A  @BASEBOARD_FAB2_LIB.BASEBOARD_FAB2(SCH_1):VR_FET_SW_P12V_STBY_PVCCIN_CPU0
    2  GND                B  @BASEBOARD_FAB2_LIB.BASEBOARD_FAB2(SCH_1):GND

CAP_A  I25  C6P3   [CAP_A_0603V-22.0UF,4V,20%,X6S,A]
    1  PVCCIN_CPU0        A  @BASEBOARD_FAB2_LIB.BASEBOARD_FAB2(SCH_1):PVCCIN_CPU0
    2  GND                B  @BASEBOARD_FAB2_LIB.BASEBOARD_FAB2(SCH_1):GND

CAP_A  I11  C6P4   [CAP_A_0402V-0.1UF,16V,10%,X7R,A]
    1  P3V3_DB1200        A  @BASEBOARD_FAB2_LIB.BASEBOARD_FAB2(SCH_1):P3V3_DB1200
    2  GND                B  @BASEBOARD_FAB2_LIB.BASEBOARD_FAB2(SCH_1):GND

CAP_A  I14  C6P5   [CAP_A_0402V-0.1UF,16V,10%,X7R,A]
    1  P3V3_DB1200        A  @BASEBOARD_FAB2_LIB.BASEBOARD_FAB2(SCH_1):P3V3_DB1200
    2  GND                B  @BASEBOARD_FAB2_LIB.BASEBOARD_FAB2(SCH_1):GND

CAP_A  I12  C6P6   [CAP_A_0402V-0.1UF,16V,10%,X7R,A]
    1  P3V3_DB1200        A  @BASEBOARD_FAB2_LIB.BASEBOARD_FAB2(SCH_1):P3V3_DB1200
    2  GND                B  @BASEBOARD_FAB2_LIB.BASEBOARD_FAB2(SCH_1):GND

CAP  I59  C6P7   [CAP_0805-10UF,16V,10%,X6S,C953A]
    1  VR_FET_SW_P12V_STBY_PVCCIN_CPU0      A  @BASEBOARD_FAB2_LIB.BASEBOARD_FAB2(SCH_1):VR_FET_SW_P12V_STBY_PVCCIN_CPU0
    2  GND                B  @BASEBOARD_FAB2_LIB.BASEBOARD_FAB2(SCH_1):GND

CAPP  I32  C6P8   [CAPP_3018-470UF,2.5V,20%,ALUM,A]
    1  PVCCIN_CPU0        A  @BASEBOARD_FAB2_LIB.BASEBOARD_FAB2(SCH_1):PVCCIN_CPU0
    2  GND                B  @BASEBOARD_FAB2_LIB.BASEBOARD_FAB2(SCH_1):GND

CAP_A  I79  C6P9   [CAP_A_0402V-0.1UF,16V,10%,X7R,A]
    1  P3V3_DB1200        A  @BASEBOARD_FAB2_LIB.BASEBOARD_FAB2(SCH_1):P3V3_DB1200
    2  GND                B  @BASEBOARD_FAB2_LIB.BASEBOARD_FAB2(SCH_1):GND

CAP_A  I13  C6P10  [CAP_A_0402V-0.1UF,16V,10%,X7R,A]
    1  P3V3_DB1200        A  @BASEBOARD_FAB2_LIB.BASEBOARD_FAB2(SCH_1):P3V3_DB1200
    2  GND                B  @BASEBOARD_FAB2_LIB.BASEBOARD_FAB2(SCH_1):GND

CAP_A  I16  C6P11  [CAP_A_0402V-0.1UF,16V,10%,X7R,A]
    1  P3V3_DB1200        A  @BASEBOARD_FAB2_LIB.BASEBOARD_FAB2(SCH_1):P3V3_DB1200
    2  GND                B  @BASEBOARD_FAB2_LIB.BASEBOARD_FAB2(SCH_1):GND

CAP_A  I15  C6P12  [CAP_A_0402V-0.1UF,16V,10%,X7R,A]
    1  P3V3_DB1200        A  @BASEBOARD_FAB2_LIB.BASEBOARD_FAB2(SCH_1):P3V3_DB1200
    2  GND                B  @BASEBOARD_FAB2_LIB.BASEBOARD_FAB2(SCH_1):GND

CAP  I38  C6P13  [CAP_0805-10UF,16V,10%,X6S,C953A]
    1  VR_FET_SW_P12V_STBY_PVCCIN_CPU0      A  @BASEBOARD_FAB2_LIB.BASEBOARD_FAB2(SCH_1):VR_FET_SW_P12V_STBY_PVCCIN_CPU0
    2  GND                B  @BASEBOARD_FAB2_LIB.BASEBOARD_FAB2(SCH_1):GND

CAPP  I29  C6P14  [CAPP_3018-470UF,2.5V,20%,ALUM,A]
    1  PVCCIN_CPU0        A  @BASEBOARD_FAB2_LIB.BASEBOARD_FAB2(SCH_1):PVCCIN_CPU0
    2  GND                B  @BASEBOARD_FAB2_LIB.BASEBOARD_FAB2(SCH_1):GND

CAP  I58  C6P15  [CAP_0805-10UF,16V,10%,X6S,C953A]
    1  VR_FET_SW_P12V_STBY_PVCCIN_CPU0      A  @BASEBOARD_FAB2_LIB.BASEBOARD_FAB2(SCH_1):VR_FET_SW_P12V_STBY_PVCCIN_CPU0
    2  GND                B  @BASEBOARD_FAB2_LIB.BASEBOARD_FAB2(SCH_1):GND

CAP_A  I62  C6P16  [CAP_A_0603V-22.0UF,4V,20%,X6S,A]
    1  PVCCIN_CPU0        A  @BASEBOARD_FAB2_LIB.BASEBOARD_FAB2(SCH_1):PVCCIN_CPU0
    2  GND                B  @BASEBOARD_FAB2_LIB.BASEBOARD_FAB2(SCH_1):GND

CAP  I38  C6P17  [CAP_0805-10UF,16V,10%,X6S,C953A]
    1  VR_FET_SW_P12V_STBY_PVCCIN_CPU0      A  @BASEBOARD_FAB2_LIB.BASEBOARD_FAB2(SCH_1):VR_FET_SW_P12V_STBY_PVCCIN_CPU0
    2  GND                B  @BASEBOARD_FAB2_LIB.BASEBOARD_FAB2(SCH_1):GND

CAPP  I30  C6P18  [CAPP_3018-470UF,2.5V,20%,ALUM,A]
    1  PVCCIN_CPU0        A  @BASEBOARD_FAB2_LIB.BASEBOARD_FAB2(SCH_1):PVCCIN_CPU0
    2  GND                B  @BASEBOARD_FAB2_LIB.BASEBOARD_FAB2(SCH_1):GND

CAP  I54  C6P19  [CAP_0805-10UF,16V,10%,X6S,C953A]
    1  VR_FET_SW_P12V_STBY_PVCCIN_CPU0      A  @BASEBOARD_FAB2_LIB.BASEBOARD_FAB2(SCH_1):VR_FET_SW_P12V_STBY_PVCCIN_CPU0
    2  GND                B  @BASEBOARD_FAB2_LIB.BASEBOARD_FAB2(SCH_1):GND

CAP  I57  C6P20  [CAP_0805-10UF,16V,10%,X6S,C953A]
    1  VR_FET_SW_P12V_STBY_PVCCIN_CPU0      A  @BASEBOARD_FAB2_LIB.BASEBOARD_FAB2(SCH_1):VR_FET_SW_P12V_STBY_PVCCIN_CPU0
    2  GND                B  @BASEBOARD_FAB2_LIB.BASEBOARD_FAB2(SCH_1):GND

CAP_A  I66  C6P21  [CAP_A_0603V-22.0UF,4V,20%,X6S,A]
    1  PVCCIN_CPU0        A  @BASEBOARD_FAB2_LIB.BASEBOARD_FAB2(SCH_1):PVCCIN_CPU0
    2  GND                B  @BASEBOARD_FAB2_LIB.BASEBOARD_FAB2(SCH_1):GND

CAP  I49  C6P22  [CAP_0805-10UF,16V,10%,X6S,C953A]
    1  VR_FET_SW_P12V_STBY_PVCCIN_CPU0      A  @BASEBOARD_FAB2_LIB.BASEBOARD_FAB2(SCH_1):VR_FET_SW_P12V_STBY_PVCCIN_CPU0
    2  GND                B  @BASEBOARD_FAB2_LIB.BASEBOARD_FAB2(SCH_1):GND

CAPP  I28  C6P23  [CAPP_3018-470UF,2.5V,20%,ALUM,A]
    1  PVCCIN_CPU0        A  @BASEBOARD_FAB2_LIB.BASEBOARD_FAB2(SCH_1):PVCCIN_CPU0
    2  GND                B  @BASEBOARD_FAB2_LIB.BASEBOARD_FAB2(SCH_1):GND

CAP  I1   C6P24  [CAP_0805-10UF,16V,10%,X6S,C953A]
    1  VR_FET_SW_P12V_STBY_PVCCIN_CPU0      A  @BASEBOARD_FAB2_LIB.BASEBOARD_FAB2(SCH_1):VR_FET_SW_P12V_STBY_PVCCIN_CPU0
    2  GND                B  @BASEBOARD_FAB2_LIB.BASEBOARD_FAB2(SCH_1):GND

CAP_A  I70  C6R2   [CAP_A_0603V-22.0UF,4V,20%,X6S,A]
    1  PVCCIN_CPU0        A  @BASEBOARD_FAB2_LIB.BASEBOARD_FAB2(SCH_1):PVCCIN_CPU0
    2  GND                B  @BASEBOARD_FAB2_LIB.BASEBOARD_FAB2(SCH_1):GND

CAPP  I16  C6R3   [CAPP_3018-470UF,2.5V,20%,ALUM,A]
    1  PVCCIN_CPU0        A  @BASEBOARD_FAB2_LIB.BASEBOARD_FAB2(SCH_1):PVCCIN_CPU0
    2  GND                B  @BASEBOARD_FAB2_LIB.BASEBOARD_FAB2(SCH_1):GND

CAP  I48  C6R4   [CAP_0805-10UF,16V,10%,X6S,C953A]
    1  VR_FET_SW_P12V_STBY_PVCCIN_CPU0      A  @BASEBOARD_FAB2_LIB.BASEBOARD_FAB2(SCH_1):VR_FET_SW_P12V_STBY_PVCCIN_CPU0
    2  GND                B  @BASEBOARD_FAB2_LIB.BASEBOARD_FAB2(SCH_1):GND

CAPP  I24  C6R5   [CAPP_3018-470UF,2.5V,20%,ALUM,A]
    1  PVCCIO_CPU1        A  @BASEBOARD_FAB2_LIB.BASEBOARD_FAB2(SCH_1):PVCCIO_CPU1
    2  GND                B  @BASEBOARD_FAB2_LIB.BASEBOARD_FAB2(SCH_1):GND

CAP  I2   C6R6   [CAP_0805-10UF,16V,10%,X6S,C953A]
    1  VR_FET_SW_P12V_STBY_PVCCIN_CPU0      A  @BASEBOARD_FAB2_LIB.BASEBOARD_FAB2(SCH_1):VR_FET_SW_P12V_STBY_PVCCIN_CPU0
    2  GND                B  @BASEBOARD_FAB2_LIB.BASEBOARD_FAB2(SCH_1):GND

CAP_A  I9   C6R7   [CAP_A_0603V-22.0UF,4V,20%,X6S,A]
    1  PVCCIN_CPU0        A  @BASEBOARD_FAB2_LIB.BASEBOARD_FAB2(SCH_1):PVCCIN_CPU0
    2  GND                B  @BASEBOARD_FAB2_LIB.BASEBOARD_FAB2(SCH_1):GND

CAP  I83  C6R8   [CAP_0805-10UF,16V,10%,X6S,C953A]
    1  VR_FET_SW_P12V_STBY_PVCCIN_CPU0      A  @BASEBOARD_FAB2_LIB.BASEBOARD_FAB2(SCH_1):VR_FET_SW_P12V_STBY_PVCCIN_CPU0
    2  GND                B  @BASEBOARD_FAB2_LIB.BASEBOARD_FAB2(SCH_1):GND

CAPP  I18  C6R9   [CAPP_3018-470UF,2.5V,20%,ALUM,A]
    1  PVCCIN_CPU0        A  @BASEBOARD_FAB2_LIB.BASEBOARD_FAB2(SCH_1):PVCCIN_CPU0
    2  GND                B  @BASEBOARD_FAB2_LIB.BASEBOARD_FAB2(SCH_1):GND

CAP  I81  C6R10  [CAP_0805-10UF,16V,10%,X6S,C953A]
    1  VR_FET_SW_P12V_STBY_PVCCIN_CPU0      A  @BASEBOARD_FAB2_LIB.BASEBOARD_FAB2(SCH_1):VR_FET_SW_P12V_STBY_PVCCIN_CPU0
    2  GND                B  @BASEBOARD_FAB2_LIB.BASEBOARD_FAB2(SCH_1):GND

CAP  I37  C6R11  [CAP_0805-10UF,16V,10%,X6S,C953A]
    1  VR_FET_SW_P12V_STBY_PVCCIN_CPU0      A  @BASEBOARD_FAB2_LIB.BASEBOARD_FAB2(SCH_1):VR_FET_SW_P12V_STBY_PVCCIN_CPU0
    2  GND                B  @BASEBOARD_FAB2_LIB.BASEBOARD_FAB2(SCH_1):GND

CAPP  I21  C6R12  [CAPP_3018-470UF,2.5V,20%,ALUM,A]
    1  PVCCIO_CPU1        A  @BASEBOARD_FAB2_LIB.BASEBOARD_FAB2(SCH_1):PVCCIO_CPU1
    2  GND                B  @BASEBOARD_FAB2_LIB.BASEBOARD_FAB2(SCH_1):GND

CAP  I42  C6R13  [CAP_0805-10UF,16V,10%,X6S,C953A]
    1  VR_FET_SW_P12V_STBY_PVCCIN_CPU0      A  @BASEBOARD_FAB2_LIB.BASEBOARD_FAB2(SCH_1):VR_FET_SW_P12V_STBY_PVCCIN_CPU0
    2  GND                B  @BASEBOARD_FAB2_LIB.BASEBOARD_FAB2(SCH_1):GND

CAP  I80  C6R14  [CAP_0805-10UF,16V,10%,X6S,C953A]
    1  VR_FET_SW_P12V_STBY_PVCCIN_CPU0      A  @BASEBOARD_FAB2_LIB.BASEBOARD_FAB2(SCH_1):VR_FET_SW_P12V_STBY_PVCCIN_CPU0
    2  GND                B  @BASEBOARD_FAB2_LIB.BASEBOARD_FAB2(SCH_1):GND

CAPP  I62  C6R16  [CAPP_3018-470UF,2.5V,20%,ALUM,A]
    1  PVCCMCP_CPU1       A  @BASEBOARD_FAB2_LIB.BASEBOARD_FAB2(SCH_1):PVCCMCP_CPU1
    2  GND                B  @BASEBOARD_FAB2_LIB.BASEBOARD_FAB2(SCH_1):GND

CAP_A  I2   C6T1   [CAP_A_0402V-0.01UF,25V,10%,X7RA]
    1  M_A_VREF           A  @BASEBOARD_FAB2_LIB.BASEBOARD_FAB2(SCH_1):M_A_VREF
    2  GND                B  @BASEBOARD_FAB2_LIB.BASEBOARD_FAB2(SCH_1):GND

CAP  I54  C6T2   [CAP_0805-10UF,16V,10%,X7R,G106A]
    1  P12V_NVDIMM_ABC      A  @BASEBOARD_FAB2_LIB.BASEBOARD_FAB2(SCH_1):P12V_NVDIMM_ABC
    2  GND                B  @BASEBOARD_FAB2_LIB.BASEBOARD_FAB2(SCH_1):GND

CAP  I223  C6U2   [CAP_0805-47UF,4V,20%,X6S,C9533A]
    1  PVPP_GHJ           A  @BASEBOARD_FAB2_LIB.BASEBOARD_FAB2(SCH_1):PVPP_GHJ
    2  GND                B  @BASEBOARD_FAB2_LIB.BASEBOARD_FAB2(SCH_1):GND

CAP  I221  C6U3   [CAP_0805-47UF,4V,20%,X6S,C9533A]
    1  PVPP_GHJ           A  @BASEBOARD_FAB2_LIB.BASEBOARD_FAB2(SCH_1):PVPP_GHJ
    2  GND                B  @BASEBOARD_FAB2_LIB.BASEBOARD_FAB2(SCH_1):GND

CAP  I248  C6U4   [CAP_0805-10UF,16V,10%,X6S,C953A]
    1  VR_FET_SW_P12V_STBY_PVPP_GHJ      A  @BASEBOARD_FAB2_LIB.BASEBOARD_FAB2(SCH_1):VR_FET_SW_P12V_STBY_PVPP_GHJ
    2  GND                B  @BASEBOARD_FAB2_LIB.BASEBOARD_FAB2(SCH_1):GND

CAP_A  I242  C6U5   [CAP_A_0402V-0.1UF,16V,10%,X7R,A]
    1  VR_FET_SW_P12V_STBY_PVPP_GHJ      A  @BASEBOARD_FAB2_LIB.BASEBOARD_FAB2(SCH_1):VR_FET_SW_P12V_STBY_PVPP_GHJ
    2  GND                B  @BASEBOARD_FAB2_LIB.BASEBOARD_FAB2(SCH_1):GND

CAP  I187  C6U6   [CAP_0603-4.7UF,6.3V,10%,X6S,E1A]
    1  VR_VB_PVPP_GHJ      A  @BASEBOARD_FAB2_LIB.BASEBOARD_FAB2(SCH_1):VR_VB_PVPP_GHJ
    2  AGND_PVPP_GHJ      B  @BASEBOARD_FAB2_LIB.BASEBOARD_FAB2(SCH_1):AGND_PVPP_GHJ

CAP  I254  C6U7   [CAP_0805-10UF,16V,10%,X6S,C953A]
    1  VR_FET_SW_P12V_STBY_PVPP_GHJ      A  @BASEBOARD_FAB2_LIB.BASEBOARD_FAB2(SCH_1):VR_FET_SW_P12V_STBY_PVPP_GHJ
    2  GND                B  @BASEBOARD_FAB2_LIB.BASEBOARD_FAB2(SCH_1):GND

CAP  I255  C6U8   [CAP_0805-10UF,16V,10%,X6S,C953A]
    1  VR_FET_SW_P12V_STBY_PVPP_GHJ      A  @BASEBOARD_FAB2_LIB.BASEBOARD_FAB2(SCH_1):VR_FET_SW_P12V_STBY_PVPP_GHJ
    2  GND                B  @BASEBOARD_FAB2_LIB.BASEBOARD_FAB2(SCH_1):GND

CAP_A  I5   C6U9   [CAP_A_0402V-0.01UF,25V,10%,X7RA]
    1  M_B_VREF           A  @BASEBOARD_FAB2_LIB.BASEBOARD_FAB2(SCH_1):M_B_VREF
    2  GND                B  @BASEBOARD_FAB2_LIB.BASEBOARD_FAB2(SCH_1):GND

CAP  I65  C6U10  [CAP_0805-10UF,16V,10%,X7R,G106A]
    1  P12V_NVDIMM_ABC      A  @BASEBOARD_FAB2_LIB.BASEBOARD_FAB2(SCH_1):P12V_NVDIMM_ABC
    2  GND                B  @BASEBOARD_FAB2_LIB.BASEBOARD_FAB2(SCH_1):GND

CAP  I46  C6U11  [CAP_0603-4.7UF,6.3V,10%,X6S,E1A]
    1  VSENSE_PVDDQ_GHJ_VTT      A  @BASEBOARD_FAB2_LIB.BASEBOARD_FAB2(SCH_1):VSENSE_PVDDQ_GHJ_VTT
    2  GND                B  @BASEBOARD_FAB2_LIB.BASEBOARD_FAB2(SCH_1):GND

CAP  I49  C6U12  [CAP_0603-4.7UF,6.3V,10%,X6S,E1A]
    1  VSENSE_PVDDQ_ABC_VTT      A  @BASEBOARD_FAB2_LIB.BASEBOARD_FAB2(SCH_1):VSENSE_PVDDQ_ABC_VTT
    2  GND                B  @BASEBOARD_FAB2_LIB.BASEBOARD_FAB2(SCH_1):GND

CAP  I29  C6U13  [CAP_0603LF-10UF,4V,20%,X6S,E15A]
    1  PVDDQ_GHJ          A  @BASEBOARD_FAB2_LIB.BASEBOARD_FAB2(SCH_1):PVDDQ_GHJ
    2  GND                B  @BASEBOARD_FAB2_LIB.BASEBOARD_FAB2(SCH_1):GND

CAP  I25  C6U14  [CAP_0603LF-10UF,4V,20%,X6S,E15A]
    1  PVDDQ_GHJ          A  @BASEBOARD_FAB2_LIB.BASEBOARD_FAB2(SCH_1):PVDDQ_GHJ
    2  GND                B  @BASEBOARD_FAB2_LIB.BASEBOARD_FAB2(SCH_1):GND

CAP  I26  C6U15  [CAP_0603LF-10UF,4V,20%,X6S,E15A]
    1  PVDDQ_ABC          A  @BASEBOARD_FAB2_LIB.BASEBOARD_FAB2(SCH_1):PVDDQ_ABC
    2  GND                B  @BASEBOARD_FAB2_LIB.BASEBOARD_FAB2(SCH_1):GND

CAP  I22  C6U16  [CAP_0603LF-10UF,4V,20%,X6S,E15A]
    1  PVDDQ_ABC          A  @BASEBOARD_FAB2_LIB.BASEBOARD_FAB2(SCH_1):PVDDQ_ABC
    2  GND                B  @BASEBOARD_FAB2_LIB.BASEBOARD_FAB2(SCH_1):GND

CAP_A  I176  C6U17  [CAP_A_0402V-0.01UF,25V,10%,X7RA]
    1  M_C_VREF           A  @BASEBOARD_FAB2_LIB.BASEBOARD_FAB2(SCH_1):M_C_VREF
    2  GND                B  @BASEBOARD_FAB2_LIB.BASEBOARD_FAB2(SCH_1):GND

CAP  I52  C6U18  [CAP_0805-10UF,16V,10%,X7R,G106A]
    1  P12V_NVDIMM_ABC      A  @BASEBOARD_FAB2_LIB.BASEBOARD_FAB2(SCH_1):P12V_NVDIMM_ABC
    2  GND                B  @BASEBOARD_FAB2_LIB.BASEBOARD_FAB2(SCH_1):GND

CAP_A  I51  C7A5   [CAP_A_0402V-0.1UF,16V,10%,X7R,A]
    1  VR_FET_SW_P12V_STBY_PVDDQ_DEF      A  @BASEBOARD_FAB2_LIB.BASEBOARD_FAB2(SCH_1):VR_FET_SW_P12V_STBY_PVDDQ_DEF
    2  GND                B  @BASEBOARD_FAB2_LIB.BASEBOARD_FAB2(SCH_1):GND

CAP_0402  I19  C7A6   [CAP_0402-1.0UF,16V,10%,X6S,D97A]
    1  VR_PVNN_PCH_PH1_VCIN      A  @BASEBOARD_FAB2_LIB.BASEBOARD_FAB2(SCH_1):VR_PVNN_PCH_PH1_VCIN
    2  GND                B  @BASEBOARD_FAB2_LIB.BASEBOARD_FAB2(SCH_1):GND

CAP_0402  I22  C7A7   [CAP_0402-1.0UF,16V,10%,X6S,D97A]
    1  VR_FET_SW_P12V_STBY_PVDDQ_DEF      A  @BASEBOARD_FAB2_LIB.BASEBOARD_FAB2(SCH_1):VR_FET_SW_P12V_STBY_PVDDQ_DEF
    2  GND                B  @BASEBOARD_FAB2_LIB.BASEBOARD_FAB2(SCH_1):GND

CAP_0402  I16  C7A8   [CAP_0402-0.22UF,16V,10%,X7R,A3A]
    1  P5V_STBY           A  @BASEBOARD_FAB2_LIB.BASEBOARD_FAB2(SCH_1):P5V_STBY
    2  GND                B  @BASEBOARD_FAB2_LIB.BASEBOARD_FAB2(SCH_1):GND

CAP_0402  I33  C7A9   [CAP_0402-1.0UF,16V,10%,X6S,D97A]
    1  VR_FET_SW_P12V_STBY_PVDDQ_DEF      A  @BASEBOARD_FAB2_LIB.BASEBOARD_FAB2(SCH_1):VR_FET_SW_P12V_STBY_PVDDQ_DEF
    2  GND                B  @BASEBOARD_FAB2_LIB.BASEBOARD_FAB2(SCH_1):GND

CAP_0402  I36  C7A10  [CAP_0402-1.0UF,16V,10%,X6S,D97A]
    1  VR_P1V05_PCH_STBY_PH1_VCIN      A  @BASEBOARD_FAB2_LIB.BASEBOARD_FAB2(SCH_1):VR_P1V05_PCH_STBY_PH1_VCIN
    2  GND                B  @BASEBOARD_FAB2_LIB.BASEBOARD_FAB2(SCH_1):GND

CAP_0402  I48  C7A11  [CAP_0402-1.0UF,16V,10%,X6S,D97A]
    1  VR_FET_SW_P12V_STBY_PVDDQ_DEF      A  @BASEBOARD_FAB2_LIB.BASEBOARD_FAB2(SCH_1):VR_FET_SW_P12V_STBY_PVDDQ_DEF
    2  GND                B  @BASEBOARD_FAB2_LIB.BASEBOARD_FAB2(SCH_1):GND

CAP_0402  I44  C7A12  [CAP_0402-0.220UF,16V,10%,X7R,AA]
    2  VR_PVDDQ_DEF_PH1_PHASE      B  @BASEBOARD_FAB2_LIB.BASEBOARD_FAB2(SCH_1):VR_PVDDQ_DEF_PH1_PHASE
    1  VR_PVDDQ_DEF_PH1_BOOT      A  @BASEBOARD_FAB2_LIB.BASEBOARD_FAB2(SCH_1):VR_PVDDQ_DEF_PH1_BOOT

CAP  I63  C7A13  [CAP_1210-100UF,16V,20%,X5R,644A]
    1  VR_FET_SW_P12V_STBY_PVDDQ_DEF      A  @BASEBOARD_FAB2_LIB.BASEBOARD_FAB2(SCH_1):VR_FET_SW_P12V_STBY_PVDDQ_DEF
    2  GND                B  @BASEBOARD_FAB2_LIB.BASEBOARD_FAB2(SCH_1):GND

CAP  I65  C7A14  [CAP_1210-100UF,16V,20%,X5R,644A]
    1  VR_FET_SW_P12V_STBY_PVDDQ_DEF      A  @BASEBOARD_FAB2_LIB.BASEBOARD_FAB2(SCH_1):VR_FET_SW_P12V_STBY_PVDDQ_DEF
    2  GND                B  @BASEBOARD_FAB2_LIB.BASEBOARD_FAB2(SCH_1):GND

CAP_0402  I50  C7A16  [CAP_0402-1.0UF,16V,10%,X6S,D97A]
    1  VR_PVDDQ_DEF_PH1_VCIN      A  @BASEBOARD_FAB2_LIB.BASEBOARD_FAB2(SCH_1):VR_PVDDQ_DEF_PH1_VCIN
    2  GND                B  @BASEBOARD_FAB2_LIB.BASEBOARD_FAB2(SCH_1):GND

CAP_0402  I54  C7A17  [CAP_0402-0.22UF,16V,10%,X7R,A3A]
    1  P5V_STBY           A  @BASEBOARD_FAB2_LIB.BASEBOARD_FAB2(SCH_1):P5V_STBY
    2  GND                B  @BASEBOARD_FAB2_LIB.BASEBOARD_FAB2(SCH_1):GND

CAP_A  I53  C7A18  [CAP_A_0402V-1.0UF,6.3V,10%,X6SA]
    1  P5V_STBY           A  @BASEBOARD_FAB2_LIB.BASEBOARD_FAB2(SCH_1):P5V_STBY
    2  GND                B  @BASEBOARD_FAB2_LIB.BASEBOARD_FAB2(SCH_1):GND

CAPP  I175  C7A19  [CAPP_2626-270UF,16V,20%,OSCON,A]
    1  VR_FET_SW_P12V_STBY_PVDDQ_DEF      A  @BASEBOARD_FAB2_LIB.BASEBOARD_FAB2(SCH_1):VR_FET_SW_P12V_STBY_PVDDQ_DEF
    2  GND                B  @BASEBOARD_FAB2_LIB.BASEBOARD_FAB2(SCH_1):GND

CAP_A  I78  C7A20  [CAP_A_0402V-0.1UF,16V,10%,X7R,A]
    1  VR_FET_SW_P12V_STBY_PVDDQ_DEF      A  @BASEBOARD_FAB2_LIB.BASEBOARD_FAB2(SCH_1):VR_FET_SW_P12V_STBY_PVDDQ_DEF
    2  GND                B  @BASEBOARD_FAB2_LIB.BASEBOARD_FAB2(SCH_1):GND

CAP_0402  I79  C7A21  [CAP_0402-1.0UF,16V,10%,X6S,D97A]
    1  VR_FET_SW_P12V_STBY_PVDDQ_DEF      A  @BASEBOARD_FAB2_LIB.BASEBOARD_FAB2(SCH_1):VR_FET_SW_P12V_STBY_PVDDQ_DEF
    2  GND                B  @BASEBOARD_FAB2_LIB.BASEBOARD_FAB2(SCH_1):GND

CAP_0402  I75  C7A22  [CAP_0402-0.220UF,16V,10%,X7R,AA]
    2  VR_PVDDQ_DEF_PH2_PHASE      B  @BASEBOARD_FAB2_LIB.BASEBOARD_FAB2(SCH_1):VR_PVDDQ_DEF_PH2_PHASE
    1  VR_PVDDQ_DEF_PH2_BOOT      A  @BASEBOARD_FAB2_LIB.BASEBOARD_FAB2(SCH_1):VR_PVDDQ_DEF_PH2_BOOT

CAP_0402  I77  C7A24  [CAP_0402-1.0UF,16V,10%,X6S,D97A]
    1  VR_PVDDQ_DEF_PH2_VCIN      A  @BASEBOARD_FAB2_LIB.BASEBOARD_FAB2(SCH_1):VR_PVDDQ_DEF_PH2_VCIN
    2  GND                B  @BASEBOARD_FAB2_LIB.BASEBOARD_FAB2(SCH_1):GND

CAP_0402  I72  C7A25  [CAP_0402-0.22UF,16V,10%,X7R,A3A]
    1  P5V_STBY           A  @BASEBOARD_FAB2_LIB.BASEBOARD_FAB2(SCH_1):P5V_STBY
    2  GND                B  @BASEBOARD_FAB2_LIB.BASEBOARD_FAB2(SCH_1):GND

CAP_A  I73  C7A26  [CAP_A_0402V-1.0UF,6.3V,10%,X6SA]
    1  P5V_STBY           A  @BASEBOARD_FAB2_LIB.BASEBOARD_FAB2(SCH_1):P5V_STBY
    2  GND                B  @BASEBOARD_FAB2_LIB.BASEBOARD_FAB2(SCH_1):GND

CAPP  I75  C7A27  [CAPP_SM-470UF,2V,20%,ALUM,6990A]
    1  PVNN_PCH_STBY      A  @BASEBOARD_FAB2_LIB.BASEBOARD_FAB2(SCH_1):PVNN_PCH_STBY
    2  GND                B  @BASEBOARD_FAB2_LIB.BASEBOARD_FAB2(SCH_1):GND

CAP  I61  C7A28  [CAP_0402LF-220PF,50V,10%,X7R,AA]
    2  VSENSE_PVDDQ_DEF_N      B  @BASEBOARD_FAB2_LIB.BASEBOARD_FAB2(SCH_1):VSENSE_PVDDQ_DEF_N
    1  VR_PVDDQ_DEF_AVSP      A  @BASEBOARD_FAB2_LIB.BASEBOARD_FAB2(SCH_1):VR_PVDDQ_DEF_AVSP

CAP  I39  C7A29  [CAP_0402LF-220PF,50V,10%,X7R,AA]
    2  GND                B  @BASEBOARD_FAB2_LIB.BASEBOARD_FAB2(SCH_1):GND
    1  A_TSENSE_PVDDQ_DEF      A  @BASEBOARD_FAB2_LIB.BASEBOARD_FAB2(SCH_1):A_TSENSE_PVDDQ_DEF

CAP  I9   C7A30  [CAP_0805LF-22UF,4V,20%,X6S,C95A]
    1  PVNN_PCH_STBY      A  @BASEBOARD_FAB2_LIB.BASEBOARD_FAB2(SCH_1):PVNN_PCH_STBY
    2  GND                B  @BASEBOARD_FAB2_LIB.BASEBOARD_FAB2(SCH_1):GND

CAP  I40  C7A31  [CAP_0805-47UF,4V,20%,X6S,C9533A]
    1  PVNN_PCH_STBY      A  @BASEBOARD_FAB2_LIB.BASEBOARD_FAB2(SCH_1):PVNN_PCH_STBY
    2  GND                B  @BASEBOARD_FAB2_LIB.BASEBOARD_FAB2(SCH_1):GND

CAP  I38  C7A32  [CAP_0805-47UF,4V,20%,X6S,C9533A]
    1  PVNN_PCH_STBY      A  @BASEBOARD_FAB2_LIB.BASEBOARD_FAB2(SCH_1):PVNN_PCH_STBY
    2  GND                B  @BASEBOARD_FAB2_LIB.BASEBOARD_FAB2(SCH_1):GND

CAP  I23  C7A33  [CAP_0805-47UF,4V,20%,X6S,C9533A]
    1  PVNN_PCH_STBY      A  @BASEBOARD_FAB2_LIB.BASEBOARD_FAB2(SCH_1):PVNN_PCH_STBY
    2  GND                B  @BASEBOARD_FAB2_LIB.BASEBOARD_FAB2(SCH_1):GND

CAP  I220  C7A34  [CAP_0402LF-3300PF,50V,10%,EMPTA]
    2  VR_PVPP_DEF_SNUB      B  @BASEBOARD_FAB2_LIB.BASEBOARD_FAB2(SCH_1):VR_PVPP_DEF_SNUB
    1  VR_PVPP_DEF_PHASE      A  @BASEBOARD_FAB2_LIB.BASEBOARD_FAB2(SCH_1):VR_PVPP_DEF_PHASE

CAP  I55  C7A35  [CAP_0402LF-1000PF,50V,10%,X7R,A]
    1  VR_PVDDQ_DEF_VINSEN      A  @BASEBOARD_FAB2_LIB.BASEBOARD_FAB2(SCH_1):VR_PVDDQ_DEF_VINSEN
    2  GND                B  @BASEBOARD_FAB2_LIB.BASEBOARD_FAB2(SCH_1):GND

CAP_A  I11  C7A36  [CAP_A_0603V-22.0UF,4V,20%,X6S,A]
    1  PVNN_PCH_STBY      A  @BASEBOARD_FAB2_LIB.BASEBOARD_FAB2(SCH_1):PVNN_PCH_STBY
    2  GND                B  @BASEBOARD_FAB2_LIB.BASEBOARD_FAB2(SCH_1):GND

CAP_A  I29  C7A37  [CAP_A_0402V-1.0UF,6.3V,10%,X6SA]
    1  VR_PVDDQ_DEF_VDD      A  @BASEBOARD_FAB2_LIB.BASEBOARD_FAB2(SCH_1):VR_PVDDQ_DEF_VDD
    2  GND                B  @BASEBOARD_FAB2_LIB.BASEBOARD_FAB2(SCH_1):GND

CAP_A  I31  C7A38  [CAP_A_0402V-0.1UF,16V,10%,X7R,A]
    1  VR_PVDDQ_DEF_VDD      A  @BASEBOARD_FAB2_LIB.BASEBOARD_FAB2(SCH_1):VR_PVDDQ_DEF_VDD
    2  GND                B  @BASEBOARD_FAB2_LIB.BASEBOARD_FAB2(SCH_1):GND

CAP_A  I20  C7A39  [CAP_A_0402V-0.1UF,16V,10%,X7R,A]
    1  VR_FET_SW_P12V_STBY_PVDDQ_DEF      A  @BASEBOARD_FAB2_LIB.BASEBOARD_FAB2(SCH_1):VR_FET_SW_P12V_STBY_PVDDQ_DEF
    2  GND                B  @BASEBOARD_FAB2_LIB.BASEBOARD_FAB2(SCH_1):GND

CAP_A  I35  C7A40  [CAP_A_0402V-0.1UF,16V,10%,X7R,A]
    1  VR_FET_SW_P12V_STBY_PVDDQ_DEF      A  @BASEBOARD_FAB2_LIB.BASEBOARD_FAB2(SCH_1):VR_FET_SW_P12V_STBY_PVDDQ_DEF
    2  GND                B  @BASEBOARD_FAB2_LIB.BASEBOARD_FAB2(SCH_1):GND

CAP_0402  I39  C7A41  [CAP_0402-0.22UF,16V,10%,X7R,A3A]
    1  P5V_STBY           A  @BASEBOARD_FAB2_LIB.BASEBOARD_FAB2(SCH_1):P5V_STBY
    2  GND                B  @BASEBOARD_FAB2_LIB.BASEBOARD_FAB2(SCH_1):GND

CAP  I46  C7A42  [CAP_0805LF-22UF,4V,20%,X6S,C95A]
    1  P1V05_PCH_STBY      A  @BASEBOARD_FAB2_LIB.BASEBOARD_FAB2(SCH_1):P1V05_PCH_STBY
    2  GND                B  @BASEBOARD_FAB2_LIB.BASEBOARD_FAB2(SCH_1):GND

CAP_0402  I21  C7A43  [CAP_0402-0.220UF,16V,10%,X7R,AA]
    2  VR_PVNN_PCH_PH1_PHASE      B  @BASEBOARD_FAB2_LIB.BASEBOARD_FAB2(SCH_1):VR_PVNN_PCH_PH1_PHASE
    1  VR_PVNN_PCH_PH1_BOOT      A  @BASEBOARD_FAB2_LIB.BASEBOARD_FAB2(SCH_1):VR_PVNN_PCH_PH1_BOOT

CAP_0402  I34  C7A44  [CAP_0402-0.220UF,16V,10%,X7R,AA]
    2  VR_P1V05_PCH_STBY_PH1_PHASE      B  @BASEBOARD_FAB2_LIB.BASEBOARD_FAB2(SCH_1):VR_P1V05_PCH_STBY_PH1_PHASE
    1  VR_P1V05_PCH_STBY_PH1_BOOT      A  @BASEBOARD_FAB2_LIB.BASEBOARD_FAB2(SCH_1):VR_P1V05_PCH_STBY_PH1_BOOT

CAP_A  I22  C7B1   [CAP_A_0402V-1.0UF,6.3V,10%,X6SA]
    1  VR_PVDDQ_DEF_VD12      A  @BASEBOARD_FAB2_LIB.BASEBOARD_FAB2(SCH_1):VR_PVDDQ_DEF_VD12
    2  GND                B  @BASEBOARD_FAB2_LIB.BASEBOARD_FAB2(SCH_1):GND

CAP_A  I23  C7B2   [CAP_A_0402V-0.1UF,16V,10%,X7R,A]
    1  VR_PVDDQ_DEF_VD12      A  @BASEBOARD_FAB2_LIB.BASEBOARD_FAB2(SCH_1):VR_PVDDQ_DEF_VD12
    2  GND                B  @BASEBOARD_FAB2_LIB.BASEBOARD_FAB2(SCH_1):GND

CAP  I26  C7B3   [CAP_0402LF-1000PF,50V,10%,X7R,A]
    1  PWRGD_PVDDQ_DEF_R      A  @BASEBOARD_FAB2_LIB.BASEBOARD_FAB2(SCH_1):PWRGD_PVDDQ_DEF_R
    2  GND                B  @BASEBOARD_FAB2_LIB.BASEBOARD_FAB2(SCH_1):GND

CAP  I24  C7B4   [CAP_0805-47UF,4V,20%,X6S,C9533A]
    1  PVNN_PCH_STBY      A  @BASEBOARD_FAB2_LIB.BASEBOARD_FAB2(SCH_1):PVNN_PCH_STBY
    2  GND                B  @BASEBOARD_FAB2_LIB.BASEBOARD_FAB2(SCH_1):GND

CAP  I262  C7B5   [CAP_0805-10UF,16V,10%,X6S,C953A]
    1  VR_FET_SW_P12V_STBY_PVPP_DEF      A  @BASEBOARD_FAB2_LIB.BASEBOARD_FAB2(SCH_1):VR_FET_SW_P12V_STBY_PVPP_DEF
    2  GND                B  @BASEBOARD_FAB2_LIB.BASEBOARD_FAB2(SCH_1):GND

CAP_A  I252  C7B6   [CAP_A_0402V-0.1UF,16V,10%,X7R,A]
    1  VR_FET_SW_P12V_STBY_PVPP_DEF      A  @BASEBOARD_FAB2_LIB.BASEBOARD_FAB2(SCH_1):VR_FET_SW_P12V_STBY_PVPP_DEF
    2  GND                B  @BASEBOARD_FAB2_LIB.BASEBOARD_FAB2(SCH_1):GND

CAP  I238  C7B7   [CAP_0805-47UF,4V,20%,X6S,C9533A]
    1  PVPP_DEF           A  @BASEBOARD_FAB2_LIB.BASEBOARD_FAB2(SCH_1):PVPP_DEF
    2  GND                B  @BASEBOARD_FAB2_LIB.BASEBOARD_FAB2(SCH_1):GND

CAP  I202  C7B8   [CAP_1210-47UF,16V,20%,X6S,D384A]
    1  VR_FET_SW_P12V_STBY_PVPP_DEF      A  @BASEBOARD_FAB2_LIB.BASEBOARD_FAB2(SCH_1):VR_FET_SW_P12V_STBY_PVPP_DEF
    2  GND                B  @BASEBOARD_FAB2_LIB.BASEBOARD_FAB2(SCH_1):GND

CAP  I185  C7B9   [CAP_0402LF-1000PF,50V,10%,EMPTA]
    1  FM_PVPP_CPU0_EN      A  @BASEBOARD_FAB2_LIB.BASEBOARD_FAB2(SCH_1):FM_PVPP_CPU0_EN
    2  AGND_PVPP_DEF      B  @BASEBOARD_FAB2_LIB.BASEBOARD_FAB2(SCH_1):AGND_PVPP_DEF

CAP  I301  C7B10  [CAP_0402LF-100.0PF,50V,5%,COG,A]
    1  VR_FB_PVPP_DEF      A  @BASEBOARD_FAB2_LIB.BASEBOARD_FAB2(SCH_1):VR_FB_PVPP_DEF
    2  VR_COMP_PVPP_DEF_3      B  @BASEBOARD_FAB2_LIB.BASEBOARD_FAB2(SCH_1):VR_COMP_PVPP_DEF_3

CAP_0402  I197  C7B11  [CAP_0402-0.027UF,16V,10%,X7R,AA]
    1  VR_PVPP_DEF_SS      A  @BASEBOARD_FAB2_LIB.BASEBOARD_FAB2(SCH_1):VR_PVPP_DEF_SS
    2  AGND_PVPP_DEF      B  @BASEBOARD_FAB2_LIB.BASEBOARD_FAB2(SCH_1):AGND_PVPP_DEF

CAP  I209  C7B12  [CAP_0402LF-1000PF,50V,10%,X7R,A]
    1  PWRGD_PVPP_DEF_R      A  @BASEBOARD_FAB2_LIB.BASEBOARD_FAB2(SCH_1):PWRGD_PVPP_DEF_R
    2  GND                B  @BASEBOARD_FAB2_LIB.BASEBOARD_FAB2(SCH_1):GND

CAP  I302  C7B13  [CAP_0402LF-2200PF,50V,10%,X7R,A]
    2  VR_FB_PVPP_DEF      B  @BASEBOARD_FAB2_LIB.BASEBOARD_FAB2(SCH_1):VR_FB_PVPP_DEF
    1  VR_COMP_PVPP_DEF      A  @BASEBOARD_FAB2_LIB.BASEBOARD_FAB2(SCH_1):VR_COMP_PVPP_DEF

CAP  I306  C7B14  [CAP_0402LF-2200PF,50V,10%,X7R,A]
    1  VR_COMP_RC_PVPP_DEF      A  @BASEBOARD_FAB2_LIB.BASEBOARD_FAB2(SCH_1):VR_COMP_RC_PVPP_DEF
    2  VR_COMP_PVPP_DEF_3      B  @BASEBOARD_FAB2_LIB.BASEBOARD_FAB2(SCH_1):VR_COMP_PVPP_DEF_3

CAP_A  I1   C7B15  [CAP_A_0603V-22.0UF,4V,20%,X6S,A]
    1  P1V05_PCH_STBY      A  @BASEBOARD_FAB2_LIB.BASEBOARD_FAB2(SCH_1):P1V05_PCH_STBY
    2  GND                B  @BASEBOARD_FAB2_LIB.BASEBOARD_FAB2(SCH_1):GND

CAP_A  I3   C7B16  [CAP_A_0603V-22.0UF,4V,20%,X6S,A]
    1  P1V05_PCH_STBY      A  @BASEBOARD_FAB2_LIB.BASEBOARD_FAB2(SCH_1):P1V05_PCH_STBY
    2  GND                B  @BASEBOARD_FAB2_LIB.BASEBOARD_FAB2(SCH_1):GND

CAP_A  I18  C7B17  [CAP_A_0603V-22.0UF,4V,20%,X6S,A]
    1  P1V05_PCH_STBY      A  @BASEBOARD_FAB2_LIB.BASEBOARD_FAB2(SCH_1):P1V05_PCH_STBY
    2  GND                B  @BASEBOARD_FAB2_LIB.BASEBOARD_FAB2(SCH_1):GND

CAP_A  I12  C7B18  [CAP_A_0603V-22.0UF,4V,20%,X6S,A]
    1  P1V05_PCH_STBY      A  @BASEBOARD_FAB2_LIB.BASEBOARD_FAB2(SCH_1):P1V05_PCH_STBY
    2  GND                B  @BASEBOARD_FAB2_LIB.BASEBOARD_FAB2(SCH_1):GND

CAP_A  I2   C7B19  [CAP_A_0603V-22.0UF,4V,20%,X6S,A]
    1  P1V05_PCH_STBY      A  @BASEBOARD_FAB2_LIB.BASEBOARD_FAB2(SCH_1):P1V05_PCH_STBY
    2  GND                B  @BASEBOARD_FAB2_LIB.BASEBOARD_FAB2(SCH_1):GND

CAP_A  I6   C7B20  [CAP_A_0603V-22.0UF,4V,20%,X6S,A]
    1  P1V05_PCH_STBY      A  @BASEBOARD_FAB2_LIB.BASEBOARD_FAB2(SCH_1):P1V05_PCH_STBY
    2  GND                B  @BASEBOARD_FAB2_LIB.BASEBOARD_FAB2(SCH_1):GND

CAP_A  I4   C7B21  [CAP_A_0603V-22.0UF,4V,20%,X6S,A]
    1  P1V05_PCH_STBY      A  @BASEBOARD_FAB2_LIB.BASEBOARD_FAB2(SCH_1):P1V05_PCH_STBY
    2  GND                B  @BASEBOARD_FAB2_LIB.BASEBOARD_FAB2(SCH_1):GND

CAP_A  I10  C7B22  [CAP_A_0603V-22.0UF,4V,20%,X6S,A]
    1  P1V05_PCH_STBY      A  @BASEBOARD_FAB2_LIB.BASEBOARD_FAB2(SCH_1):P1V05_PCH_STBY
    2  GND                B  @BASEBOARD_FAB2_LIB.BASEBOARD_FAB2(SCH_1):GND

CAP_A  I7   C7B23  [CAP_A_0603V-22.0UF,4V,20%,X6S,A]
    1  P1V05_PCH_STBY      A  @BASEBOARD_FAB2_LIB.BASEBOARD_FAB2(SCH_1):P1V05_PCH_STBY
    2  GND                B  @BASEBOARD_FAB2_LIB.BASEBOARD_FAB2(SCH_1):GND

CAP_A  I11  C7B24  [CAP_A_0603V-22.0UF,4V,20%,X6S,A]
    1  P1V05_PCH_STBY      A  @BASEBOARD_FAB2_LIB.BASEBOARD_FAB2(SCH_1):P1V05_PCH_STBY
    2  GND                B  @BASEBOARD_FAB2_LIB.BASEBOARD_FAB2(SCH_1):GND

CAP_0402  I35  C7B25  [CAP_0402-0.22UF,16V,10%,X7R,A3A]
    1  DMI_CPU0_PCH_TX_DP<3>      A  @BASEBOARD_FAB2_LIB.BASEBOARD_FAB2(SCH_1):DMI_CPU0_PCH_TX_DP<3>
    2  DMI_CPU0_PCH_TX_C_DP<3>      B  @BASEBOARD_FAB2_LIB.BASEBOARD_FAB2(SCH_1):DMI_CPU0_PCH_TX_C_DP<3>

CAP_0402  I79  C7B26  [CAP_0402-0.22UF,16V,10%,X7R,A3A]
    1  DMI_CPU0_PCH_TX_DN<3>      A  @BASEBOARD_FAB2_LIB.BASEBOARD_FAB2(SCH_1):DMI_CPU0_PCH_TX_DN<3>
    2  DMI_CPU0_PCH_TX_C_DN<3>      B  @BASEBOARD_FAB2_LIB.BASEBOARD_FAB2(SCH_1):DMI_CPU0_PCH_TX_C_DN<3>

CAP_0402  I69  C7B27  [CAP_0402-0.22UF,16V,10%,X7R,A3A]
    1  DMI_CPU0_PCH_TX_DP<2>      A  @BASEBOARD_FAB2_LIB.BASEBOARD_FAB2(SCH_1):DMI_CPU0_PCH_TX_DP<2>
    2  DMI_CPU0_PCH_TX_C_DP<2>      B  @BASEBOARD_FAB2_LIB.BASEBOARD_FAB2(SCH_1):DMI_CPU0_PCH_TX_C_DP<2>

CAP_0402  I70  C7B28  [CAP_0402-0.22UF,16V,10%,X7R,A3A]
    1  DMI_CPU0_PCH_TX_DP<1>      A  @BASEBOARD_FAB2_LIB.BASEBOARD_FAB2(SCH_1):DMI_CPU0_PCH_TX_DP<1>
    2  DMI_CPU0_PCH_TX_C_DP<1>      B  @BASEBOARD_FAB2_LIB.BASEBOARD_FAB2(SCH_1):DMI_CPU0_PCH_TX_C_DP<1>

CAP_0402  I78  C7B29  [CAP_0402-0.22UF,16V,10%,X7R,A3A]
    1  DMI_CPU0_PCH_TX_DN<2>      A  @BASEBOARD_FAB2_LIB.BASEBOARD_FAB2(SCH_1):DMI_CPU0_PCH_TX_DN<2>
    2  DMI_CPU0_PCH_TX_C_DN<2>      B  @BASEBOARD_FAB2_LIB.BASEBOARD_FAB2(SCH_1):DMI_CPU0_PCH_TX_C_DN<2>

CAP  I241  C7B30  [CAP_0603LF-0.1UF,25V,10%,X7R,6A]
    1  VR_PVPP_DEF_PHASE      A  @BASEBOARD_FAB2_LIB.BASEBOARD_FAB2(SCH_1):VR_PVPP_DEF_PHASE
    2  VR_PVPP_DEF_BOOT_R      B  @BASEBOARD_FAB2_LIB.BASEBOARD_FAB2(SCH_1):VR_PVPP_DEF_BOOT_R

CAP_0402  I77  C7C1   [CAP_0402-0.22UF,16V,10%,X7R,A3A]
    1  DMI_CPU0_PCH_TX_DN<1>      A  @BASEBOARD_FAB2_LIB.BASEBOARD_FAB2(SCH_1):DMI_CPU0_PCH_TX_DN<1>
    2  DMI_CPU0_PCH_TX_C_DN<1>      B  @BASEBOARD_FAB2_LIB.BASEBOARD_FAB2(SCH_1):DMI_CPU0_PCH_TX_C_DN<1>

CAP_0402  I71  C7C2   [CAP_0402-0.22UF,16V,10%,X7R,A3A]
    1  DMI_CPU0_PCH_TX_DP<0>      A  @BASEBOARD_FAB2_LIB.BASEBOARD_FAB2(SCH_1):DMI_CPU0_PCH_TX_DP<0>
    2  DMI_CPU0_PCH_TX_C_DP<0>      B  @BASEBOARD_FAB2_LIB.BASEBOARD_FAB2(SCH_1):DMI_CPU0_PCH_TX_C_DP<0>

CAP_0402  I76  C7C3   [CAP_0402-0.22UF,16V,10%,X7R,A3A]
    1  DMI_CPU0_PCH_TX_DN<0>      A  @BASEBOARD_FAB2_LIB.BASEBOARD_FAB2(SCH_1):DMI_CPU0_PCH_TX_DN<0>
    2  DMI_CPU0_PCH_TX_C_DN<0>      B  @BASEBOARD_FAB2_LIB.BASEBOARD_FAB2(SCH_1):DMI_CPU0_PCH_TX_C_DN<0>

CAP  I50  C7C4   [CAP_0402LF-15.0PF,50V,5%,COG,AA]
    1  XTAL_PCH_48M_IN      A  @BASEBOARD_FAB2_LIB.BASEBOARD_FAB2(SCH_1):XTAL_PCH_48M_IN
    2  GND                B  @BASEBOARD_FAB2_LIB.BASEBOARD_FAB2(SCH_1):GND

CAP  I47  C7C5   [CAP_0402LF-15.0PF,50V,5%,COG,AA]
    1  XTAL_PCH_48M_OUT      A  @BASEBOARD_FAB2_LIB.BASEBOARD_FAB2(SCH_1):XTAL_PCH_48M_OUT
    2  GND                B  @BASEBOARD_FAB2_LIB.BASEBOARD_FAB2(SCH_1):GND

CAP_A  I23  C7C6   [CAP_A_0603V-22.0UF,4V,20%,X6S,A]
    1  PVCCIO_CPU0        A  @BASEBOARD_FAB2_LIB.BASEBOARD_FAB2(SCH_1):PVCCIO_CPU0
    2  GND                B  @BASEBOARD_FAB2_LIB.BASEBOARD_FAB2(SCH_1):GND

CAP  I54  C7C7   [CAP_1210-100UF,16V,20%,X5R,644A]
    1  VR_FET_SW_P12V_STBY_PVCCIO_CPU0      A  @BASEBOARD_FAB2_LIB.BASEBOARD_FAB2(SCH_1):VR_FET_SW_P12V_STBY_PVCCIO_CPU0
    2  GND                B  @BASEBOARD_FAB2_LIB.BASEBOARD_FAB2(SCH_1):GND

CAP  I51  C7C8   [CAP_1210-100UF,16V,20%,X5R,644A]
    1  VR_FET_SW_P12V_STBY_PVCCIO_CPU0      A  @BASEBOARD_FAB2_LIB.BASEBOARD_FAB2(SCH_1):VR_FET_SW_P12V_STBY_PVCCIO_CPU0
    2  GND                B  @BASEBOARD_FAB2_LIB.BASEBOARD_FAB2(SCH_1):GND

CAP_A  I7   C7C9   [CAP_A_0603V-22.0UF,4V,20%,X6S,A]
    1  PVNN_PCH_STBY      A  @BASEBOARD_FAB2_LIB.BASEBOARD_FAB2(SCH_1):PVNN_PCH_STBY
    2  GND                B  @BASEBOARD_FAB2_LIB.BASEBOARD_FAB2(SCH_1):GND

CAP_A  I77  C7C10  [CAP_A_0603V-22.0UF,4V,20%,X6S,A]
    1  PVCCIO_CPU0        A  @BASEBOARD_FAB2_LIB.BASEBOARD_FAB2(SCH_1):PVCCIO_CPU0
    2  GND                B  @BASEBOARD_FAB2_LIB.BASEBOARD_FAB2(SCH_1):GND

CAP_A  I38  C7C11  [CAP_A_0402V-0.1UF,16V,10%,X7R,A]
    1  VR_FET_SW_P12V_STBY_PVCCIO_CPU0      A  @BASEBOARD_FAB2_LIB.BASEBOARD_FAB2(SCH_1):VR_FET_SW_P12V_STBY_PVCCIO_CPU0
    2  GND                B  @BASEBOARD_FAB2_LIB.BASEBOARD_FAB2(SCH_1):GND

CAP_0402  I39  C7C12  [CAP_0402-1.0UF,16V,10%,X6S,D97A]
    1  VR_FET_SW_P12V_STBY_PVCCIO_CPU0      A  @BASEBOARD_FAB2_LIB.BASEBOARD_FAB2(SCH_1):VR_FET_SW_P12V_STBY_PVCCIO_CPU0
    2  GND                B  @BASEBOARD_FAB2_LIB.BASEBOARD_FAB2(SCH_1):GND

CAP  I56  C7C13  [CAP_0402LF-18PF,50V,5%,C0G,A36A]
    1  XTAL_33K_RTC1      A  @BASEBOARD_FAB2_LIB.BASEBOARD_FAB2(SCH_1):XTAL_33K_RTC1
    2  GND                B  @BASEBOARD_FAB2_LIB.BASEBOARD_FAB2(SCH_1):GND

CAP_0402  I37  C7C14  [CAP_0402-0.220UF,16V,10%,X7R,AA]
    2  VR_PVCCIO_CPU0_PH1_PHASE      B  @BASEBOARD_FAB2_LIB.BASEBOARD_FAB2(SCH_1):VR_PVCCIO_CPU0_PH1_PHASE
    1  VR_PVCCIO_CPU0_PH1_BOOT      A  @BASEBOARD_FAB2_LIB.BASEBOARD_FAB2(SCH_1):VR_PVCCIO_CPU0_PH1_BOOT

CAP  I46  C7C15  [CAP_0402LF-18PF,50V,5%,C0G,A36A]
    1  XTAL_33K_RTC2      A  @BASEBOARD_FAB2_LIB.BASEBOARD_FAB2(SCH_1):XTAL_33K_RTC2
    2  GND                B  @BASEBOARD_FAB2_LIB.BASEBOARD_FAB2(SCH_1):GND

CAP_0402  I36  C7C17  [CAP_0402-1.0UF,16V,10%,X6S,D97A]
    1  VR_PVCCIO_CPU0_PH1_VCIN      A  @BASEBOARD_FAB2_LIB.BASEBOARD_FAB2(SCH_1):VR_PVCCIO_CPU0_PH1_VCIN
    2  GND                B  @BASEBOARD_FAB2_LIB.BASEBOARD_FAB2(SCH_1):GND

CAP_0402  I33  C7C18  [CAP_0402-0.22UF,16V,10%,X7R,A3A]
    1  P5V_STBY           A  @BASEBOARD_FAB2_LIB.BASEBOARD_FAB2(SCH_1):P5V_STBY
    2  GND                B  @BASEBOARD_FAB2_LIB.BASEBOARD_FAB2(SCH_1):GND

CAP_A  I14  C7C19  [CAP_A_0402V-1.0UF,6.3V,10%,X6SA]
    1  RST_RTCRST_N       A  @BASEBOARD_FAB2_LIB.BASEBOARD_FAB2(SCH_1):RST_RTCRST_N
    2  GND                B  @BASEBOARD_FAB2_LIB.BASEBOARD_FAB2(SCH_1):GND

CAP_A  I34  C7C20  [CAP_A_0402V-1.0UF,6.3V,10%,X6SA]
    1  P5V_STBY           A  @BASEBOARD_FAB2_LIB.BASEBOARD_FAB2(SCH_1):P5V_STBY
    2  GND                B  @BASEBOARD_FAB2_LIB.BASEBOARD_FAB2(SCH_1):GND

CAP_A  I136  C7D1   [CAP_A_0402V-0.1UF,16V,10%,X7R,A]
    1  P3V3_STBY          A  @BASEBOARD_FAB2_LIB.BASEBOARD_FAB2(SCH_1):P3V3_STBY
    2  GND                B  @BASEBOARD_FAB2_LIB.BASEBOARD_FAB2(SCH_1):GND

CAP  I2   C7D2   [CAP_0603-10UF,6.3V,20%,X6S,E15A]
    1  P3V3_STBY          A  @BASEBOARD_FAB2_LIB.BASEBOARD_FAB2(SCH_1):P3V3_STBY
    2  GND                B  @BASEBOARD_FAB2_LIB.BASEBOARD_FAB2(SCH_1):GND

CAP_A  I38  C7D3   [CAP_A_0603V-22.0UF,4V,20%,X6S,A]
    1  P1V8_PCH_STBY      A  @BASEBOARD_FAB2_LIB.BASEBOARD_FAB2(SCH_1):P1V8_PCH_STBY
    2  GND                B  @BASEBOARD_FAB2_LIB.BASEBOARD_FAB2(SCH_1):GND

CAP_0402  I79  C7D4   [CAP_0402-1.0UF,16V,10%,X6S,D97A]
    1  P3V3               A  @BASEBOARD_FAB2_LIB.BASEBOARD_FAB2(SCH_1):P3V3
    2  GND                B  @BASEBOARD_FAB2_LIB.BASEBOARD_FAB2(SCH_1):GND

CAP_A  I52  C7D5   [CAP_A_0402V-0.1UF,16V,10%,X7R,A]
    1  P0V7_GTL2104_VREF_0      A  @BASEBOARD_FAB2_LIB.BASEBOARD_FAB2(SCH_1):P0V7_GTL2104_VREF_0
    2  GND                B  @BASEBOARD_FAB2_LIB.BASEBOARD_FAB2(SCH_1):GND

CAP_A  I23  C7E1   [CAP_A_0402V-0.1UF,16V,10%,X7R,A]
    1  PVCCIO_CPU0        A  @BASEBOARD_FAB2_LIB.BASEBOARD_FAB2(SCH_1):PVCCIO_CPU0
    2  GND                B  @BASEBOARD_FAB2_LIB.BASEBOARD_FAB2(SCH_1):GND

CAP_A  I32  C7E2   [CAP_A_0402V-0.1UF,16V,10%,X7R,A]
    1  PVPP_DEF           A  @BASEBOARD_FAB2_LIB.BASEBOARD_FAB2(SCH_1):PVPP_DEF
    2  GND                B  @BASEBOARD_FAB2_LIB.BASEBOARD_FAB2(SCH_1):GND

CAP_A  I92  C7E3   [CAP_A_0402V-0.1UF,16V,10%,X7R,A]
    1  P3V3_STBY          A  @BASEBOARD_FAB2_LIB.BASEBOARD_FAB2(SCH_1):P3V3_STBY
    2  GND                B  @BASEBOARD_FAB2_LIB.BASEBOARD_FAB2(SCH_1):GND

CAP_A  I115  C7E4   [CAP_A_0402V-0.1UF,16V,10%,X7R,A]
    1  P3V3_STBY          A  @BASEBOARD_FAB2_LIB.BASEBOARD_FAB2(SCH_1):P3V3_STBY
    2  GND                B  @BASEBOARD_FAB2_LIB.BASEBOARD_FAB2(SCH_1):GND

CAP_A  I52  C7E5   [CAP_A_0402V-0.1UF,16V,10%,X7R,A]
    1  P12V_STBY          A  @BASEBOARD_FAB2_LIB.BASEBOARD_FAB2(SCH_1):P12V_STBY
    2  GND                B  @BASEBOARD_FAB2_LIB.BASEBOARD_FAB2(SCH_1):GND

CAP  I53  C7E6   [CAP_0805-10UF,16V,10%,X6S,C953A]
    1  P12V_STBY          A  @BASEBOARD_FAB2_LIB.BASEBOARD_FAB2(SCH_1):P12V_STBY
    2  GND                B  @BASEBOARD_FAB2_LIB.BASEBOARD_FAB2(SCH_1):GND

CAP  I50  C7E8   [CAP_0805-10UF,16V,10%,X6S,C953A]
    1  P12V               A  @BASEBOARD_FAB2_LIB.BASEBOARD_FAB2(SCH_1):P12V
    2  GND                B  @BASEBOARD_FAB2_LIB.BASEBOARD_FAB2(SCH_1):GND

CAP_A  I49  C7E9   [CAP_A_0402V-0.1UF,16V,10%,X7R,A]
    1  P12V               A  @BASEBOARD_FAB2_LIB.BASEBOARD_FAB2(SCH_1):P12V
    2  GND                B  @BASEBOARD_FAB2_LIB.BASEBOARD_FAB2(SCH_1):GND

CAP  I14  C7E10  [CAP_0402LF-1000PF,50V,10%,X7R,A]
    1  PWRGD_P5V_STBY_R      A  @BASEBOARD_FAB2_LIB.BASEBOARD_FAB2(SCH_1):PWRGD_P5V_STBY_R
    2  GND                B  @BASEBOARD_FAB2_LIB.BASEBOARD_FAB2(SCH_1):GND

CAP  I39  C7E11  [CAP_1206LF-22UF,16V,10%,X6S,D3A]
    1  VR_FET_SW_P5V_STBY_PVIN      A  @BASEBOARD_FAB2_LIB.BASEBOARD_FAB2(SCH_1):VR_FET_SW_P5V_STBY_PVIN
    2  GND                B  @BASEBOARD_FAB2_LIB.BASEBOARD_FAB2(SCH_1):GND

CAP  I47  C7E12  [CAP_1210-47UF,16V,20%,X6S,D384A]
    1  VR_FET_SW_P5V_STBY_PVIN      A  @BASEBOARD_FAB2_LIB.BASEBOARD_FAB2(SCH_1):VR_FET_SW_P5V_STBY_PVIN
    2  GND                B  @BASEBOARD_FAB2_LIB.BASEBOARD_FAB2(SCH_1):GND

CAP  I45  C7E13  [CAP_1210-47UF,16V,20%,X6S,D384A]
    1  VR_FET_SW_P5V_STBY_PVIN      A  @BASEBOARD_FAB2_LIB.BASEBOARD_FAB2(SCH_1):VR_FET_SW_P5V_STBY_PVIN
    2  GND                B  @BASEBOARD_FAB2_LIB.BASEBOARD_FAB2(SCH_1):GND

CAP_0402  I30  C7E14  [CAP_0402-1.0UF,16V,10%,X6S,D97A]
    1  VR_P5V_STBY_VIN      A  @BASEBOARD_FAB2_LIB.BASEBOARD_FAB2(SCH_1):VR_P5V_STBY_VIN
    2  GND                B  @BASEBOARD_FAB2_LIB.BASEBOARD_FAB2(SCH_1):GND

CAP_A  I131  C7F1   [CAP_A_0402V-0.01UF,25V,10%,X7RA]
    1  P3V3_STBY          A  @BASEBOARD_FAB2_LIB.BASEBOARD_FAB2(SCH_1):P3V3_STBY
    2  GND                B  @BASEBOARD_FAB2_LIB.BASEBOARD_FAB2(SCH_1):GND

CAP_A  I130  C7F2   [CAP_A_0402V-1.0UF,6.3V,10%,X6SA]
    1  P3V3_STBY          A  @BASEBOARD_FAB2_LIB.BASEBOARD_FAB2(SCH_1):P3V3_STBY
    2  GND                B  @BASEBOARD_FAB2_LIB.BASEBOARD_FAB2(SCH_1):GND

CAP  I175  C7F3   [CAP_0402LF-3300PF,50V,10%,EMPTA]
    2  VR_PVPP_ABC_SNUB      B  @BASEBOARD_FAB2_LIB.BASEBOARD_FAB2(SCH_1):VR_PVPP_ABC_SNUB
    1  VR_PVPP_ABC_PHASE      A  @BASEBOARD_FAB2_LIB.BASEBOARD_FAB2(SCH_1):VR_PVPP_ABC_PHASE

CAP  I159  C7F4   [CAP_0603LF-0.1UF,25V,10%,X7R,6A]
    1  VR_PVPP_ABC_PHASE      A  @BASEBOARD_FAB2_LIB.BASEBOARD_FAB2(SCH_1):VR_PVPP_ABC_PHASE
    2  VR_PVPP_ABC_BOOT_R      B  @BASEBOARD_FAB2_LIB.BASEBOARD_FAB2(SCH_1):VR_PVPP_ABC_BOOT_R

CAP  I209  C7F5   [CAP_0805-10UF,16V,10%,X6S,C953A]
    1  VR_FET_SW_P12V_STBY_PVPP_ABC      A  @BASEBOARD_FAB2_LIB.BASEBOARD_FAB2(SCH_1):VR_FET_SW_P12V_STBY_PVPP_ABC
    2  GND                B  @BASEBOARD_FAB2_LIB.BASEBOARD_FAB2(SCH_1):GND

CAP_A  I205  C7F6   [CAP_A_0402V-0.1UF,16V,10%,X7R,A]
    1  VR_FET_SW_P12V_STBY_PVPP_ABC      A  @BASEBOARD_FAB2_LIB.BASEBOARD_FAB2(SCH_1):VR_FET_SW_P12V_STBY_PVPP_ABC
    2  GND                B  @BASEBOARD_FAB2_LIB.BASEBOARD_FAB2(SCH_1):GND

CAP  I151  C7F7   [CAP_1210-47UF,16V,20%,X6S,D384A]
    1  VR_FET_SW_P12V_STBY_PVPP_ABC      A  @BASEBOARD_FAB2_LIB.BASEBOARD_FAB2(SCH_1):VR_FET_SW_P12V_STBY_PVPP_ABC
    2  GND                B  @BASEBOARD_FAB2_LIB.BASEBOARD_FAB2(SCH_1):GND

CAP  I140  C7F8   [CAP_0402LF-1000PF,50V,10%,EMPTA]
    1  FM_PVPP_CPU0_EN      A  @BASEBOARD_FAB2_LIB.BASEBOARD_FAB2(SCH_1):FM_PVPP_CPU0_EN
    2  AGND_PVPP_ABC      B  @BASEBOARD_FAB2_LIB.BASEBOARD_FAB2(SCH_1):AGND_PVPP_ABC

CAP  I199  C7F9   [CAP_0402LF-100.0PF,50V,5%,COG,A]
    1  VR_FB_PVPP_ABC      A  @BASEBOARD_FAB2_LIB.BASEBOARD_FAB2(SCH_1):VR_FB_PVPP_ABC
    2  VR_COMP_PVPP_ABC_3      B  @BASEBOARD_FAB2_LIB.BASEBOARD_FAB2(SCH_1):VR_COMP_PVPP_ABC_3

CAP_0402  I194  C7F10  [CAP_0402-0.027UF,16V,10%,X7R,AA]
    1  VR_PVPP_ABC_SS      A  @BASEBOARD_FAB2_LIB.BASEBOARD_FAB2(SCH_1):VR_PVPP_ABC_SS
    2  AGND_PVPP_ABC      B  @BASEBOARD_FAB2_LIB.BASEBOARD_FAB2(SCH_1):AGND_PVPP_ABC

CAP  I142  C7F11  [CAP_0402LF-1000PF,50V,10%,X7R,A]
    1  PWRGD_PVPP_ABC_R      A  @BASEBOARD_FAB2_LIB.BASEBOARD_FAB2(SCH_1):PWRGD_PVPP_ABC_R
    2  GND                B  @BASEBOARD_FAB2_LIB.BASEBOARD_FAB2(SCH_1):GND

CAP  I200  C7F12  [CAP_0402LF-2200PF,50V,10%,X7R,A]
    1  VR_COMP_RC_PVPP_ABC      A  @BASEBOARD_FAB2_LIB.BASEBOARD_FAB2(SCH_1):VR_COMP_RC_PVPP_ABC
    2  VR_COMP_PVPP_ABC_3      B  @BASEBOARD_FAB2_LIB.BASEBOARD_FAB2(SCH_1):VR_COMP_PVPP_ABC_3

CAP  I219  C7F13  [CAP_0402LF-2200PF,50V,10%,X7R,A]
    2  VR_FB_PVPP_ABC      B  @BASEBOARD_FAB2_LIB.BASEBOARD_FAB2(SCH_1):VR_FB_PVPP_ABC
    1  VR_COMP_PVPP_ABC      A  @BASEBOARD_FAB2_LIB.BASEBOARD_FAB2(SCH_1):VR_COMP_PVPP_ABC

CAP  I305  C7F14  [CAP_0402LF-1000PF,50V,10%,X7R,A]
    1  PWRGD_PVDDQ_ABC_R      A  @BASEBOARD_FAB2_LIB.BASEBOARD_FAB2(SCH_1):PWRGD_PVDDQ_ABC_R
    2  GND                B  @BASEBOARD_FAB2_LIB.BASEBOARD_FAB2(SCH_1):GND

CAP_A  I327  C7F15  [CAP_A_0402V-0.1UF,16V,10%,X7R,A]
    1  VR_PVDDQ_ABC_VD12      A  @BASEBOARD_FAB2_LIB.BASEBOARD_FAB2(SCH_1):VR_PVDDQ_ABC_VD12
    2  GND                B  @BASEBOARD_FAB2_LIB.BASEBOARD_FAB2(SCH_1):GND

CAP_A  I325  C7F16  [CAP_A_0402V-1.0UF,6.3V,10%,X6SA]
    1  VR_PVDDQ_ABC_VD12      A  @BASEBOARD_FAB2_LIB.BASEBOARD_FAB2(SCH_1):VR_PVDDQ_ABC_VD12
    2  GND                B  @BASEBOARD_FAB2_LIB.BASEBOARD_FAB2(SCH_1):GND

CAP_A  I311  C7F17  [CAP_A_0402V-0.1UF,16V,10%,X7R,A]
    1  VR_PVDDQ_ABC_VDD      A  @BASEBOARD_FAB2_LIB.BASEBOARD_FAB2(SCH_1):VR_PVDDQ_ABC_VDD
    2  GND                B  @BASEBOARD_FAB2_LIB.BASEBOARD_FAB2(SCH_1):GND

CAP_A  I309  C7F18  [CAP_A_0402V-1.0UF,6.3V,10%,X6SA]
    1  VR_PVDDQ_ABC_VDD      A  @BASEBOARD_FAB2_LIB.BASEBOARD_FAB2(SCH_1):VR_PVDDQ_ABC_VDD
    2  GND                B  @BASEBOARD_FAB2_LIB.BASEBOARD_FAB2(SCH_1):GND

CAP  I339  C7G1   [CAP_0402LF-1000PF,50V,10%,X7R,A]
    1  VR_PVDDQ_ABC_VINSEN      A  @BASEBOARD_FAB2_LIB.BASEBOARD_FAB2(SCH_1):VR_PVDDQ_ABC_VINSEN
    2  GND                B  @BASEBOARD_FAB2_LIB.BASEBOARD_FAB2(SCH_1):GND

CAPP  I175  C7G2   [CAPP_2626-270UF,16V,20%,OSCON,A]
    1  VR_FET_SW_P12V_STBY_PVDDQ_ABC      A  @BASEBOARD_FAB2_LIB.BASEBOARD_FAB2(SCH_1):VR_FET_SW_P12V_STBY_PVDDQ_ABC
    2  GND                B  @BASEBOARD_FAB2_LIB.BASEBOARD_FAB2(SCH_1):GND

CAP  I320  C7G3   [CAP_0402LF-220PF,50V,10%,X7R,AA]
    2  GND                B  @BASEBOARD_FAB2_LIB.BASEBOARD_FAB2(SCH_1):GND
    1  A_TSENSE_PVDDQ_ABC      A  @BASEBOARD_FAB2_LIB.BASEBOARD_FAB2(SCH_1):A_TSENSE_PVDDQ_ABC

CAP  I342  C7G4   [CAP_0402LF-220PF,50V,10%,X7R,AA]
    2  VSENSE_PVDDQ_ABC_N      B  @BASEBOARD_FAB2_LIB.BASEBOARD_FAB2(SCH_1):VSENSE_PVDDQ_ABC_N
    1  VR_PVDDQ_ABC_AVSP      A  @BASEBOARD_FAB2_LIB.BASEBOARD_FAB2(SCH_1):VR_PVDDQ_ABC_AVSP

CAP_0402  I20  C7G5   [CAP_0402-0.22UF,16V,10%,X7R,A3A]
    1  P3E_CPU0_PE2_SS_TXP<15>      A  @BASEBOARD_FAB2_LIB.BASEBOARD_FAB2(SCH_1):P3E_CPU0_PE2_SS_TXP<15>
    2  P3E_CPU0_PE2_SS_C_TXP<15>      B  @BASEBOARD_FAB2_LIB.BASEBOARD_FAB2(SCH_1):P3E_CPU0_PE2_SS_C_TXP<15>

CAP_0402  I6   C7G6   [CAP_0402-0.22UF,16V,10%,X7R,A3A]
    1  P3E_CPU0_PE2_SS_TXN<15>      A  @BASEBOARD_FAB2_LIB.BASEBOARD_FAB2(SCH_1):P3E_CPU0_PE2_SS_TXN<15>
    2  P3E_CPU0_PE2_SS_C_TXN<15>      B  @BASEBOARD_FAB2_LIB.BASEBOARD_FAB2(SCH_1):P3E_CPU0_PE2_SS_C_TXN<15>

CAP_0402  I7   C7G7   [CAP_0402-0.22UF,16V,10%,X7R,A3A]
    1  P3E_CPU0_PE2_SS_TXN<14>      A  @BASEBOARD_FAB2_LIB.BASEBOARD_FAB2(SCH_1):P3E_CPU0_PE2_SS_TXN<14>
    2  P3E_CPU0_PE2_SS_C_TXN<14>      B  @BASEBOARD_FAB2_LIB.BASEBOARD_FAB2(SCH_1):P3E_CPU0_PE2_SS_C_TXN<14>

CAP_0402  I22  C7G8   [CAP_0402-0.22UF,16V,10%,X7R,A3A]
    1  P3E_CPU0_PE2_SS_TXP<14>      A  @BASEBOARD_FAB2_LIB.BASEBOARD_FAB2(SCH_1):P3E_CPU0_PE2_SS_TXP<14>
    2  P3E_CPU0_PE2_SS_C_TXP<14>      B  @BASEBOARD_FAB2_LIB.BASEBOARD_FAB2(SCH_1):P3E_CPU0_PE2_SS_C_TXP<14>

CAP_0402  I21  C7G9   [CAP_0402-0.22UF,16V,10%,X7R,A3A]
    1  P3E_CPU0_PE2_SS_TXP<13>      A  @BASEBOARD_FAB2_LIB.BASEBOARD_FAB2(SCH_1):P3E_CPU0_PE2_SS_TXP<13>
    2  P3E_CPU0_PE2_SS_C_TXP<13>      B  @BASEBOARD_FAB2_LIB.BASEBOARD_FAB2(SCH_1):P3E_CPU0_PE2_SS_C_TXP<13>

CAP_0402  I8   C7G10  [CAP_0402-0.22UF,16V,10%,X7R,A3A]
    1  P3E_CPU0_PE2_SS_TXN<13>      A  @BASEBOARD_FAB2_LIB.BASEBOARD_FAB2(SCH_1):P3E_CPU0_PE2_SS_TXN<13>
    2  P3E_CPU0_PE2_SS_C_TXN<13>      B  @BASEBOARD_FAB2_LIB.BASEBOARD_FAB2(SCH_1):P3E_CPU0_PE2_SS_C_TXN<13>

CAP_0402  I27  C7G11  [CAP_0402-0.22UF,16V,10%,X7R,A3A]
    1  P3E_CPU0_PE2_SS_TXP<12>      A  @BASEBOARD_FAB2_LIB.BASEBOARD_FAB2(SCH_1):P3E_CPU0_PE2_SS_TXP<12>
    2  P3E_CPU0_PE2_SS_C_TXP<12>      B  @BASEBOARD_FAB2_LIB.BASEBOARD_FAB2(SCH_1):P3E_CPU0_PE2_SS_C_TXP<12>

CAP_0402  I12  C7G12  [CAP_0402-0.22UF,16V,10%,X7R,A3A]
    1  P3E_CPU0_PE2_SS_TXN<12>      A  @BASEBOARD_FAB2_LIB.BASEBOARD_FAB2(SCH_1):P3E_CPU0_PE2_SS_TXN<12>
    2  P3E_CPU0_PE2_SS_C_TXN<12>      B  @BASEBOARD_FAB2_LIB.BASEBOARD_FAB2(SCH_1):P3E_CPU0_PE2_SS_C_TXN<12>

CAP_0402  I13  C7G13  [CAP_0402-0.22UF,16V,10%,X7R,A3A]
    1  P3E_CPU0_PE2_SS_TXN<11>      A  @BASEBOARD_FAB2_LIB.BASEBOARD_FAB2(SCH_1):P3E_CPU0_PE2_SS_TXN<11>
    2  P3E_CPU0_PE2_SS_C_TXN<11>      B  @BASEBOARD_FAB2_LIB.BASEBOARD_FAB2(SCH_1):P3E_CPU0_PE2_SS_C_TXN<11>

CAP_0402  I28  C7G14  [CAP_0402-0.22UF,16V,10%,X7R,A3A]
    1  P3E_CPU0_PE2_SS_TXP<11>      A  @BASEBOARD_FAB2_LIB.BASEBOARD_FAB2(SCH_1):P3E_CPU0_PE2_SS_TXP<11>
    2  P3E_CPU0_PE2_SS_C_TXP<11>      B  @BASEBOARD_FAB2_LIB.BASEBOARD_FAB2(SCH_1):P3E_CPU0_PE2_SS_C_TXP<11>

CAP_0402  I45  C7G15  [CAP_0402-0.22UF,16V,10%,X7R,A3A]
    1  P3E_CPU0_PE2_SS_TXP<10>      A  @BASEBOARD_FAB2_LIB.BASEBOARD_FAB2(SCH_1):P3E_CPU0_PE2_SS_TXP<10>
    2  P3E_CPU0_PE2_SS_C_TXP<10>      B  @BASEBOARD_FAB2_LIB.BASEBOARD_FAB2(SCH_1):P3E_CPU0_PE2_SS_C_TXP<10>

CAP_0402  I31  C7G16  [CAP_0402-0.22UF,16V,10%,X7R,A3A]
    1  P3E_CPU0_PE2_SS_TXN<10>      A  @BASEBOARD_FAB2_LIB.BASEBOARD_FAB2(SCH_1):P3E_CPU0_PE2_SS_TXN<10>
    2  P3E_CPU0_PE2_SS_C_TXN<10>      B  @BASEBOARD_FAB2_LIB.BASEBOARD_FAB2(SCH_1):P3E_CPU0_PE2_SS_C_TXN<10>

CAP_0402  I44  C7G17  [CAP_0402-0.22UF,16V,10%,X7R,A3A]
    1  P3E_CPU0_PE2_SS_TXP<9>      A  @BASEBOARD_FAB2_LIB.BASEBOARD_FAB2(SCH_1):P3E_CPU0_PE2_SS_TXP<9>
    2  P3E_CPU0_PE2_SS_C_TXP<9>      B  @BASEBOARD_FAB2_LIB.BASEBOARD_FAB2(SCH_1):P3E_CPU0_PE2_SS_C_TXP<9>

CAP_0402  I32  C7G18  [CAP_0402-0.22UF,16V,10%,X7R,A3A]
    1  P3E_CPU0_PE2_SS_TXN<9>      A  @BASEBOARD_FAB2_LIB.BASEBOARD_FAB2(SCH_1):P3E_CPU0_PE2_SS_TXN<9>
    2  P3E_CPU0_PE2_SS_C_TXN<9>      B  @BASEBOARD_FAB2_LIB.BASEBOARD_FAB2(SCH_1):P3E_CPU0_PE2_SS_C_TXN<9>

CAP_0402  I46  C7G19  [CAP_0402-0.22UF,16V,10%,X7R,A3A]
    1  P3E_CPU0_PE2_SS_TXP<8>      A  @BASEBOARD_FAB2_LIB.BASEBOARD_FAB2(SCH_1):P3E_CPU0_PE2_SS_TXP<8>
    2  P3E_CPU0_PE2_SS_C_TXP<8>      B  @BASEBOARD_FAB2_LIB.BASEBOARD_FAB2(SCH_1):P3E_CPU0_PE2_SS_C_TXP<8>

CAP_0402  I34  C7G20  [CAP_0402-0.22UF,16V,10%,X7R,A3A]
    1  P3E_CPU0_PE2_SS_TXN<8>      A  @BASEBOARD_FAB2_LIB.BASEBOARD_FAB2(SCH_1):P3E_CPU0_PE2_SS_TXN<8>
    2  P3E_CPU0_PE2_SS_C_TXN<8>      B  @BASEBOARD_FAB2_LIB.BASEBOARD_FAB2(SCH_1):P3E_CPU0_PE2_SS_C_TXN<8>

CAP_0402  I51  C7G21  [CAP_0402-0.22UF,16V,10%,X7R,A3A]
    1  P3E_CPU0_PE2_SS_TXP<7>      A  @BASEBOARD_FAB2_LIB.BASEBOARD_FAB2(SCH_1):P3E_CPU0_PE2_SS_TXP<7>
    2  P3E_CPU0_PE2_SS_C_TXP<7>      B  @BASEBOARD_FAB2_LIB.BASEBOARD_FAB2(SCH_1):P3E_CPU0_PE2_SS_C_TXP<7>

CAP_0402  I37  C7G22  [CAP_0402-0.22UF,16V,10%,X7R,A3A]
    1  P3E_CPU0_PE2_SS_TXN<7>      A  @BASEBOARD_FAB2_LIB.BASEBOARD_FAB2(SCH_1):P3E_CPU0_PE2_SS_TXN<7>
    2  P3E_CPU0_PE2_SS_C_TXN<7>      B  @BASEBOARD_FAB2_LIB.BASEBOARD_FAB2(SCH_1):P3E_CPU0_PE2_SS_C_TXN<7>

CAP_0402  I52  C7G23  [CAP_0402-0.22UF,16V,10%,X7R,A3A]
    1  P3E_CPU0_PE2_SS_TXP<6>      A  @BASEBOARD_FAB2_LIB.BASEBOARD_FAB2(SCH_1):P3E_CPU0_PE2_SS_TXP<6>
    2  P3E_CPU0_PE2_SS_C_TXP<6>      B  @BASEBOARD_FAB2_LIB.BASEBOARD_FAB2(SCH_1):P3E_CPU0_PE2_SS_C_TXP<6>

CAP_0402  I1   C7G24  [CAP_0402-0.22UF,16V,10%,X7R,A3A]
    1  P3E_CPU0_PE2_SS_TXN<6>      A  @BASEBOARD_FAB2_LIB.BASEBOARD_FAB2(SCH_1):P3E_CPU0_PE2_SS_TXN<6>
    2  P3E_CPU0_PE2_SS_C_TXN<6>      B  @BASEBOARD_FAB2_LIB.BASEBOARD_FAB2(SCH_1):P3E_CPU0_PE2_SS_C_TXN<6>

CAP_0402  I69  C7G25  [CAP_0402-0.22UF,16V,10%,X7R,A3A]
    1  P3E_CPU0_PE2_SS_TXP<5>      A  @BASEBOARD_FAB2_LIB.BASEBOARD_FAB2(SCH_1):P3E_CPU0_PE2_SS_TXP<5>
    2  P3E_CPU0_PE2_SS_C_TXP<5>      B  @BASEBOARD_FAB2_LIB.BASEBOARD_FAB2(SCH_1):P3E_CPU0_PE2_SS_C_TXP<5>

CAP_0402  I55  C7G26  [CAP_0402-0.22UF,16V,10%,X7R,A3A]
    1  P3E_CPU0_PE2_SS_TXN<5>      A  @BASEBOARD_FAB2_LIB.BASEBOARD_FAB2(SCH_1):P3E_CPU0_PE2_SS_TXN<5>
    2  P3E_CPU0_PE2_SS_C_TXN<5>      B  @BASEBOARD_FAB2_LIB.BASEBOARD_FAB2(SCH_1):P3E_CPU0_PE2_SS_C_TXN<5>

CAP  I68  C7G27  [CAP_0805LF-22UF,4V,20%,X6S,C95A]
    1  PVDDQ_ABC          A  @BASEBOARD_FAB2_LIB.BASEBOARD_FAB2(SCH_1):PVDDQ_ABC
    2  GND                B  @BASEBOARD_FAB2_LIB.BASEBOARD_FAB2(SCH_1):GND

CAPP  I75  C7G28  [CAPP_3018-470UF,2.5V,20%,ALUM,A]
    1  PVDDQ_ABC          A  @BASEBOARD_FAB2_LIB.BASEBOARD_FAB2(SCH_1):PVDDQ_ABC
    2  GND                B  @BASEBOARD_FAB2_LIB.BASEBOARD_FAB2(SCH_1):GND

CAP_A  I51  C7G29  [CAP_A_0402V-0.1UF,16V,10%,X7R,A]
    1  VR_FET_SW_P12V_STBY_PVDDQ_ABC      A  @BASEBOARD_FAB2_LIB.BASEBOARD_FAB2(SCH_1):VR_FET_SW_P12V_STBY_PVDDQ_ABC
    2  GND                B  @BASEBOARD_FAB2_LIB.BASEBOARD_FAB2(SCH_1):GND

CAP_0402  I79  C7G30  [CAP_0402-1.0UF,16V,10%,X6S,D97A]
    1  VR_FET_SW_P12V_STBY_PVDDQ_ABC      A  @BASEBOARD_FAB2_LIB.BASEBOARD_FAB2(SCH_1):VR_FET_SW_P12V_STBY_PVDDQ_ABC
    2  GND                B  @BASEBOARD_FAB2_LIB.BASEBOARD_FAB2(SCH_1):GND

CAP_0402  I44  C7G31  [CAP_0402-0.220UF,16V,10%,X7R,AA]
    2  VR_PVDDQ_ABC_PH1_PHASE      B  @BASEBOARD_FAB2_LIB.BASEBOARD_FAB2(SCH_1):VR_PVDDQ_ABC_PH1_PHASE
    1  VR_PVDDQ_ABC_PH1_BOOT      A  @BASEBOARD_FAB2_LIB.BASEBOARD_FAB2(SCH_1):VR_PVDDQ_ABC_PH1_BOOT

CAP_0402  I50  C7G33  [CAP_0402-1.0UF,16V,10%,X6S,D97A]
    1  VR_PVDDQ_ABC_PH1_VCIN      A  @BASEBOARD_FAB2_LIB.BASEBOARD_FAB2(SCH_1):VR_PVDDQ_ABC_PH1_VCIN
    2  GND                B  @BASEBOARD_FAB2_LIB.BASEBOARD_FAB2(SCH_1):GND

CAP_0402  I54  C7G34  [CAP_0402-0.22UF,16V,10%,X7R,A3A]
    1  P5V_STBY           A  @BASEBOARD_FAB2_LIB.BASEBOARD_FAB2(SCH_1):P5V_STBY
    2  GND                B  @BASEBOARD_FAB2_LIB.BASEBOARD_FAB2(SCH_1):GND

CAP_A  I53  C7G35  [CAP_A_0402V-1.0UF,6.3V,10%,X6SA]
    1  P5V_STBY           A  @BASEBOARD_FAB2_LIB.BASEBOARD_FAB2(SCH_1):P5V_STBY
    2  GND                B  @BASEBOARD_FAB2_LIB.BASEBOARD_FAB2(SCH_1):GND

CAP_A  I78  C7G36  [CAP_A_0402V-0.1UF,16V,10%,X7R,A]
    1  VR_FET_SW_P12V_STBY_PVDDQ_ABC      A  @BASEBOARD_FAB2_LIB.BASEBOARD_FAB2(SCH_1):VR_FET_SW_P12V_STBY_PVDDQ_ABC
    2  GND                B  @BASEBOARD_FAB2_LIB.BASEBOARD_FAB2(SCH_1):GND

CAP_0402  I48  C7G37  [CAP_0402-1.0UF,16V,10%,X6S,D97A]
    1  VR_FET_SW_P12V_STBY_PVDDQ_ABC      A  @BASEBOARD_FAB2_LIB.BASEBOARD_FAB2(SCH_1):VR_FET_SW_P12V_STBY_PVDDQ_ABC
    2  GND                B  @BASEBOARD_FAB2_LIB.BASEBOARD_FAB2(SCH_1):GND

CAP_0402  I75  C7G38  [CAP_0402-0.220UF,16V,10%,X7R,AA]
    2  VR_PVDDQ_ABC_PH2_PHASE      B  @BASEBOARD_FAB2_LIB.BASEBOARD_FAB2(SCH_1):VR_PVDDQ_ABC_PH2_PHASE
    1  VR_PVDDQ_ABC_PH2_BOOT      A  @BASEBOARD_FAB2_LIB.BASEBOARD_FAB2(SCH_1):VR_PVDDQ_ABC_PH2_BOOT

CAP_0402  I77  C7G40  [CAP_0402-1.0UF,16V,10%,X6S,D97A]
    1  VR_PVDDQ_ABC_PH2_VCIN      A  @BASEBOARD_FAB2_LIB.BASEBOARD_FAB2(SCH_1):VR_PVDDQ_ABC_PH2_VCIN
    2  GND                B  @BASEBOARD_FAB2_LIB.BASEBOARD_FAB2(SCH_1):GND

CAP_0402  I72  C7G41  [CAP_0402-0.22UF,16V,10%,X7R,A3A]
    1  P5V_STBY           A  @BASEBOARD_FAB2_LIB.BASEBOARD_FAB2(SCH_1):P5V_STBY
    2  GND                B  @BASEBOARD_FAB2_LIB.BASEBOARD_FAB2(SCH_1):GND

CAP_A  I73  C7G42  [CAP_A_0402V-1.0UF,6.3V,10%,X6SA]
    1  P5V_STBY           A  @BASEBOARD_FAB2_LIB.BASEBOARD_FAB2(SCH_1):P5V_STBY
    2  GND                B  @BASEBOARD_FAB2_LIB.BASEBOARD_FAB2(SCH_1):GND

CAP  I92  C7L1   [CAP_0805-100UF,4V,20%,X5R,6024A]
    1  PVDDQ_KLM          A  @BASEBOARD_FAB2_LIB.BASEBOARD_FAB2(SCH_1):PVDDQ_KLM
    2  GND                B  @BASEBOARD_FAB2_LIB.BASEBOARD_FAB2(SCH_1):GND

CAP  I88  C7L2   [CAP_0603LF-10UF,4V,20%,X6S,E15A]
    1  PVPP_KLM           A  @BASEBOARD_FAB2_LIB.BASEBOARD_FAB2(SCH_1):PVPP_KLM
    2  GND                B  @BASEBOARD_FAB2_LIB.BASEBOARD_FAB2(SCH_1):GND

CAP  I87  C7L3   [CAP_0603LF-10UF,4V,20%,X6S,E15A]
    1  PVPP_KLM           A  @BASEBOARD_FAB2_LIB.BASEBOARD_FAB2(SCH_1):PVPP_KLM
    2  GND                B  @BASEBOARD_FAB2_LIB.BASEBOARD_FAB2(SCH_1):GND

CAP_A  I238  C7L4   [CAP_A_0603V-22.0UF,4V,20%,X6S,A]
    1  PVDDQ_KLM          A  @BASEBOARD_FAB2_LIB.BASEBOARD_FAB2(SCH_1):PVDDQ_KLM
    2  GND                B  @BASEBOARD_FAB2_LIB.BASEBOARD_FAB2(SCH_1):GND

CAP_A  I225  C7L5   [CAP_A_0603V-22.0UF,4V,20%,X6S,A]
    1  PVDDQ_KLM          A  @BASEBOARD_FAB2_LIB.BASEBOARD_FAB2(SCH_1):PVDDQ_KLM
    2  GND                B  @BASEBOARD_FAB2_LIB.BASEBOARD_FAB2(SCH_1):GND

CAP  I90  C7L6   [CAP_0603LF-10UF,4V,20%,X6S,E15A]
    1  PVPP_KLM           A  @BASEBOARD_FAB2_LIB.BASEBOARD_FAB2(SCH_1):PVPP_KLM
    2  GND                B  @BASEBOARD_FAB2_LIB.BASEBOARD_FAB2(SCH_1):GND

CAP  I89  C7L7   [CAP_0603LF-10UF,4V,20%,X6S,E15A]
    1  PVPP_KLM           A  @BASEBOARD_FAB2_LIB.BASEBOARD_FAB2(SCH_1):PVPP_KLM
    2  GND                B  @BASEBOARD_FAB2_LIB.BASEBOARD_FAB2(SCH_1):GND

CAP_A  I231  C7M1   [CAP_A_0603V-22.0UF,4V,20%,X6S,A]
    1  PVDDQ_KLM          A  @BASEBOARD_FAB2_LIB.BASEBOARD_FAB2(SCH_1):PVDDQ_KLM
    2  GND                B  @BASEBOARD_FAB2_LIB.BASEBOARD_FAB2(SCH_1):GND

CAP_A  I232  C7M2   [CAP_A_0603V-22.0UF,4V,20%,X6S,A]
    1  PVDDQ_KLM          A  @BASEBOARD_FAB2_LIB.BASEBOARD_FAB2(SCH_1):PVDDQ_KLM
    2  GND                B  @BASEBOARD_FAB2_LIB.BASEBOARD_FAB2(SCH_1):GND

CAP  I92  C7M3   [CAP_0603LF-10UF,4V,20%,X6S,E15A]
    1  PVPP_KLM           A  @BASEBOARD_FAB2_LIB.BASEBOARD_FAB2(SCH_1):PVPP_KLM
    2  GND                B  @BASEBOARD_FAB2_LIB.BASEBOARD_FAB2(SCH_1):GND

CAP  I91  C7M4   [CAP_0603LF-10UF,4V,20%,X6S,E15A]
    1  PVPP_KLM           A  @BASEBOARD_FAB2_LIB.BASEBOARD_FAB2(SCH_1):PVPP_KLM
    2  GND                B  @BASEBOARD_FAB2_LIB.BASEBOARD_FAB2(SCH_1):GND

CAP_A  I202  C7M5   [CAP_A_0603V-47UF,4V,20%,X5R,60A]
    1  PVDDQ_KLM          A  @BASEBOARD_FAB2_LIB.BASEBOARD_FAB2(SCH_1):PVDDQ_KLM
    2  GND                B  @BASEBOARD_FAB2_LIB.BASEBOARD_FAB2(SCH_1):GND

CAPP  I108  C7M6   [CAPP_3018-68UF,16V,20%,TANT,72A]
    1  P12V_STBY          A  @BASEBOARD_FAB2_LIB.BASEBOARD_FAB2(SCH_1):P12V_STBY
    2  GND                B  @BASEBOARD_FAB2_LIB.BASEBOARD_FAB2(SCH_1):GND

CAP  I105  C7P1   [CAP_0805-47UF,4V,20%,X6S,C9533A]
    1  PVCCIN_CPU1        A  @BASEBOARD_FAB2_LIB.BASEBOARD_FAB2(SCH_1):PVCCIN_CPU1
    2  GND                B  @BASEBOARD_FAB2_LIB.BASEBOARD_FAB2(SCH_1):GND

CAP  I100  C7P2   [CAP_0805-47UF,4V,20%,X6S,C9533A]
    1  PVCCIN_CPU1        A  @BASEBOARD_FAB2_LIB.BASEBOARD_FAB2(SCH_1):PVCCIN_CPU1
    2  GND                B  @BASEBOARD_FAB2_LIB.BASEBOARD_FAB2(SCH_1):GND

CAP  I52  C7P3   [CAP_0805-47UF,4V,20%,X6S,C9533A]
    1  PVCCIO_CPU1        A  @BASEBOARD_FAB2_LIB.BASEBOARD_FAB2(SCH_1):PVCCIO_CPU1
    2  GND                B  @BASEBOARD_FAB2_LIB.BASEBOARD_FAB2(SCH_1):GND

CAP  I195  C7P4   [CAP_0805-47UF,4V,20%,X6S,C9533A]
    1  PVCCMCP_CPU1       A  @BASEBOARD_FAB2_LIB.BASEBOARD_FAB2(SCH_1):PVCCMCP_CPU1
    2  GND                B  @BASEBOARD_FAB2_LIB.BASEBOARD_FAB2(SCH_1):GND

CAP  I182  C7P5   [CAP_0805-47UF,4V,20%,X6S,C9533A]
    1  PVCCMCP_CPU1       A  @BASEBOARD_FAB2_LIB.BASEBOARD_FAB2(SCH_1):PVCCMCP_CPU1
    2  GND                B  @BASEBOARD_FAB2_LIB.BASEBOARD_FAB2(SCH_1):GND

CAP  I23  C7P6   [CAP_0805-47UF,4V,20%,X6S,C9533A]
    1  PVCCMCP_CPU1       A  @BASEBOARD_FAB2_LIB.BASEBOARD_FAB2(SCH_1):PVCCMCP_CPU1
    2  GND                B  @BASEBOARD_FAB2_LIB.BASEBOARD_FAB2(SCH_1):GND

CAP  I27  C7P7   [CAP_0805-47UF,4V,20%,X6S,C9533A]
    1  PVCCMCP_CPU1       A  @BASEBOARD_FAB2_LIB.BASEBOARD_FAB2(SCH_1):PVCCMCP_CPU1
    2  GND                B  @BASEBOARD_FAB2_LIB.BASEBOARD_FAB2(SCH_1):GND

CAP  I184  C7P8   [CAP_0805-47UF,4V,20%,X6S,C9533A]
    1  PVCCMCP_CPU1       A  @BASEBOARD_FAB2_LIB.BASEBOARD_FAB2(SCH_1):PVCCMCP_CPU1
    2  GND                B  @BASEBOARD_FAB2_LIB.BASEBOARD_FAB2(SCH_1):GND

CAP  I181  C7P9   [CAP_0805-47UF,4V,20%,X6S,C9533A]
    1  PVCCMCP_CPU1       A  @BASEBOARD_FAB2_LIB.BASEBOARD_FAB2(SCH_1):PVCCMCP_CPU1
    2  GND                B  @BASEBOARD_FAB2_LIB.BASEBOARD_FAB2(SCH_1):GND

CAP  I26  C7P10  [CAP_0805-47UF,4V,20%,X6S,C9533A]
    1  PVCCMCP_CPU1       A  @BASEBOARD_FAB2_LIB.BASEBOARD_FAB2(SCH_1):PVCCMCP_CPU1
    2  GND                B  @BASEBOARD_FAB2_LIB.BASEBOARD_FAB2(SCH_1):GND

CAP  I183  C7P11  [CAP_0805-47UF,4V,20%,X6S,C9533A]
    1  PVCCMCP_CPU1       A  @BASEBOARD_FAB2_LIB.BASEBOARD_FAB2(SCH_1):PVCCMCP_CPU1
    2  GND                B  @BASEBOARD_FAB2_LIB.BASEBOARD_FAB2(SCH_1):GND

CAP_A  I179  C7P12  [CAP_A_0603V-22.0UF,4V,20%,X6S,A]
    1  PVCCIO_CPU1        A  @BASEBOARD_FAB2_LIB.BASEBOARD_FAB2(SCH_1):PVCCIO_CPU1
    2  GND                B  @BASEBOARD_FAB2_LIB.BASEBOARD_FAB2(SCH_1):GND

CAP  I25  C7P13  [CAP_0805-47UF,4V,20%,X6S,C9533A]
    1  PVCCMCP_CPU1       A  @BASEBOARD_FAB2_LIB.BASEBOARD_FAB2(SCH_1):PVCCMCP_CPU1
    2  GND                B  @BASEBOARD_FAB2_LIB.BASEBOARD_FAB2(SCH_1):GND

CAP  I49  C7P14  [CAP_0805-47UF,4V,20%,X6S,C9533A]
    1  PVCCMCP_CPU1       A  @BASEBOARD_FAB2_LIB.BASEBOARD_FAB2(SCH_1):PVCCMCP_CPU1
    2  GND                B  @BASEBOARD_FAB2_LIB.BASEBOARD_FAB2(SCH_1):GND

CAP  I45  C7P15  [CAP_0805-47UF,4V,20%,X6S,C9533A]
    1  PVCCMCP_CPU1       A  @BASEBOARD_FAB2_LIB.BASEBOARD_FAB2(SCH_1):PVCCMCP_CPU1
    2  GND                B  @BASEBOARD_FAB2_LIB.BASEBOARD_FAB2(SCH_1):GND

CAP_A  I206  C7P16  [CAP_A_0603V-22.0UF,4V,20%,X6S,A]
    1  PVCCIO_CPU1        A  @BASEBOARD_FAB2_LIB.BASEBOARD_FAB2(SCH_1):PVCCIO_CPU1
    2  GND                B  @BASEBOARD_FAB2_LIB.BASEBOARD_FAB2(SCH_1):GND

CAP  I29  C7P17  [CAP_0805-47UF,4V,20%,X6S,C9533A]
    1  PVCCIO_CPU1        A  @BASEBOARD_FAB2_LIB.BASEBOARD_FAB2(SCH_1):PVCCIO_CPU1
    2  GND                B  @BASEBOARD_FAB2_LIB.BASEBOARD_FAB2(SCH_1):GND

CAP  I51  C7P18  [CAP_0805-47UF,4V,20%,X6S,C9533A]
    1  PVCCIO_CPU1        A  @BASEBOARD_FAB2_LIB.BASEBOARD_FAB2(SCH_1):PVCCIO_CPU1
    2  GND                B  @BASEBOARD_FAB2_LIB.BASEBOARD_FAB2(SCH_1):GND

CAP  I215  C7P19  [CAP_0805-47UF,4V,20%,X6S,C9533A]
    1  PVCCIN_CPU1        A  @BASEBOARD_FAB2_LIB.BASEBOARD_FAB2(SCH_1):PVCCIN_CPU1
    2  GND                B  @BASEBOARD_FAB2_LIB.BASEBOARD_FAB2(SCH_1):GND

CAP  I218  C7P20  [CAP_0805-47UF,4V,20%,X6S,C9533A]
    1  PVCCIN_CPU1        A  @BASEBOARD_FAB2_LIB.BASEBOARD_FAB2(SCH_1):PVCCIN_CPU1
    2  GND                B  @BASEBOARD_FAB2_LIB.BASEBOARD_FAB2(SCH_1):GND

CAP_A  I65  C7R1   [CAP_A_0603V-22.0UF,4V,20%,X6S,A]
    1  PVCCIO_CPU1        A  @BASEBOARD_FAB2_LIB.BASEBOARD_FAB2(SCH_1):PVCCIO_CPU1
    2  GND                B  @BASEBOARD_FAB2_LIB.BASEBOARD_FAB2(SCH_1):GND

CAP  I90  C7T1   [CAP_0805-100UF,4V,20%,X5R,6024A]
    1  PVDDQ_GHJ          A  @BASEBOARD_FAB2_LIB.BASEBOARD_FAB2(SCH_1):PVDDQ_GHJ
    2  GND                B  @BASEBOARD_FAB2_LIB.BASEBOARD_FAB2(SCH_1):GND

CAP  I112  C7T2   [CAP_0603LF-10UF,4V,20%,X6S,E15A]
    1  PVPP_GHJ           A  @BASEBOARD_FAB2_LIB.BASEBOARD_FAB2(SCH_1):PVPP_GHJ
    2  GND                B  @BASEBOARD_FAB2_LIB.BASEBOARD_FAB2(SCH_1):GND

CAP  I113  C7T3   [CAP_0603LF-10UF,4V,20%,X6S,E15A]
    1  PVPP_GHJ           A  @BASEBOARD_FAB2_LIB.BASEBOARD_FAB2(SCH_1):PVPP_GHJ
    2  GND                B  @BASEBOARD_FAB2_LIB.BASEBOARD_FAB2(SCH_1):GND

CAP_A  I235  C7T4   [CAP_A_0603V-22.0UF,4V,20%,X6S,A]
    1  PVDDQ_GHJ          A  @BASEBOARD_FAB2_LIB.BASEBOARD_FAB2(SCH_1):PVDDQ_GHJ
    2  GND                B  @BASEBOARD_FAB2_LIB.BASEBOARD_FAB2(SCH_1):GND

CAP_A  I234  C7T5   [CAP_A_0603V-22.0UF,4V,20%,X6S,A]
    1  PVDDQ_GHJ          A  @BASEBOARD_FAB2_LIB.BASEBOARD_FAB2(SCH_1):PVDDQ_GHJ
    2  GND                B  @BASEBOARD_FAB2_LIB.BASEBOARD_FAB2(SCH_1):GND

CAP_A  I237  C7U1   [CAP_A_0603V-22.0UF,4V,20%,X6S,A]
    1  PVDDQ_GHJ          A  @BASEBOARD_FAB2_LIB.BASEBOARD_FAB2(SCH_1):PVDDQ_GHJ
    2  GND                B  @BASEBOARD_FAB2_LIB.BASEBOARD_FAB2(SCH_1):GND

CAP_A  I238  C7U2   [CAP_A_0603V-22.0UF,4V,20%,X6S,A]
    1  PVDDQ_GHJ          A  @BASEBOARD_FAB2_LIB.BASEBOARD_FAB2(SCH_1):PVDDQ_GHJ
    2  GND                B  @BASEBOARD_FAB2_LIB.BASEBOARD_FAB2(SCH_1):GND

CAP  I136  C7U3   [CAP_0603LF-10UF,4V,20%,X6S,E15A]
    1  PVPP_GHJ           A  @BASEBOARD_FAB2_LIB.BASEBOARD_FAB2(SCH_1):PVPP_GHJ
    2  GND                B  @BASEBOARD_FAB2_LIB.BASEBOARD_FAB2(SCH_1):GND

CAP  I109  C7U4   [CAP_0603LF-10UF,4V,20%,X6S,E15A]
    1  PVPP_GHJ           A  @BASEBOARD_FAB2_LIB.BASEBOARD_FAB2(SCH_1):PVPP_GHJ
    2  GND                B  @BASEBOARD_FAB2_LIB.BASEBOARD_FAB2(SCH_1):GND

CAP  I111  C7U5   [CAP_0603LF-10UF,4V,20%,X6S,E15A]
    1  PVPP_GHJ           A  @BASEBOARD_FAB2_LIB.BASEBOARD_FAB2(SCH_1):PVPP_GHJ
    2  GND                B  @BASEBOARD_FAB2_LIB.BASEBOARD_FAB2(SCH_1):GND

CAP  I115  C7U6   [CAP_0603LF-10UF,4V,20%,X6S,E15A]
    1  PVPP_GHJ           A  @BASEBOARD_FAB2_LIB.BASEBOARD_FAB2(SCH_1):PVPP_GHJ
    2  GND                B  @BASEBOARD_FAB2_LIB.BASEBOARD_FAB2(SCH_1):GND

CAP  I91  C7U7   [CAP_0805-100UF,4V,20%,X5R,6024A]
    1  PVDDQ_GHJ          A  @BASEBOARD_FAB2_LIB.BASEBOARD_FAB2(SCH_1):PVDDQ_GHJ
    2  GND                B  @BASEBOARD_FAB2_LIB.BASEBOARD_FAB2(SCH_1):GND

CAP  I209  C8A2   [CAP_0402LF-220PF,50V,10%,X7R,AA]
    2  VSENSE_PVNN_PCH_STBY_AVSN      B  @BASEBOARD_FAB2_LIB.BASEBOARD_FAB2(SCH_1):VSENSE_PVNN_PCH_STBY_AVSN
    1  VR_PVNN_PCH_AVSP      A  @BASEBOARD_FAB2_LIB.BASEBOARD_FAB2(SCH_1):VR_PVNN_PCH_AVSP

CAP  I167  C8A3   [CAP_0402LF-1000PF,50V,10%,X7R,A]
    1  VR_PVNN_PCH_VINSEN      A  @BASEBOARD_FAB2_LIB.BASEBOARD_FAB2(SCH_1):VR_PVNN_PCH_VINSEN
    2  GND                B  @BASEBOARD_FAB2_LIB.BASEBOARD_FAB2(SCH_1):GND

CAP  I31  C8A4   [CAP_0603LF-0.1UF,25V,10%,X7R,6A]
    1  P3V3_STBY          A  @BASEBOARD_FAB2_LIB.BASEBOARD_FAB2(SCH_1):P3V3_STBY
    2  GND                B  @BASEBOARD_FAB2_LIB.BASEBOARD_FAB2(SCH_1):GND

CAP  I29  C8A6   [CAP_0603-10UF,6.3V,20%,X6S,E15A]
    1  P3V3_STBY          A  @BASEBOARD_FAB2_LIB.BASEBOARD_FAB2(SCH_1):P3V3_STBY
    2  GND                B  @BASEBOARD_FAB2_LIB.BASEBOARD_FAB2(SCH_1):GND

CAP_A  I143  C8A7   [CAP_A_0402V-1.0UF,6.3V,10%,X6SA]
    1  VR_PVNN_P1V05_PCH_VD12      A  @BASEBOARD_FAB2_LIB.BASEBOARD_FAB2(SCH_1):VR_PVNN_P1V05_PCH_VD12
    2  GND                B  @BASEBOARD_FAB2_LIB.BASEBOARD_FAB2(SCH_1):GND

CAP_A  I145  C8A8   [CAP_A_0402V-0.1UF,16V,10%,X7R,A]
    1  VR_PVNN_P1V05_PCH_VD12      A  @BASEBOARD_FAB2_LIB.BASEBOARD_FAB2(SCH_1):VR_PVNN_P1V05_PCH_VD12
    2  GND                B  @BASEBOARD_FAB2_LIB.BASEBOARD_FAB2(SCH_1):GND

CAP  I218  C8A9   [CAP_0402LF-1000PF,50V,10%,X7R,A]
    1  PWRGD_PVNN_PCH_R      A  @BASEBOARD_FAB2_LIB.BASEBOARD_FAB2(SCH_1):PWRGD_PVNN_PCH_R
    2  GND                B  @BASEBOARD_FAB2_LIB.BASEBOARD_FAB2(SCH_1):GND

CAP  I55  C8A10  [CAP_0402LF-1000PF,50V,10%,EMPTA]
    1  PWRGD_P3V3_STBY      A  @BASEBOARD_FAB2_LIB.BASEBOARD_FAB2(SCH_1):PWRGD_P3V3_STBY
    2  GND                B  @BASEBOARD_FAB2_LIB.BASEBOARD_FAB2(SCH_1):GND

CAP  I5   C8A11  [CAP_0402LF-1000PF,50V,10%,X7R,A]
    1  PWRGD_P1V8_PCH_STBY_R      A  @BASEBOARD_FAB2_LIB.BASEBOARD_FAB2(SCH_1):PWRGD_P1V8_PCH_STBY_R
    2  GND                B  @BASEBOARD_FAB2_LIB.BASEBOARD_FAB2(SCH_1):GND

CAP  I77  C8A12  [CAP_0805-47UF,4V,20%,X6S,C9533A]
    1  P1V8_PCH_STBY      A  @BASEBOARD_FAB2_LIB.BASEBOARD_FAB2(SCH_1):P1V8_PCH_STBY
    2  GND                B  @BASEBOARD_FAB2_LIB.BASEBOARD_FAB2(SCH_1):GND

CAP  I37  C8A13  [CAP_0805-47UF,4V,20%,X6S,C9533A]
    1  P1V05_PCH_STBY      A  @BASEBOARD_FAB2_LIB.BASEBOARD_FAB2(SCH_1):P1V05_PCH_STBY
    2  GND                B  @BASEBOARD_FAB2_LIB.BASEBOARD_FAB2(SCH_1):GND

CAP  I13  C8A14  [CAP_0805-22UF,6.3V,20%,X6S,C95A]
    1  P1V8_PCH_STBY      A  @BASEBOARD_FAB2_LIB.BASEBOARD_FAB2(SCH_1):P1V8_PCH_STBY
    2  GND                B  @BASEBOARD_FAB2_LIB.BASEBOARD_FAB2(SCH_1):GND

CAPP  I78  C8A15  [CAPP_SM-470UF,2V,20%,ALUM,6990A]
    1  P1V05_PCH_STBY      A  @BASEBOARD_FAB2_LIB.BASEBOARD_FAB2(SCH_1):P1V05_PCH_STBY
    2  GND                B  @BASEBOARD_FAB2_LIB.BASEBOARD_FAB2(SCH_1):GND

CAP_A  I41  C8B1   [CAP_A_0603V-22.0UF,4V,20%,X6S,A]
    1  P1V8_PCH_STBY      A  @BASEBOARD_FAB2_LIB.BASEBOARD_FAB2(SCH_1):P1V8_PCH_STBY
    2  GND                B  @BASEBOARD_FAB2_LIB.BASEBOARD_FAB2(SCH_1):GND

CAP_A  I30  C8B2   [CAP_A_0603V-22.0UF,4V,20%,X6S,A]
    1  P1V8_PCH_STBY      A  @BASEBOARD_FAB2_LIB.BASEBOARD_FAB2(SCH_1):P1V8_PCH_STBY
    2  GND                B  @BASEBOARD_FAB2_LIB.BASEBOARD_FAB2(SCH_1):GND

CAP_A  I32  C8B3   [CAP_A_0603V-22.0UF,4V,20%,X6S,A]
    1  P1V8_PCH_STBY      A  @BASEBOARD_FAB2_LIB.BASEBOARD_FAB2(SCH_1):P1V8_PCH_STBY
    2  GND                B  @BASEBOARD_FAB2_LIB.BASEBOARD_FAB2(SCH_1):GND

CAP_A  I39  C8B4   [CAP_A_0603V-22.0UF,4V,20%,X6S,A]
    1  P1V8_PCH_STBY      A  @BASEBOARD_FAB2_LIB.BASEBOARD_FAB2(SCH_1):P1V8_PCH_STBY
    2  GND                B  @BASEBOARD_FAB2_LIB.BASEBOARD_FAB2(SCH_1):GND

CAP_A  I37  C8B5   [CAP_A_0402V-0.1UF,16V,10%,X7R,A]
    1  P5V_STBY           A  @BASEBOARD_FAB2_LIB.BASEBOARD_FAB2(SCH_1):P5V_STBY
    2  GND                B  @BASEBOARD_FAB2_LIB.BASEBOARD_FAB2(SCH_1):GND

CAP  I40  C8B6   [CAP_0805-10UF,16V,10%,X6S,C953A]
    1  P5V                A  @BASEBOARD_FAB2_LIB.BASEBOARD_FAB2(SCH_1):P5V
    2  GND                B  @BASEBOARD_FAB2_LIB.BASEBOARD_FAB2(SCH_1):GND

CAP_A  I41  C8B7   [CAP_A_0402V-0.1UF,16V,10%,X7R,A]
    1  P5V                A  @BASEBOARD_FAB2_LIB.BASEBOARD_FAB2(SCH_1):P5V
    2  GND                B  @BASEBOARD_FAB2_LIB.BASEBOARD_FAB2(SCH_1):GND

CAP_A  I26  C8B8   [CAP_A_0402V-0.1UF,16V,10%,X7R,A]
    1  P5V_STBY           A  @BASEBOARD_FAB2_LIB.BASEBOARD_FAB2(SCH_1):P5V_STBY
    2  GND                B  @BASEBOARD_FAB2_LIB.BASEBOARD_FAB2(SCH_1):GND

CAP_A  I14  C8B9   [CAP_A_0603V-22.0UF,4V,20%,X6S,A]
    1  P1V05_PCH_STBY      A  @BASEBOARD_FAB2_LIB.BASEBOARD_FAB2(SCH_1):P1V05_PCH_STBY
    2  GND                B  @BASEBOARD_FAB2_LIB.BASEBOARD_FAB2(SCH_1):GND

CAP_A  I8   C8B10  [CAP_A_0603V-22.0UF,4V,20%,X6S,A]
    1  P1V05_PCH_STBY      A  @BASEBOARD_FAB2_LIB.BASEBOARD_FAB2(SCH_1):P1V05_PCH_STBY
    2  GND                B  @BASEBOARD_FAB2_LIB.BASEBOARD_FAB2(SCH_1):GND

CAP_A  I15  C8B11  [CAP_A_0603V-22.0UF,4V,20%,X6S,A]
    1  P1V05_PCH_STBY      A  @BASEBOARD_FAB2_LIB.BASEBOARD_FAB2(SCH_1):P1V05_PCH_STBY
    2  GND                B  @BASEBOARD_FAB2_LIB.BASEBOARD_FAB2(SCH_1):GND

CAP  I38  C8B12  [CAP_0805-10UF,16V,10%,X6S,C953A]
    1  P5V_STBY           A  @BASEBOARD_FAB2_LIB.BASEBOARD_FAB2(SCH_1):P5V_STBY
    2  GND                B  @BASEBOARD_FAB2_LIB.BASEBOARD_FAB2(SCH_1):GND

CAP_A  I20  C8B13  [CAP_A_0603V-22.0UF,4V,20%,X6S,A]
    1  P1V05_PCH_STBY      A  @BASEBOARD_FAB2_LIB.BASEBOARD_FAB2(SCH_1):P1V05_PCH_STBY
    2  GND                B  @BASEBOARD_FAB2_LIB.BASEBOARD_FAB2(SCH_1):GND

CAP_A  I16  C8B14  [CAP_A_0603V-22.0UF,4V,20%,X6S,A]
    1  P1V05_PCH_STBY      A  @BASEBOARD_FAB2_LIB.BASEBOARD_FAB2(SCH_1):P1V05_PCH_STBY
    2  GND                B  @BASEBOARD_FAB2_LIB.BASEBOARD_FAB2(SCH_1):GND

CAP  I24  C8B15  [CAP_0805-47UF,4V,20%,X6S,C9533A]
    1  P1V05_PCH_STBY      A  @BASEBOARD_FAB2_LIB.BASEBOARD_FAB2(SCH_1):P1V05_PCH_STBY
    2  GND                B  @BASEBOARD_FAB2_LIB.BASEBOARD_FAB2(SCH_1):GND

CAP  I22  C8B16  [CAP_0805-47UF,4V,20%,X6S,C9533A]
    1  P1V05_PCH_STBY      A  @BASEBOARD_FAB2_LIB.BASEBOARD_FAB2(SCH_1):P1V05_PCH_STBY
    2  GND                B  @BASEBOARD_FAB2_LIB.BASEBOARD_FAB2(SCH_1):GND

CAP  I79  C8C1   [CAP_0402LF-33.0PF,50V,5%,COG,AA]
    1  XTAL_KR_25M_IN      A  @BASEBOARD_FAB2_LIB.BASEBOARD_FAB2(SCH_1):XTAL_KR_25M_IN
    2  GND                B  @BASEBOARD_FAB2_LIB.BASEBOARD_FAB2(SCH_1):GND

CAP  I77  C8C2   [CAP_0402LF-33.0PF,50V,5%,COG,AA]
    1  XTAL_KR_25M_OUT      A  @BASEBOARD_FAB2_LIB.BASEBOARD_FAB2(SCH_1):XTAL_KR_25M_OUT
    2  GND                B  @BASEBOARD_FAB2_LIB.BASEBOARD_FAB2(SCH_1):GND

CAP  I19  C8C3   [CAP_0603-10UF,6.3V,20%,X6S,E15A]
    1  P3V3_STBY          A  @BASEBOARD_FAB2_LIB.BASEBOARD_FAB2(SCH_1):P3V3_STBY
    2  GND                B  @BASEBOARD_FAB2_LIB.BASEBOARD_FAB2(SCH_1):GND

CAP  I20  C8C4   [CAP_0603-10UF,6.3V,20%,X6S,E15A]
    1  P3V3_STBY          A  @BASEBOARD_FAB2_LIB.BASEBOARD_FAB2(SCH_1):P3V3_STBY
    2  GND                B  @BASEBOARD_FAB2_LIB.BASEBOARD_FAB2(SCH_1):GND

CAP  I21  C8C5   [CAP_0603-10UF,6.3V,20%,X6S,E15A]
    1  P3V3_STBY          A  @BASEBOARD_FAB2_LIB.BASEBOARD_FAB2(SCH_1):P3V3_STBY
    2  GND                B  @BASEBOARD_FAB2_LIB.BASEBOARD_FAB2(SCH_1):GND

CAP  I22  C8C6   [CAP_0603-10UF,6.3V,20%,X6S,E15A]
    1  P3V3_STBY          A  @BASEBOARD_FAB2_LIB.BASEBOARD_FAB2(SCH_1):P3V3_STBY
    2  GND                B  @BASEBOARD_FAB2_LIB.BASEBOARD_FAB2(SCH_1):GND

CAP_A  I64  C8C8   [CAP_A_0402V-0.1UF,16V,10%,X7R,A]
    1  KR_P3_OCP_RX_DP      A  @BASEBOARD_FAB2_LIB.BASEBOARD_FAB2(SCH_1):KR_P3_OCP_RX_DP
    2  KR_P3_OCP_RX_C_DP      B  @BASEBOARD_FAB2_LIB.BASEBOARD_FAB2(SCH_1):KR_P3_OCP_RX_C_DP

CAP_A  I68  C8C9   [CAP_A_0402V-0.1UF,16V,10%,X7R,A]
    1  KR_P3_OCP_RX_DN      A  @BASEBOARD_FAB2_LIB.BASEBOARD_FAB2(SCH_1):KR_P3_OCP_RX_DN
    2  KR_P3_OCP_RX_C_DN      B  @BASEBOARD_FAB2_LIB.BASEBOARD_FAB2(SCH_1):KR_P3_OCP_RX_C_DN

CAP_A  I73  C8C10  [CAP_A_0402V-0.1UF,16V,10%,X7R,A]
    1  KR_P2_OCP_RX_DN      A  @BASEBOARD_FAB2_LIB.BASEBOARD_FAB2(SCH_1):KR_P2_OCP_RX_DN
    2  KR_P2_OCP_RX_C_DN      B  @BASEBOARD_FAB2_LIB.BASEBOARD_FAB2(SCH_1):KR_P2_OCP_RX_C_DN

CAP_A  I72  C8C11  [CAP_A_0402V-0.1UF,16V,10%,X7R,A]
    1  KR_P2_OCP_RX_DP      A  @BASEBOARD_FAB2_LIB.BASEBOARD_FAB2(SCH_1):KR_P2_OCP_RX_DP
    2  KR_P2_OCP_RX_C_DP      B  @BASEBOARD_FAB2_LIB.BASEBOARD_FAB2(SCH_1):KR_P2_OCP_RX_C_DP

CAP_A  I80  C8C12  [CAP_A_0402V-0.1UF,16V,10%,X7R,A]
    1  KR_P1_OCP_RX_DP      A  @BASEBOARD_FAB2_LIB.BASEBOARD_FAB2(SCH_1):KR_P1_OCP_RX_DP
    2  KR_P1_OCP_RX_C_DP      B  @BASEBOARD_FAB2_LIB.BASEBOARD_FAB2(SCH_1):KR_P1_OCP_RX_C_DP

CAP_A  I81  C8C13  [CAP_A_0402V-0.1UF,16V,10%,X7R,A]
    1  KR_P1_OCP_RX_DN      A  @BASEBOARD_FAB2_LIB.BASEBOARD_FAB2(SCH_1):KR_P1_OCP_RX_DN
    2  KR_P1_OCP_RX_C_DN      B  @BASEBOARD_FAB2_LIB.BASEBOARD_FAB2(SCH_1):KR_P1_OCP_RX_C_DN

CAP_A  I86  C8C14  [CAP_A_0402V-0.1UF,16V,10%,X7R,A]
    1  KR_P0_OCP_RX_DN      A  @BASEBOARD_FAB2_LIB.BASEBOARD_FAB2(SCH_1):KR_P0_OCP_RX_DN
    2  KR_P0_OCP_RX_C_DN      B  @BASEBOARD_FAB2_LIB.BASEBOARD_FAB2(SCH_1):KR_P0_OCP_RX_C_DN

CAP_A  I82  C8C15  [CAP_A_0402V-0.1UF,16V,10%,X7R,A]
    1  KR_P0_OCP_RX_DP      A  @BASEBOARD_FAB2_LIB.BASEBOARD_FAB2(SCH_1):KR_P0_OCP_RX_DP
    2  KR_P0_OCP_RX_C_DP      B  @BASEBOARD_FAB2_LIB.BASEBOARD_FAB2(SCH_1):KR_P0_OCP_RX_C_DP

CAP_A  I376  C8D1   [CAP_A_0402V-0.1UF,16V,10%,X7R,A]
    1  P3V3_STBY          A  @BASEBOARD_FAB2_LIB.BASEBOARD_FAB2(SCH_1):P3V3_STBY
    2  GND                B  @BASEBOARD_FAB2_LIB.BASEBOARD_FAB2(SCH_1):GND

CAP_A  I33  C8D2   [CAP_A_0402V-0.1UF,16V,10%,X7R,A]
    1  P3V3_STBY          A  @BASEBOARD_FAB2_LIB.BASEBOARD_FAB2(SCH_1):P3V3_STBY
    2  GND                B  @BASEBOARD_FAB2_LIB.BASEBOARD_FAB2(SCH_1):GND

CAP  I42  C8D3   [CAP_0402LF-470PF,50V,10%,EMPTYA]
    1  IRQ_SML1_PMBUS_ALERT_N      A  @BASEBOARD_FAB2_LIB.BASEBOARD_FAB2(SCH_1):IRQ_SML1_PMBUS_ALERT_N
    2  GND                B  @BASEBOARD_FAB2_LIB.BASEBOARD_FAB2(SCH_1):GND

CAP_A  I105  C8D4   [CAP_A_0402V-0.1UF,16V,10%,X7R,A]
    1  P3V3_STBY          A  @BASEBOARD_FAB2_LIB.BASEBOARD_FAB2(SCH_1):P3V3_STBY
    2  GND                B  @BASEBOARD_FAB2_LIB.BASEBOARD_FAB2(SCH_1):GND

CAP_A  I253  C8E1   [CAP_A_0402V-0.1UF,16V,10%,X7R,A]
    1  P3V3_STBY          A  @BASEBOARD_FAB2_LIB.BASEBOARD_FAB2(SCH_1):P3V3_STBY
    2  GND                B  @BASEBOARD_FAB2_LIB.BASEBOARD_FAB2(SCH_1):GND

CAP_A  I40  C8E2   [CAP_A_0402V-0.1UF,16V,10%,X7R,A]
    1  P3V3_STBY          A  @BASEBOARD_FAB2_LIB.BASEBOARD_FAB2(SCH_1):P3V3_STBY
    2  GND                B  @BASEBOARD_FAB2_LIB.BASEBOARD_FAB2(SCH_1):GND

CAP_A  I94  C8E3   [CAP_A_0402V-0.1UF,16V,10%,X7R,A]
    1  PWRGD_P12V_HSC      A  @BASEBOARD_FAB2_LIB.BASEBOARD_FAB2(SCH_1):PWRGD_P12V_HSC
    2  GND                B  @BASEBOARD_FAB2_LIB.BASEBOARD_FAB2(SCH_1):GND

CAPP  I8   C8E4   [CAPP_3018-470UF,6.3V,20%,POSCAA]
    1  P5V_STBY           A  @BASEBOARD_FAB2_LIB.BASEBOARD_FAB2(SCH_1):P5V_STBY
    2  GND                B  @BASEBOARD_FAB2_LIB.BASEBOARD_FAB2(SCH_1):GND

CAP_A  I20  C8E5   [CAP_A_0402V-0.1UF,16V,10%,X7R,A]
    1  P3V3_STBY          A  @BASEBOARD_FAB2_LIB.BASEBOARD_FAB2(SCH_1):P3V3_STBY
    2  GND                B  @BASEBOARD_FAB2_LIB.BASEBOARD_FAB2(SCH_1):GND

CAP  I12  C8E6   [CAP_0603LF-0.1UF,25V,10%,X7R,6A]
    2  VR_P5V_STBY_PHASE      B  @BASEBOARD_FAB2_LIB.BASEBOARD_FAB2(SCH_1):VR_P5V_STBY_PHASE
    1  VR_P5V_STBY_BOOT      A  @BASEBOARD_FAB2_LIB.BASEBOARD_FAB2(SCH_1):VR_P5V_STBY_BOOT

CAP  I3   C8E7   [CAP_0805-22UF,6.3V,20%,X6S,C95A]
    1  P5V_STBY           A  @BASEBOARD_FAB2_LIB.BASEBOARD_FAB2(SCH_1):P5V_STBY
    2  GND                B  @BASEBOARD_FAB2_LIB.BASEBOARD_FAB2(SCH_1):GND

CAP_A  I128  C8E8   [CAP_A_0402V-0.1UF,16V,10%,X7R,A]
    1  P3V3_STBY          A  @BASEBOARD_FAB2_LIB.BASEBOARD_FAB2(SCH_1):P3V3_STBY
    2  GND                B  @BASEBOARD_FAB2_LIB.BASEBOARD_FAB2(SCH_1):GND

CAP  I2   C8E9   [CAP_0805-22UF,6.3V,20%,X6S,C95A]
    1  P5V_STBY           A  @BASEBOARD_FAB2_LIB.BASEBOARD_FAB2(SCH_1):P5V_STBY
    2  GND                B  @BASEBOARD_FAB2_LIB.BASEBOARD_FAB2(SCH_1):GND

CAP  I137  C8E10  [CAP_1206LF-22UF,16V,10%,X6S,D3A]
    1  VR_FET_SW_P12V_STBY_P3V3_STBY      A  @BASEBOARD_FAB2_LIB.BASEBOARD_FAB2(SCH_1):VR_FET_SW_P12V_STBY_P3V3_STBY
    2  GND                B  @BASEBOARD_FAB2_LIB.BASEBOARD_FAB2(SCH_1):GND

CAP  I135  C8E11  [CAP_1210-47UF,16V,20%,X6S,D384A]
    1  VR_FET_SW_P12V_STBY_P3V3_STBY      A  @BASEBOARD_FAB2_LIB.BASEBOARD_FAB2(SCH_1):VR_FET_SW_P12V_STBY_P3V3_STBY
    2  GND                B  @BASEBOARD_FAB2_LIB.BASEBOARD_FAB2(SCH_1):GND

CAP  I129  C8E12  [CAP_0603LF-0.1UF,25V,10%,X7R,6A]
    1  VR_P3V3_STBY_PHASE      A  @BASEBOARD_FAB2_LIB.BASEBOARD_FAB2(SCH_1):VR_P3V3_STBY_PHASE
    2  VR_P3V3_STBY_BOOT_R      B  @BASEBOARD_FAB2_LIB.BASEBOARD_FAB2(SCH_1):VR_P3V3_STBY_BOOT_R

CAP  I41  C8E13  [CAP_0402LF-1000PF,50V,10%,EMPTA]
    1  PWRGD_P12V_HSC_DLY      A  @BASEBOARD_FAB2_LIB.BASEBOARD_FAB2(SCH_1):PWRGD_P12V_HSC_DLY
    2  AGND_P5V_STBY      B  @BASEBOARD_FAB2_LIB.BASEBOARD_FAB2(SCH_1):AGND_P5V_STBY

CAP_0402  I139  C8E14  [CAP_0402-1.0UF,16V,10%,X6S,D97A]
    1  VR_FET_SW_P12V_STBY_P3V3_STBY      A  @BASEBOARD_FAB2_LIB.BASEBOARD_FAB2(SCH_1):VR_FET_SW_P12V_STBY_P3V3_STBY
    2  GND                B  @BASEBOARD_FAB2_LIB.BASEBOARD_FAB2(SCH_1):GND

CAP  I63  C8E15  [CAP_0402LF-0.022UF,16V,10%,X7RA]
    1  VR_P5V_STBY_SS      A  @BASEBOARD_FAB2_LIB.BASEBOARD_FAB2(SCH_1):VR_P5V_STBY_SS
    2  AGND_P5V_STBY      B  @BASEBOARD_FAB2_LIB.BASEBOARD_FAB2(SCH_1):AGND_P5V_STBY

CAP  I53  C8E16  [CAP_0402LF-270PF,50V,10%,X7R,AA]
    1  VR_P5V_STBY_COMP      A  @BASEBOARD_FAB2_LIB.BASEBOARD_FAB2(SCH_1):VR_P5V_STBY_COMP
    2  AGND_P5V_STBY      B  @BASEBOARD_FAB2_LIB.BASEBOARD_FAB2(SCH_1):AGND_P5V_STBY

CAP  I113  C8E17  [CAP_0402LF-1000PF,50V,10%,EMPTA]
    1  PWRGD_P5V_STBY      A  @BASEBOARD_FAB2_LIB.BASEBOARD_FAB2(SCH_1):PWRGD_P5V_STBY
    2  AGND_P3V3_STBY      B  @BASEBOARD_FAB2_LIB.BASEBOARD_FAB2(SCH_1):AGND_P3V3_STBY

CAP_A  I14  C8E18  [CAP_A_0402V-0.1UF,16V,10%,X7R,A]
    1  P3V3_STBY          A  @BASEBOARD_FAB2_LIB.BASEBOARD_FAB2(SCH_1):P3V3_STBY
    2  GND                B  @BASEBOARD_FAB2_LIB.BASEBOARD_FAB2(SCH_1):GND

CAP_A  I28  C8E19  [CAP_A_0402V-0.1UF,16V,10%,X7R,A]
    1  P5V_STBY           A  @BASEBOARD_FAB2_LIB.BASEBOARD_FAB2(SCH_1):P5V_STBY
    2  GND                B  @BASEBOARD_FAB2_LIB.BASEBOARD_FAB2(SCH_1):GND

CAP  I57  C8F1   [CAP_0402LF-2200PF,50V,10%,X7R,A]
    1  VR_P5V_STBY_RC_COMP      A  @BASEBOARD_FAB2_LIB.BASEBOARD_FAB2(SCH_1):VR_P5V_STBY_RC_COMP
    2  AGND_P5V_STBY      B  @BASEBOARD_FAB2_LIB.BASEBOARD_FAB2(SCH_1):AGND_P5V_STBY

CAP  I116  C8F2   [CAP_0402LF-1000PF,50V,10%,X7R,A]
    1  PWRGD_P3V3_STBY_R      A  @BASEBOARD_FAB2_LIB.BASEBOARD_FAB2(SCH_1):PWRGD_P3V3_STBY_R
    2  GND                B  @BASEBOARD_FAB2_LIB.BASEBOARD_FAB2(SCH_1):GND

CAP  I163  C8F3   [CAP_0402LF-3300PF,50V,10%,EMPTA]
    2  VR_P3V3_STBY_SNUB      B  @BASEBOARD_FAB2_LIB.BASEBOARD_FAB2(SCH_1):VR_P3V3_STBY_SNUB
    1  VR_P3V3_STBY_PHASE      A  @BASEBOARD_FAB2_LIB.BASEBOARD_FAB2(SCH_1):VR_P3V3_STBY_PHASE

CAP_A  I30  C8F4   [CAP_A_0402V-1.0UF,6.3V,10%,X6SA]
    1  P3V3_STBY          A  @BASEBOARD_FAB2_LIB.BASEBOARD_FAB2(SCH_1):P3V3_STBY
    2  GND                B  @BASEBOARD_FAB2_LIB.BASEBOARD_FAB2(SCH_1):GND

CAP_A  I28  C8F5   [CAP_A_0402V-0.01UF,25V,10%,X7RA]
    1  P3V3_STBY          A  @BASEBOARD_FAB2_LIB.BASEBOARD_FAB2(SCH_1):P3V3_STBY
    2  GND                B  @BASEBOARD_FAB2_LIB.BASEBOARD_FAB2(SCH_1):GND

CAP_A  I95  C8F6   [CAP_A_0402V-0.01UF,25V,10%,EMPA]
    1  SATA6G_S0_TX_DP      A  @BASEBOARD_FAB2_LIB.BASEBOARD_FAB2(SCH_1):SATA6G_S0_TX_DP
    2  P3E_PCH_M2_SATA6G_TX_R_DP      B  @BASEBOARD_FAB2_LIB.BASEBOARD_FAB2(SCH_1):P3E_PCH_M2_SATA6G_TX_R_DP

CAP_0402  I96  C8F7   [CAP_0402-0.22UF,16V,10%,X7R,A3A]
    1  P3E_PCH_TX_0_DP      A  @BASEBOARD_FAB2_LIB.BASEBOARD_FAB2(SCH_1):P3E_PCH_TX_0_DP
    2  P3E_PCH_M2_SATA6G_TX_R_DP      B  @BASEBOARD_FAB2_LIB.BASEBOARD_FAB2(SCH_1):P3E_PCH_M2_SATA6G_TX_R_DP

CAPP  I155  C8F8   [CAPP_3018-470UF,6.3V,20%,POSCAA]
    1  P3V3_STBY          A  @BASEBOARD_FAB2_LIB.BASEBOARD_FAB2(SCH_1):P3V3_STBY
    2  GND                B  @BASEBOARD_FAB2_LIB.BASEBOARD_FAB2(SCH_1):GND

CAP_A  I161  C8F9   [CAP_A_0402V-1.0UF,6.3V,10%,EMPA]
    1  P1V8_BMC_STBY_PCIEA      A  @BASEBOARD_FAB2_LIB.BASEBOARD_FAB2(SCH_1):P1V8_BMC_STBY_PCIEA
    2  GND                B  @BASEBOARD_FAB2_LIB.BASEBOARD_FAB2(SCH_1):GND

CAP  I159  C8F10  [CAP_0603-10UF,6.3V,20%,EMPTY,EA]
    1  P1V8_BMC_STBY_PCIEA      A  @BASEBOARD_FAB2_LIB.BASEBOARD_FAB2(SCH_1):P1V8_BMC_STBY_PCIEA
    2  GND                B  @BASEBOARD_FAB2_LIB.BASEBOARD_FAB2(SCH_1):GND

CAP_A  I97  C8F11  [CAP_A_0402V-0.01UF,25V,10%,EMPA]
    1  SATA6G_S0_TX_DN      A  @BASEBOARD_FAB2_LIB.BASEBOARD_FAB2(SCH_1):SATA6G_S0_TX_DN
    2  P3E_PCH_M2_SATA6G_TX_R_DN      B  @BASEBOARD_FAB2_LIB.BASEBOARD_FAB2(SCH_1):P3E_PCH_M2_SATA6G_TX_R_DN

CAP_0402  I98  C8F12  [CAP_0402-0.22UF,16V,10%,X7R,A3A]
    1  P3E_PCH_TX_0_DN      A  @BASEBOARD_FAB2_LIB.BASEBOARD_FAB2(SCH_1):P3E_PCH_TX_0_DN
    2  P3E_PCH_M2_SATA6G_TX_R_DN      B  @BASEBOARD_FAB2_LIB.BASEBOARD_FAB2(SCH_1):P3E_PCH_M2_SATA6G_TX_R_DN

CAP_A  I99  C8F13  [CAP_A_0402V-0.01UF,25V,10%,EMPA]
    1  SATA6G_S0_RX_DP      A  @BASEBOARD_FAB2_LIB.BASEBOARD_FAB2(SCH_1):SATA6G_S0_RX_DP
    2  P3E_PCH_M2_SATA6G_RX_R_DP      B  @BASEBOARD_FAB2_LIB.BASEBOARD_FAB2(SCH_1):P3E_PCH_M2_SATA6G_RX_R_DP

CAPP  I154  C8F14  [CAPP_3018-470UF,6.3V,20%,POSCAA]
    1  P3V3_STBY          A  @BASEBOARD_FAB2_LIB.BASEBOARD_FAB2(SCH_1):P3V3_STBY
    2  GND                B  @BASEBOARD_FAB2_LIB.BASEBOARD_FAB2(SCH_1):GND

CAP_A  I90  C8F15  [CAP_A_0402V-0.01UF,25V,10%,EMPA]
    1  SATA6G_S0_RX_DN      A  @BASEBOARD_FAB2_LIB.BASEBOARD_FAB2(SCH_1):SATA6G_S0_RX_DN
    2  P3E_PCH_M2_SATA6G_RX_R_DN      B  @BASEBOARD_FAB2_LIB.BASEBOARD_FAB2(SCH_1):P3E_PCH_M2_SATA6G_RX_R_DN

CAP_A  I275  C8F16  [CAP_A_0402V-0.1UF,16V,10%,X7R,A]
    1  P3V3_STBY          A  @BASEBOARD_FAB2_LIB.BASEBOARD_FAB2(SCH_1):P3V3_STBY
    2  GND                B  @BASEBOARD_FAB2_LIB.BASEBOARD_FAB2(SCH_1):GND

CAP_A  I24  C8F17  [CAP_A_0402V-0.1UF,16V,10%,X7R,A]
    1  P5V_STBY           A  @BASEBOARD_FAB2_LIB.BASEBOARD_FAB2(SCH_1):P5V_STBY
    2  GND                B  @BASEBOARD_FAB2_LIB.BASEBOARD_FAB2(SCH_1):GND

CAP  I49  C8F18  [CAP_0402LF-27.0PF,50V,5%,COG,AA]
    1  XTAL_CK_MNG_IN      A  @BASEBOARD_FAB2_LIB.BASEBOARD_FAB2(SCH_1):XTAL_CK_MNG_IN
    2  GND                B  @BASEBOARD_FAB2_LIB.BASEBOARD_FAB2(SCH_1):GND

CAP  I53  C8F19  [CAP_0402LF-27.0PF,50V,5%,COG,AA]
    1  XTAL_CK_MNG_OUT      A  @BASEBOARD_FAB2_LIB.BASEBOARD_FAB2(SCH_1):XTAL_CK_MNG_OUT
    2  GND                B  @BASEBOARD_FAB2_LIB.BASEBOARD_FAB2(SCH_1):GND

CAP_0402  I70  C8G1   [CAP_0402-0.22UF,16V,10%,X7R,A3A]
    1  P3E_CPU0_PE2_SS_TXP<4>      A  @BASEBOARD_FAB2_LIB.BASEBOARD_FAB2(SCH_1):P3E_CPU0_PE2_SS_TXP<4>
    2  P3E_CPU0_PE2_SS_C_TXP<4>      B  @BASEBOARD_FAB2_LIB.BASEBOARD_FAB2(SCH_1):P3E_CPU0_PE2_SS_C_TXP<4>

CAP_0402  I58  C8G2   [CAP_0402-0.22UF,16V,10%,X7R,A3A]
    1  P3E_CPU0_PE2_SS_TXN<4>      A  @BASEBOARD_FAB2_LIB.BASEBOARD_FAB2(SCH_1):P3E_CPU0_PE2_SS_TXN<4>
    2  P3E_CPU0_PE2_SS_C_TXN<4>      B  @BASEBOARD_FAB2_LIB.BASEBOARD_FAB2(SCH_1):P3E_CPU0_PE2_SS_C_TXN<4>

CAP_0402  I71  C8G3   [CAP_0402-0.22UF,16V,10%,X7R,A3A]
    1  P3E_CPU0_PE2_SS_TXP<3>      A  @BASEBOARD_FAB2_LIB.BASEBOARD_FAB2(SCH_1):P3E_CPU0_PE2_SS_TXP<3>
    2  P3E_CPU0_PE2_SS_C_TXP<3>      B  @BASEBOARD_FAB2_LIB.BASEBOARD_FAB2(SCH_1):P3E_CPU0_PE2_SS_C_TXP<3>

CAP_0402  I56  C8G4   [CAP_0402-0.22UF,16V,10%,X7R,A3A]
    1  P3E_CPU0_PE2_SS_TXN<3>      A  @BASEBOARD_FAB2_LIB.BASEBOARD_FAB2(SCH_1):P3E_CPU0_PE2_SS_TXN<3>
    2  P3E_CPU0_PE2_SS_C_TXN<3>      B  @BASEBOARD_FAB2_LIB.BASEBOARD_FAB2(SCH_1):P3E_CPU0_PE2_SS_C_TXN<3>

CAP_0402  I75  C8G5   [CAP_0402-0.22UF,16V,10%,X7R,A3A]
    1  P3E_CPU0_PE2_SS_TXP<2>      A  @BASEBOARD_FAB2_LIB.BASEBOARD_FAB2(SCH_1):P3E_CPU0_PE2_SS_TXP<2>
    2  P3E_CPU0_PE2_SS_C_TXP<2>      B  @BASEBOARD_FAB2_LIB.BASEBOARD_FAB2(SCH_1):P3E_CPU0_PE2_SS_C_TXP<2>

CAP_0402  I61  C8G6   [CAP_0402-0.22UF,16V,10%,X7R,A3A]
    1  P3E_CPU0_PE2_SS_TXN<2>      A  @BASEBOARD_FAB2_LIB.BASEBOARD_FAB2(SCH_1):P3E_CPU0_PE2_SS_TXN<2>
    2  P3E_CPU0_PE2_SS_C_TXN<2>      B  @BASEBOARD_FAB2_LIB.BASEBOARD_FAB2(SCH_1):P3E_CPU0_PE2_SS_C_TXN<2>

CAP_0402  I62  C8G7   [CAP_0402-0.22UF,16V,10%,X7R,A3A]
    1  P3E_CPU0_PE2_SS_TXN<1>      A  @BASEBOARD_FAB2_LIB.BASEBOARD_FAB2(SCH_1):P3E_CPU0_PE2_SS_TXN<1>
    2  P3E_CPU0_PE2_SS_C_TXN<1>      B  @BASEBOARD_FAB2_LIB.BASEBOARD_FAB2(SCH_1):P3E_CPU0_PE2_SS_C_TXN<1>

CAP_0402  I76  C8G8   [CAP_0402-0.22UF,16V,10%,X7R,A3A]
    1  P3E_CPU0_PE2_SS_TXP<1>      A  @BASEBOARD_FAB2_LIB.BASEBOARD_FAB2(SCH_1):P3E_CPU0_PE2_SS_TXP<1>
    2  P3E_CPU0_PE2_SS_C_TXP<1>      B  @BASEBOARD_FAB2_LIB.BASEBOARD_FAB2(SCH_1):P3E_CPU0_PE2_SS_C_TXP<1>

CAP_0402  I93  C8G9   [CAP_0402-0.22UF,16V,10%,X7R,A3A]
    1  P3E_CPU0_PE2_SS_TXP<0>      A  @BASEBOARD_FAB2_LIB.BASEBOARD_FAB2(SCH_1):P3E_CPU0_PE2_SS_TXP<0>
    2  P3E_CPU0_PE2_SS_C_TXP<0>      B  @BASEBOARD_FAB2_LIB.BASEBOARD_FAB2(SCH_1):P3E_CPU0_PE2_SS_C_TXP<0>

CAP_0402  I96  C8G10  [CAP_0402-0.22UF,16V,10%,X7R,A3A]
    1  P3E_CPU0_PE2_SS_TXN<0>      A  @BASEBOARD_FAB2_LIB.BASEBOARD_FAB2(SCH_1):P3E_CPU0_PE2_SS_TXN<0>
    2  P3E_CPU0_PE2_SS_C_TXN<0>      B  @BASEBOARD_FAB2_LIB.BASEBOARD_FAB2(SCH_1):P3E_CPU0_PE2_SS_C_TXN<0>

CAP  I110  C8L1   [CAP_0805-100UF,4V,20%,X5R,6024A]
    1  PVDDQ_KLM          A  @BASEBOARD_FAB2_LIB.BASEBOARD_FAB2(SCH_1):PVDDQ_KLM
    2  GND                B  @BASEBOARD_FAB2_LIB.BASEBOARD_FAB2(SCH_1):GND

CAP  I83  C8L2   [CAP_0805-100UF,4V,20%,X5R,6024A]
    1  PVDDQ_KLM          A  @BASEBOARD_FAB2_LIB.BASEBOARD_FAB2(SCH_1):PVDDQ_KLM
    2  GND                B  @BASEBOARD_FAB2_LIB.BASEBOARD_FAB2(SCH_1):GND

CAP_A  I48  C8L3   [CAP_A_0603V-47UF,4V,20%,X5R,60A]
    1  PVTT_KLM           A  @BASEBOARD_FAB2_LIB.BASEBOARD_FAB2(SCH_1):PVTT_KLM
    2  GND                B  @BASEBOARD_FAB2_LIB.BASEBOARD_FAB2(SCH_1):GND

CAP_A  I49  C8L4   [CAP_A_0603V-47UF,4V,20%,X5R,60A]
    1  PVTT_KLM           A  @BASEBOARD_FAB2_LIB.BASEBOARD_FAB2(SCH_1):PVTT_KLM
    2  GND                B  @BASEBOARD_FAB2_LIB.BASEBOARD_FAB2(SCH_1):GND

CAP_A  I241  C8L5   [CAP_A_0603V-22.0UF,4V,20%,X6S,A]
    1  PVDDQ_KLM          A  @BASEBOARD_FAB2_LIB.BASEBOARD_FAB2(SCH_1):PVDDQ_KLM
    2  GND                B  @BASEBOARD_FAB2_LIB.BASEBOARD_FAB2(SCH_1):GND

CAP_A  I240  C8L6   [CAP_A_0603V-22.0UF,4V,20%,X6S,A]
    1  PVDDQ_KLM          A  @BASEBOARD_FAB2_LIB.BASEBOARD_FAB2(SCH_1):PVDDQ_KLM
    2  GND                B  @BASEBOARD_FAB2_LIB.BASEBOARD_FAB2(SCH_1):GND

CAP_A  I239  C8L7   [CAP_A_0603V-22.0UF,4V,20%,X6S,A]
    1  PVDDQ_KLM          A  @BASEBOARD_FAB2_LIB.BASEBOARD_FAB2(SCH_1):PVDDQ_KLM
    2  GND                B  @BASEBOARD_FAB2_LIB.BASEBOARD_FAB2(SCH_1):GND

CAP_A  I237  C8L8   [CAP_A_0603V-22.0UF,4V,20%,X6S,A]
    1  PVDDQ_KLM          A  @BASEBOARD_FAB2_LIB.BASEBOARD_FAB2(SCH_1):PVDDQ_KLM
    2  GND                B  @BASEBOARD_FAB2_LIB.BASEBOARD_FAB2(SCH_1):GND

CAP_A  I236  C8L9   [CAP_A_0603V-22.0UF,4V,20%,X6S,A]
    1  PVDDQ_KLM          A  @BASEBOARD_FAB2_LIB.BASEBOARD_FAB2(SCH_1):PVDDQ_KLM
    2  GND                B  @BASEBOARD_FAB2_LIB.BASEBOARD_FAB2(SCH_1):GND

CAP_A  I229  C8L10  [CAP_A_0603V-22.0UF,4V,20%,X6S,A]
    1  PVDDQ_KLM          A  @BASEBOARD_FAB2_LIB.BASEBOARD_FAB2(SCH_1):PVDDQ_KLM
    2  GND                B  @BASEBOARD_FAB2_LIB.BASEBOARD_FAB2(SCH_1):GND

CAP  I88  C8L11  [CAP_0805-100UF,4V,20%,X5R,6024A]
    1  PVDDQ_KLM          A  @BASEBOARD_FAB2_LIB.BASEBOARD_FAB2(SCH_1):PVDDQ_KLM
    2  GND                B  @BASEBOARD_FAB2_LIB.BASEBOARD_FAB2(SCH_1):GND

CAP_A  I201  C8L12  [CAP_A_0603V-47UF,4V,20%,X5R,60A]
    1  PVDDQ_KLM          A  @BASEBOARD_FAB2_LIB.BASEBOARD_FAB2(SCH_1):PVDDQ_KLM
    2  GND                B  @BASEBOARD_FAB2_LIB.BASEBOARD_FAB2(SCH_1):GND

CAP_A  I243  C8M1   [CAP_A_0603V-22.0UF,4V,20%,X6S,A]
    1  PVDDQ_KLM          A  @BASEBOARD_FAB2_LIB.BASEBOARD_FAB2(SCH_1):PVDDQ_KLM
    2  GND                B  @BASEBOARD_FAB2_LIB.BASEBOARD_FAB2(SCH_1):GND

CAP_A  I206  C8M2   [CAP_A_0603V-47UF,4V,20%,X5R,60A]
    1  PVDDQ_KLM          A  @BASEBOARD_FAB2_LIB.BASEBOARD_FAB2(SCH_1):PVDDQ_KLM
    2  GND                B  @BASEBOARD_FAB2_LIB.BASEBOARD_FAB2(SCH_1):GND

CAP_A  I227  C8M3   [CAP_A_0603V-22.0UF,4V,20%,X6S,A]
    1  PVDDQ_KLM          A  @BASEBOARD_FAB2_LIB.BASEBOARD_FAB2(SCH_1):PVDDQ_KLM
    2  GND                B  @BASEBOARD_FAB2_LIB.BASEBOARD_FAB2(SCH_1):GND

CAP_A  I233  C8M4   [CAP_A_0603V-22.0UF,4V,20%,X6S,A]
    1  PVDDQ_KLM          A  @BASEBOARD_FAB2_LIB.BASEBOARD_FAB2(SCH_1):PVDDQ_KLM
    2  GND                B  @BASEBOARD_FAB2_LIB.BASEBOARD_FAB2(SCH_1):GND

CAP_A  I228  C8M5   [CAP_A_0603V-22.0UF,4V,20%,X6S,A]
    1  PVDDQ_KLM          A  @BASEBOARD_FAB2_LIB.BASEBOARD_FAB2(SCH_1):PVDDQ_KLM
    2  GND                B  @BASEBOARD_FAB2_LIB.BASEBOARD_FAB2(SCH_1):GND

CAP_A  I235  C8M6   [CAP_A_0603V-22.0UF,4V,20%,X6S,A]
    1  PVDDQ_KLM          A  @BASEBOARD_FAB2_LIB.BASEBOARD_FAB2(SCH_1):PVDDQ_KLM
    2  GND                B  @BASEBOARD_FAB2_LIB.BASEBOARD_FAB2(SCH_1):GND

CAP  I90  C8M7   [CAP_0805-100UF,4V,20%,X5R,6024A]
    1  PVDDQ_KLM          A  @BASEBOARD_FAB2_LIB.BASEBOARD_FAB2(SCH_1):PVDDQ_KLM
    2  GND                B  @BASEBOARD_FAB2_LIB.BASEBOARD_FAB2(SCH_1):GND

CAP_A  I198  C8M8   [CAP_A_0603V-47UF,4V,20%,X5R,60A]
    1  PVDDQ_KLM          A  @BASEBOARD_FAB2_LIB.BASEBOARD_FAB2(SCH_1):PVDDQ_KLM
    2  GND                B  @BASEBOARD_FAB2_LIB.BASEBOARD_FAB2(SCH_1):GND

CAP_A  I205  C8M9   [CAP_A_0603V-47UF,4V,20%,X5R,60A]
    1  PVDDQ_KLM          A  @BASEBOARD_FAB2_LIB.BASEBOARD_FAB2(SCH_1):PVDDQ_KLM
    2  GND                B  @BASEBOARD_FAB2_LIB.BASEBOARD_FAB2(SCH_1):GND

CAP_A  I203  C8M10  [CAP_A_0603V-47UF,4V,20%,X5R,60A]
    1  PVDDQ_KLM          A  @BASEBOARD_FAB2_LIB.BASEBOARD_FAB2(SCH_1):PVDDQ_KLM
    2  GND                B  @BASEBOARD_FAB2_LIB.BASEBOARD_FAB2(SCH_1):GND

CAP  I91  C8M11  [CAP_0805-100UF,4V,20%,X5R,6024A]
    1  PVDDQ_KLM          A  @BASEBOARD_FAB2_LIB.BASEBOARD_FAB2(SCH_1):PVDDQ_KLM
    2  GND                B  @BASEBOARD_FAB2_LIB.BASEBOARD_FAB2(SCH_1):GND

CAP_A  I47  C8M12  [CAP_A_0603V-47UF,4V,20%,X5R,60A]
    1  PVTT_KLM           A  @BASEBOARD_FAB2_LIB.BASEBOARD_FAB2(SCH_1):PVTT_KLM
    2  GND                B  @BASEBOARD_FAB2_LIB.BASEBOARD_FAB2(SCH_1):GND

CAP  I185  C8P1   [CAP_0805LF-22UF,4V,20%,X6S,C95A]
    1  PVDDQ_KLM          A  @BASEBOARD_FAB2_LIB.BASEBOARD_FAB2(SCH_1):PVDDQ_KLM
    2  GND                B  @BASEBOARD_FAB2_LIB.BASEBOARD_FAB2(SCH_1):GND

CAP  I183  C8P2   [CAP_0805LF-22UF,4V,20%,X6S,C95A]
    1  PVDDQ_KLM          A  @BASEBOARD_FAB2_LIB.BASEBOARD_FAB2(SCH_1):PVDDQ_KLM
    2  GND                B  @BASEBOARD_FAB2_LIB.BASEBOARD_FAB2(SCH_1):GND

CAP  I101  C8P3   [CAP_0805-47UF,4V,20%,X6S,C9533A]
    1  PVCCIN_CPU1        A  @BASEBOARD_FAB2_LIB.BASEBOARD_FAB2(SCH_1):PVCCIN_CPU1
    2  GND                B  @BASEBOARD_FAB2_LIB.BASEBOARD_FAB2(SCH_1):GND

CAP  I88  C8P4   [CAP_0805-47UF,4V,20%,X6S,C9533A]
    1  PVCCIN_CPU1        A  @BASEBOARD_FAB2_LIB.BASEBOARD_FAB2(SCH_1):PVCCIN_CPU1
    2  GND                B  @BASEBOARD_FAB2_LIB.BASEBOARD_FAB2(SCH_1):GND

CAP  I58  C8P5   [CAP_0805LF-22UF,4V,20%,X6S,C95A]
    1  PVSA_CPU1          A  @BASEBOARD_FAB2_LIB.BASEBOARD_FAB2(SCH_1):PVSA_CPU1
    2  GND                B  @BASEBOARD_FAB2_LIB.BASEBOARD_FAB2(SCH_1):GND

CAP  I55  C8P6   [CAP_0805LF-22UF,4V,20%,X6S,C95A]
    1  PVSA_CPU1          A  @BASEBOARD_FAB2_LIB.BASEBOARD_FAB2(SCH_1):PVSA_CPU1
    2  GND                B  @BASEBOARD_FAB2_LIB.BASEBOARD_FAB2(SCH_1):GND

CAP  I50  C8P7   [CAP_0805LF-22UF,4V,20%,X6S,C95A]
    1  PVSA_CPU1          A  @BASEBOARD_FAB2_LIB.BASEBOARD_FAB2(SCH_1):PVSA_CPU1
    2  GND                B  @BASEBOARD_FAB2_LIB.BASEBOARD_FAB2(SCH_1):GND

CAP  I213  C8P8   [CAP_0805-47UF,4V,20%,X6S,C9533A]
    1  PVCCMCP_CPU1       A  @BASEBOARD_FAB2_LIB.BASEBOARD_FAB2(SCH_1):PVCCMCP_CPU1
    2  GND                B  @BASEBOARD_FAB2_LIB.BASEBOARD_FAB2(SCH_1):GND

CAP  I214  C8P9   [CAP_0805-47UF,4V,20%,X6S,C9533A]
    1  PVCCMCP_CPU1       A  @BASEBOARD_FAB2_LIB.BASEBOARD_FAB2(SCH_1):PVCCMCP_CPU1
    2  GND                B  @BASEBOARD_FAB2_LIB.BASEBOARD_FAB2(SCH_1):GND

CAP  I127  C8P10  [CAP_0805-47UF,4V,20%,X6S,C9533A]
    1  PVCCIN_CPU1        A  @BASEBOARD_FAB2_LIB.BASEBOARD_FAB2(SCH_1):PVCCIN_CPU1
    2  GND                B  @BASEBOARD_FAB2_LIB.BASEBOARD_FAB2(SCH_1):GND

CAP  I139  C8P11  [CAP_0805-47UF,4V,20%,X6S,C9533A]
    1  PVCCIN_CPU1        A  @BASEBOARD_FAB2_LIB.BASEBOARD_FAB2(SCH_1):PVCCIN_CPU1
    2  GND                B  @BASEBOARD_FAB2_LIB.BASEBOARD_FAB2(SCH_1):GND

CAP  I107  C8P12  [CAP_0805-47UF,4V,20%,X6S,C9533A]
    1  PVCCIN_CPU1        A  @BASEBOARD_FAB2_LIB.BASEBOARD_FAB2(SCH_1):PVCCIN_CPU1
    2  GND                B  @BASEBOARD_FAB2_LIB.BASEBOARD_FAB2(SCH_1):GND

CAP  I132  C8P13  [CAP_0805-47UF,4V,20%,X6S,C9533A]
    1  PVCCIN_CPU1        A  @BASEBOARD_FAB2_LIB.BASEBOARD_FAB2(SCH_1):PVCCIN_CPU1
    2  GND                B  @BASEBOARD_FAB2_LIB.BASEBOARD_FAB2(SCH_1):GND

CAP  I211  C8P14  [CAP_0805-47UF,4V,20%,X6S,C9533A]
    1  PVCCMCP_CPU1       A  @BASEBOARD_FAB2_LIB.BASEBOARD_FAB2(SCH_1):PVCCMCP_CPU1
    2  GND                B  @BASEBOARD_FAB2_LIB.BASEBOARD_FAB2(SCH_1):GND

CAP  I212  C8P15  [CAP_0805-47UF,4V,20%,X6S,C9533A]
    1  PVCCMCP_CPU1       A  @BASEBOARD_FAB2_LIB.BASEBOARD_FAB2(SCH_1):PVCCMCP_CPU1
    2  GND                B  @BASEBOARD_FAB2_LIB.BASEBOARD_FAB2(SCH_1):GND

CAP  I129  C8P16  [CAP_0805-47UF,4V,20%,X6S,C9533A]
    1  PVCCIN_CPU1        A  @BASEBOARD_FAB2_LIB.BASEBOARD_FAB2(SCH_1):PVCCIN_CPU1
    2  GND                B  @BASEBOARD_FAB2_LIB.BASEBOARD_FAB2(SCH_1):GND

CAP  I133  C8P17  [CAP_0805-47UF,4V,20%,X6S,C9533A]
    1  PVCCIN_CPU1        A  @BASEBOARD_FAB2_LIB.BASEBOARD_FAB2(SCH_1):PVCCIN_CPU1
    2  GND                B  @BASEBOARD_FAB2_LIB.BASEBOARD_FAB2(SCH_1):GND

CAP  I92  C8P18  [CAP_0805-47UF,4V,20%,X6S,C9533A]
    1  PVCCIN_CPU1        A  @BASEBOARD_FAB2_LIB.BASEBOARD_FAB2(SCH_1):PVCCIN_CPU1
    2  GND                B  @BASEBOARD_FAB2_LIB.BASEBOARD_FAB2(SCH_1):GND

CAP  I103  C8P19  [CAP_0805-47UF,4V,20%,X6S,C9533A]
    1  PVCCIN_CPU1        A  @BASEBOARD_FAB2_LIB.BASEBOARD_FAB2(SCH_1):PVCCIN_CPU1
    2  GND                B  @BASEBOARD_FAB2_LIB.BASEBOARD_FAB2(SCH_1):GND

CAP  I89  C8P20  [CAP_0805-47UF,4V,20%,X6S,C9533A]
    1  PVCCIN_CPU1        A  @BASEBOARD_FAB2_LIB.BASEBOARD_FAB2(SCH_1):PVCCIN_CPU1
    2  GND                B  @BASEBOARD_FAB2_LIB.BASEBOARD_FAB2(SCH_1):GND

CAP  I135  C8P21  [CAP_0805-47UF,4V,20%,X6S,C9533A]
    1  PVCCIN_CPU1        A  @BASEBOARD_FAB2_LIB.BASEBOARD_FAB2(SCH_1):PVCCIN_CPU1
    2  GND                B  @BASEBOARD_FAB2_LIB.BASEBOARD_FAB2(SCH_1):GND

CAP  I28  C8P22  [CAP_0805-47UF,4V,20%,X6S,C9533A]
    1  PVCCMCP_CPU1       A  @BASEBOARD_FAB2_LIB.BASEBOARD_FAB2(SCH_1):PVCCMCP_CPU1
    2  GND                B  @BASEBOARD_FAB2_LIB.BASEBOARD_FAB2(SCH_1):GND

CAP  I48  C8P23  [CAP_0805-47UF,4V,20%,X6S,C9533A]
    1  PVCCMCP_CPU1       A  @BASEBOARD_FAB2_LIB.BASEBOARD_FAB2(SCH_1):PVCCMCP_CPU1
    2  GND                B  @BASEBOARD_FAB2_LIB.BASEBOARD_FAB2(SCH_1):GND

CAP  I217  C8P24  [CAP_0805-47UF,4V,20%,X6S,C9533A]
    1  PVCCIN_CPU1        A  @BASEBOARD_FAB2_LIB.BASEBOARD_FAB2(SCH_1):PVCCIN_CPU1
    2  GND                B  @BASEBOARD_FAB2_LIB.BASEBOARD_FAB2(SCH_1):GND

CAP  I136  C8P25  [CAP_0805-47UF,4V,20%,X6S,C9533A]
    1  PVCCIN_CPU1        A  @BASEBOARD_FAB2_LIB.BASEBOARD_FAB2(SCH_1):PVCCIN_CPU1
    2  GND                B  @BASEBOARD_FAB2_LIB.BASEBOARD_FAB2(SCH_1):GND

CAP  I118  C8P26  [CAP_0805-47UF,4V,20%,X6S,C9533A]
    1  PVCCIN_CPU1        A  @BASEBOARD_FAB2_LIB.BASEBOARD_FAB2(SCH_1):PVCCIN_CPU1
    2  GND                B  @BASEBOARD_FAB2_LIB.BASEBOARD_FAB2(SCH_1):GND

CAP  I141  C8P27  [CAP_0805-47UF,4V,20%,X6S,C9533A]
    1  PVCCIN_CPU1        A  @BASEBOARD_FAB2_LIB.BASEBOARD_FAB2(SCH_1):PVCCIN_CPU1
    2  GND                B  @BASEBOARD_FAB2_LIB.BASEBOARD_FAB2(SCH_1):GND

CAP  I137  C8P28  [CAP_0805-47UF,4V,20%,X6S,C9533A]
    1  PVCCIN_CPU1        A  @BASEBOARD_FAB2_LIB.BASEBOARD_FAB2(SCH_1):PVCCIN_CPU1
    2  GND                B  @BASEBOARD_FAB2_LIB.BASEBOARD_FAB2(SCH_1):GND

CAP  I125  C8P29  [CAP_0805-47UF,4V,20%,X6S,C9533A]
    1  PVCCIN_CPU1        A  @BASEBOARD_FAB2_LIB.BASEBOARD_FAB2(SCH_1):PVCCIN_CPU1
    2  GND                B  @BASEBOARD_FAB2_LIB.BASEBOARD_FAB2(SCH_1):GND

CAP  I184  C8P30  [CAP_0805LF-22UF,4V,20%,X6S,C95A]
    1  PVDDQ_GHJ          A  @BASEBOARD_FAB2_LIB.BASEBOARD_FAB2(SCH_1):PVDDQ_GHJ
    2  GND                B  @BASEBOARD_FAB2_LIB.BASEBOARD_FAB2(SCH_1):GND

CAP  I178  C8P31  [CAP_0805LF-22UF,4V,20%,X6S,C95A]
    1  PVDDQ_GHJ          A  @BASEBOARD_FAB2_LIB.BASEBOARD_FAB2(SCH_1):PVDDQ_GHJ
    2  GND                B  @BASEBOARD_FAB2_LIB.BASEBOARD_FAB2(SCH_1):GND

CAP  I216  C8P32  [CAP_0805-47UF,4V,20%,X6S,C9533A]
    1  PVCCIN_CPU1        A  @BASEBOARD_FAB2_LIB.BASEBOARD_FAB2(SCH_1):PVCCIN_CPU1
    2  GND                B  @BASEBOARD_FAB2_LIB.BASEBOARD_FAB2(SCH_1):GND

CAP  I131  C8P33  [CAP_0805-47UF,4V,20%,X6S,C9533A]
    1  PVCCIN_CPU1        A  @BASEBOARD_FAB2_LIB.BASEBOARD_FAB2(SCH_1):PVCCIN_CPU1
    2  GND                B  @BASEBOARD_FAB2_LIB.BASEBOARD_FAB2(SCH_1):GND

CAP  I106  C8P34  [CAP_0805-47UF,4V,20%,X6S,C9533A]
    1  PVCCIN_CPU1        A  @BASEBOARD_FAB2_LIB.BASEBOARD_FAB2(SCH_1):PVCCIN_CPU1
    2  GND                B  @BASEBOARD_FAB2_LIB.BASEBOARD_FAB2(SCH_1):GND

CAP_A  I202  C8T1   [CAP_A_0603V-47UF,4V,20%,X5R,60A]
    1  PVDDQ_GHJ          A  @BASEBOARD_FAB2_LIB.BASEBOARD_FAB2(SCH_1):PVDDQ_GHJ
    2  GND                B  @BASEBOARD_FAB2_LIB.BASEBOARD_FAB2(SCH_1):GND

CAP_A  I198  C8T2   [CAP_A_0603V-47UF,4V,20%,X5R,60A]
    1  PVDDQ_GHJ          A  @BASEBOARD_FAB2_LIB.BASEBOARD_FAB2(SCH_1):PVDDQ_GHJ
    2  GND                B  @BASEBOARD_FAB2_LIB.BASEBOARD_FAB2(SCH_1):GND

CAP_A  I48  C8T3   [CAP_A_0603V-47UF,4V,20%,X5R,60A]
    1  PVTT_GHJ           A  @BASEBOARD_FAB2_LIB.BASEBOARD_FAB2(SCH_1):PVTT_GHJ
    2  GND                B  @BASEBOARD_FAB2_LIB.BASEBOARD_FAB2(SCH_1):GND

CAP_A  I196  C8T4   [CAP_A_0603V-47UF,4V,20%,X5R,60A]
    1  PVDDQ_GHJ          A  @BASEBOARD_FAB2_LIB.BASEBOARD_FAB2(SCH_1):PVDDQ_GHJ
    2  GND                B  @BASEBOARD_FAB2_LIB.BASEBOARD_FAB2(SCH_1):GND

CAP_A  I233  C8T5   [CAP_A_0603V-22.0UF,4V,20%,X6S,A]
    1  PVDDQ_GHJ          A  @BASEBOARD_FAB2_LIB.BASEBOARD_FAB2(SCH_1):PVDDQ_GHJ
    2  GND                B  @BASEBOARD_FAB2_LIB.BASEBOARD_FAB2(SCH_1):GND

CAP_A  I231  C8T6   [CAP_A_0603V-22.0UF,4V,20%,X6S,A]
    1  PVDDQ_GHJ          A  @BASEBOARD_FAB2_LIB.BASEBOARD_FAB2(SCH_1):PVDDQ_GHJ
    2  GND                B  @BASEBOARD_FAB2_LIB.BASEBOARD_FAB2(SCH_1):GND

CAP_A  I230  C8T7   [CAP_A_0603V-22.0UF,4V,20%,X6S,A]
    1  PVDDQ_GHJ          A  @BASEBOARD_FAB2_LIB.BASEBOARD_FAB2(SCH_1):PVDDQ_GHJ
    2  GND                B  @BASEBOARD_FAB2_LIB.BASEBOARD_FAB2(SCH_1):GND

CAP_A  I229  C8T8   [CAP_A_0603V-22.0UF,4V,20%,X6S,A]
    1  PVDDQ_GHJ          A  @BASEBOARD_FAB2_LIB.BASEBOARD_FAB2(SCH_1):PVDDQ_GHJ
    2  GND                B  @BASEBOARD_FAB2_LIB.BASEBOARD_FAB2(SCH_1):GND

CAP_A  I227  C8T9   [CAP_A_0603V-22.0UF,4V,20%,X6S,A]
    1  PVDDQ_GHJ          A  @BASEBOARD_FAB2_LIB.BASEBOARD_FAB2(SCH_1):PVDDQ_GHJ
    2  GND                B  @BASEBOARD_FAB2_LIB.BASEBOARD_FAB2(SCH_1):GND

CAP_A  I226  C8T10  [CAP_A_0603V-22.0UF,4V,20%,X6S,A]
    1  PVDDQ_GHJ          A  @BASEBOARD_FAB2_LIB.BASEBOARD_FAB2(SCH_1):PVDDQ_GHJ
    2  GND                B  @BASEBOARD_FAB2_LIB.BASEBOARD_FAB2(SCH_1):GND

CAP_A  I204  C8T11  [CAP_A_0603V-47UF,4V,20%,X5R,60A]
    1  PVDDQ_GHJ          A  @BASEBOARD_FAB2_LIB.BASEBOARD_FAB2(SCH_1):PVDDQ_GHJ
    2  GND                B  @BASEBOARD_FAB2_LIB.BASEBOARD_FAB2(SCH_1):GND

CAP  I82  C8U1   [CAP_0805-100UF,4V,20%,X5R,6024A]
    1  PVDDQ_GHJ          A  @BASEBOARD_FAB2_LIB.BASEBOARD_FAB2(SCH_1):PVDDQ_GHJ
    2  GND                B  @BASEBOARD_FAB2_LIB.BASEBOARD_FAB2(SCH_1):GND

CAP_A  I239  C8U2   [CAP_A_0603V-22.0UF,4V,20%,X6S,A]
    1  PVDDQ_GHJ          A  @BASEBOARD_FAB2_LIB.BASEBOARD_FAB2(SCH_1):PVDDQ_GHJ
    2  GND                B  @BASEBOARD_FAB2_LIB.BASEBOARD_FAB2(SCH_1):GND

CAP_A  I236  C8U3   [CAP_A_0603V-22.0UF,4V,20%,X6S,A]
    1  PVDDQ_GHJ          A  @BASEBOARD_FAB2_LIB.BASEBOARD_FAB2(SCH_1):PVDDQ_GHJ
    2  GND                B  @BASEBOARD_FAB2_LIB.BASEBOARD_FAB2(SCH_1):GND

CAP_A  I225  C8U4   [CAP_A_0603V-22.0UF,4V,20%,X6S,A]
    1  PVDDQ_GHJ          A  @BASEBOARD_FAB2_LIB.BASEBOARD_FAB2(SCH_1):PVDDQ_GHJ
    2  GND                B  @BASEBOARD_FAB2_LIB.BASEBOARD_FAB2(SCH_1):GND

CAP_A  I228  C8U5   [CAP_A_0603V-22.0UF,4V,20%,X6S,A]
    1  PVDDQ_GHJ          A  @BASEBOARD_FAB2_LIB.BASEBOARD_FAB2(SCH_1):PVDDQ_GHJ
    2  GND                B  @BASEBOARD_FAB2_LIB.BASEBOARD_FAB2(SCH_1):GND

CAP_A  I232  C8U6   [CAP_A_0603V-22.0UF,4V,20%,X6S,A]
    1  PVDDQ_GHJ          A  @BASEBOARD_FAB2_LIB.BASEBOARD_FAB2(SCH_1):PVDDQ_GHJ
    2  GND                B  @BASEBOARD_FAB2_LIB.BASEBOARD_FAB2(SCH_1):GND

CAP_A  I241  C8U7   [CAP_A_0603V-22.0UF,4V,20%,X6S,A]
    1  PVDDQ_GHJ          A  @BASEBOARD_FAB2_LIB.BASEBOARD_FAB2(SCH_1):PVDDQ_GHJ
    2  GND                B  @BASEBOARD_FAB2_LIB.BASEBOARD_FAB2(SCH_1):GND

CAP  I83  C8U8   [CAP_0805-100UF,4V,20%,X5R,6024A]
    1  PVDDQ_GHJ          A  @BASEBOARD_FAB2_LIB.BASEBOARD_FAB2(SCH_1):PVDDQ_GHJ
    2  GND                B  @BASEBOARD_FAB2_LIB.BASEBOARD_FAB2(SCH_1):GND

CAP_A  I203  C8U9   [CAP_A_0603V-47UF,4V,20%,X5R,60A]
    1  PVDDQ_GHJ          A  @BASEBOARD_FAB2_LIB.BASEBOARD_FAB2(SCH_1):PVDDQ_GHJ
    2  GND                B  @BASEBOARD_FAB2_LIB.BASEBOARD_FAB2(SCH_1):GND

CAP_A  I49  C8U10  [CAP_A_0603V-47UF,4V,20%,X5R,60A]
    1  PVTT_GHJ           A  @BASEBOARD_FAB2_LIB.BASEBOARD_FAB2(SCH_1):PVTT_GHJ
    2  GND                B  @BASEBOARD_FAB2_LIB.BASEBOARD_FAB2(SCH_1):GND

CAP  I89  C8U11  [CAP_0805-100UF,4V,20%,X5R,6024A]
    1  PVDDQ_GHJ          A  @BASEBOARD_FAB2_LIB.BASEBOARD_FAB2(SCH_1):PVDDQ_GHJ
    2  GND                B  @BASEBOARD_FAB2_LIB.BASEBOARD_FAB2(SCH_1):GND

CAP  I88  C8U12  [CAP_0805-100UF,4V,20%,X5R,6024A]
    1  PVDDQ_GHJ          A  @BASEBOARD_FAB2_LIB.BASEBOARD_FAB2(SCH_1):PVDDQ_GHJ
    2  GND                B  @BASEBOARD_FAB2_LIB.BASEBOARD_FAB2(SCH_1):GND

CAP_A  I199  C8U13  [CAP_A_0603V-47UF,4V,20%,X5R,60A]
    1  PVDDQ_GHJ          A  @BASEBOARD_FAB2_LIB.BASEBOARD_FAB2(SCH_1):PVDDQ_GHJ
    2  GND                B  @BASEBOARD_FAB2_LIB.BASEBOARD_FAB2(SCH_1):GND

CAP_A  I127  C9A1   [CAP_A_0402V-0.1UF,16V,10%,X7R,A]
    1  P5V_STBY_DGB_FS      A  @BASEBOARD_FAB2_LIB.BASEBOARD_FAB2(SCH_1):P5V_STBY_DGB_FS
    2  GND                B  @BASEBOARD_FAB2_LIB.BASEBOARD_FAB2(SCH_1):GND

CAP_A  I10  C9A2   [CAP_A_0402V-0.1UF,16V,10%,X7R,A]
    1  XDP_SYSPWROK       A  @BASEBOARD_FAB2_LIB.BASEBOARD_FAB2(SCH_1):XDP_SYSPWROK
    2  GND                B  @BASEBOARD_FAB2_LIB.BASEBOARD_FAB2(SCH_1):GND

CAP_A  I40  C9A3   [CAP_A_0402V-0.1UF,16V,10%,X7R,A]
    1  P3V3_STBY          A  @BASEBOARD_FAB2_LIB.BASEBOARD_FAB2(SCH_1):P3V3_STBY
    2  GND                B  @BASEBOARD_FAB2_LIB.BASEBOARD_FAB2(SCH_1):GND

CAP_A  I59  C9A4   [CAP_A_0402V-0.1UF,16V,10%,X7R,A]
    1  XDP_CPU_PWR_DEBUG_N      A  @BASEBOARD_FAB2_LIB.BASEBOARD_FAB2(SCH_1):XDP_CPU_PWR_DEBUG_N
    2  GND                B  @BASEBOARD_FAB2_LIB.BASEBOARD_FAB2(SCH_1):GND

CAP_A  I12  C9A5   [CAP_A_0402V-0.1UF,16V,10%,X7R,A]
    1  XDP_RST_CO_N       A  @BASEBOARD_FAB2_LIB.BASEBOARD_FAB2(SCH_1):XDP_RST_CO_N
    2  GND                B  @BASEBOARD_FAB2_LIB.BASEBOARD_FAB2(SCH_1):GND

CAP_A  I25  C9A6   [CAP_A_0402V-1.0UF,6.3V,10%,X6SA]
    1  P1V05_PCH_STBY      A  @BASEBOARD_FAB2_LIB.BASEBOARD_FAB2(SCH_1):P1V05_PCH_STBY
    2  GND                B  @BASEBOARD_FAB2_LIB.BASEBOARD_FAB2(SCH_1):GND

CAP  I39  C9B1   [CAP_0805-10UF,16V,10%,X6S,C953A]
    1  P5V_HDD_SATA       A  @BASEBOARD_FAB2_LIB.BASEBOARD_FAB2(SCH_1):P5V_HDD_SATA
    2  GND                B  @BASEBOARD_FAB2_LIB.BASEBOARD_FAB2(SCH_1):GND

CAP  I36  C9B2   [CAP_0805-10UF,16V,10%,X6S,C953A]
    1  P12V_HDD_SATA      A  @BASEBOARD_FAB2_LIB.BASEBOARD_FAB2(SCH_1):P12V_HDD_SATA
    2  GND                B  @BASEBOARD_FAB2_LIB.BASEBOARD_FAB2(SCH_1):GND

CAP_A  I39  C9B7   [CAP_A_0402V-0.1UF,16V,10%,X7R,A]
    1  P3V3_STBY          A  @BASEBOARD_FAB2_LIB.BASEBOARD_FAB2(SCH_1):P3V3_STBY
    2  GND                B  @BASEBOARD_FAB2_LIB.BASEBOARD_FAB2(SCH_1):GND

CAPP  I113  C9B8   [CAPP_7343HLF-330UF,10V,20%,POSA]
    1  P5V_USB            A  @BASEBOARD_FAB2_LIB.BASEBOARD_FAB2(SCH_1):P5V_USB
    2  GND                B  @BASEBOARD_FAB2_LIB.BASEBOARD_FAB2(SCH_1):GND

CAP_A  I347  C9B9   [CAP_A_0402V-1.0UF,6.3V,10%,X6SA]
    1  P5V_STBY           A  @BASEBOARD_FAB2_LIB.BASEBOARD_FAB2(SCH_1):P5V_STBY
    2  GND                B  @BASEBOARD_FAB2_LIB.BASEBOARD_FAB2(SCH_1):GND

CAP_A  I345  C9B10  [CAP_A_0402V-0.1UF,16V,10%,X7R,A]
    1  P5V_STBY           A  @BASEBOARD_FAB2_LIB.BASEBOARD_FAB2(SCH_1):P5V_STBY
    2  GND                B  @BASEBOARD_FAB2_LIB.BASEBOARD_FAB2(SCH_1):GND

CAP_A  I163  C9E1   [CAP_A_0603V-22.0UF,4V,20%,EMPTA]
    1  P0V9_LAN           A  @BASEBOARD_FAB2_LIB.BASEBOARD_FAB2(SCH_1):P0V9_LAN
    2  GND                B  @BASEBOARD_FAB2_LIB.BASEBOARD_FAB2(SCH_1):GND

CAP_A  I88  C9E4   [CAP_A_0402V-0.1UF,16V,10%,X7R,A]
    1  PE_PCH_SPRV_RX_DP      A  @BASEBOARD_FAB2_LIB.BASEBOARD_FAB2(SCH_1):PE_PCH_SPRV_RX_DP
    2  PE_PCH_SPRV_RX_C_DP      B  @BASEBOARD_FAB2_LIB.BASEBOARD_FAB2(SCH_1):PE_PCH_SPRV_RX_C_DP

CAP_A  I87  C9E5   [CAP_A_0402V-0.1UF,16V,10%,X7R,A]
    1  PE_PCH_SPRV_RX_DN      A  @BASEBOARD_FAB2_LIB.BASEBOARD_FAB2(SCH_1):PE_PCH_SPRV_RX_DN
    2  PE_PCH_SPRV_RX_C_DN      B  @BASEBOARD_FAB2_LIB.BASEBOARD_FAB2(SCH_1):PE_PCH_SPRV_RX_C_DN

CAP  I155  C9E6   [CAP_1210-47UF,16V,20%,EMPTY,D3A]
    1  P1V5_LAN           A  @BASEBOARD_FAB2_LIB.BASEBOARD_FAB2(SCH_1):P1V5_LAN
    2  GND                B  @BASEBOARD_FAB2_LIB.BASEBOARD_FAB2(SCH_1):GND

CAP  I76  C9E7   [CAP_0402LF-0.039UF,25V,10%,X7RA]
    1  A_CTOP             A  @BASEBOARD_FAB2_LIB.BASEBOARD_FAB2(SCH_1):A_CTOP
    2  A_CBOT             B  @BASEBOARD_FAB2_LIB.BASEBOARD_FAB2(SCH_1):A_CBOT

CAP  I111  C9E8   [CAP_0402LF-22.0PF,50V,5%,COG,AA]
    1  XTAL_25MHZ_OUT_R      A  @BASEBOARD_FAB2_LIB.BASEBOARD_FAB2(SCH_1):XTAL_25MHZ_OUT_R
    2  GND                B  @BASEBOARD_FAB2_LIB.BASEBOARD_FAB2(SCH_1):GND

CAP  I112  C9E9   [CAP_0402LF-22.0PF,50V,5%,COG,AA]
    1  XTAL_25MHZ_IN      A  @BASEBOARD_FAB2_LIB.BASEBOARD_FAB2(SCH_1):XTAL_25MHZ_IN
    2  GND                B  @BASEBOARD_FAB2_LIB.BASEBOARD_FAB2(SCH_1):GND

CAP  I23  C9E10  [CAP_0603-10UF,6.3V,20%,X6S,E15A]
    1  P1V26_BMC_STBY      A  @BASEBOARD_FAB2_LIB.BASEBOARD_FAB2(SCH_1):P1V26_BMC_STBY
    2  GND                B  @BASEBOARD_FAB2_LIB.BASEBOARD_FAB2(SCH_1):GND

CAP_0402  I39  C9E11  [CAP_0402-1.0UF,16V,10%,X6S,D97A]
    1  P3V3_STBY          A  @BASEBOARD_FAB2_LIB.BASEBOARD_FAB2(SCH_1):P3V3_STBY
    2  GND                B  @BASEBOARD_FAB2_LIB.BASEBOARD_FAB2(SCH_1):GND

CAP_A  I241  C9E12  [CAP_A_0603V-22.0UF,4V,20%,EMPTA]
    1  P0V9_LAN           A  @BASEBOARD_FAB2_LIB.BASEBOARD_FAB2(SCH_1):P0V9_LAN
    2  GND                B  @BASEBOARD_FAB2_LIB.BASEBOARD_FAB2(SCH_1):GND

CAP  I134  C9F1   [CAP_1210-47UF,16V,20%,X6S,D384A]
    1  VR_FET_SW_P12V_STBY_P3V3_STBY      A  @BASEBOARD_FAB2_LIB.BASEBOARD_FAB2(SCH_1):VR_FET_SW_P12V_STBY_P3V3_STBY
    2  GND                B  @BASEBOARD_FAB2_LIB.BASEBOARD_FAB2(SCH_1):GND

CAP  I140  C9F2   [CAP_1210-47UF,16V,20%,EMPTY,D3A]
    1  P3V3_STBY          A  @BASEBOARD_FAB2_LIB.BASEBOARD_FAB2(SCH_1):P3V3_STBY
    2  GND                B  @BASEBOARD_FAB2_LIB.BASEBOARD_FAB2(SCH_1):GND

CAP  I7   C9F3   [CAP_0603-10UF,6.3V,20%,X6S,E15A]
    1  P1V538_BMC_STBY      A  @BASEBOARD_FAB2_LIB.BASEBOARD_FAB2(SCH_1):P1V538_BMC_STBY
    2  GND                B  @BASEBOARD_FAB2_LIB.BASEBOARD_FAB2(SCH_1):GND

CAP  I30  C9F4   [CAP_0805LF-22UF,4V,20%,X6S,C95A]
    1  P1V26_BMC_STBY      A  @BASEBOARD_FAB2_LIB.BASEBOARD_FAB2(SCH_1):P1V26_BMC_STBY
    2  GND                B  @BASEBOARD_FAB2_LIB.BASEBOARD_FAB2(SCH_1):GND

CAP_A  I71  C9F5   [CAP_A_0402V-0.1UF,16V,10%,X7R,A]
    1  P3V3_STBY          A  @BASEBOARD_FAB2_LIB.BASEBOARD_FAB2(SCH_1):P3V3_STBY
    2  GND                B  @BASEBOARD_FAB2_LIB.BASEBOARD_FAB2(SCH_1):GND

CAP  I30  C9F6   [CAP_0402LF-1000PF,50V,10%,EMPTA]
    1  PWRGD_P3V3_STBY      A  @BASEBOARD_FAB2_LIB.BASEBOARD_FAB2(SCH_1):PWRGD_P3V3_STBY
    2  GND                B  @BASEBOARD_FAB2_LIB.BASEBOARD_FAB2(SCH_1):GND

CAP  I19  C9F8   [CAP_0402LF-1000PF,50V,10%,X7R,A]
    1  PWRGD_P1V26_BMC_STBY_R      A  @BASEBOARD_FAB2_LIB.BASEBOARD_FAB2(SCH_1):PWRGD_P1V26_BMC_STBY_R
    2  GND                B  @BASEBOARD_FAB2_LIB.BASEBOARD_FAB2(SCH_1):GND

CAP  I5   C9F9   [CAP_0402LF-1000PF,50V,10%,EMPTA]
    1  PWRGD_P1V538_BMC_STBY      A  @BASEBOARD_FAB2_LIB.BASEBOARD_FAB2(SCH_1):PWRGD_P1V538_BMC_STBY
    2  GND                B  @BASEBOARD_FAB2_LIB.BASEBOARD_FAB2(SCH_1):GND

CAP  I4   C9F10  [CAP_0402LF-1000PF,50V,10%,X7R,A]
    1  PWRGD_P1V538_BMC_STBY_R      A  @BASEBOARD_FAB2_LIB.BASEBOARD_FAB2(SCH_1):PWRGD_P1V538_BMC_STBY_R
    2  GND                B  @BASEBOARD_FAB2_LIB.BASEBOARD_FAB2(SCH_1):GND

CAP_A  I90  C9F11  [CAP_A_0402V-0.1UF,16V,10%,X7R,A]
    1  P3V3_STBY          A  @BASEBOARD_FAB2_LIB.BASEBOARD_FAB2(SCH_1):P3V3_STBY
    2  GND                B  @BASEBOARD_FAB2_LIB.BASEBOARD_FAB2(SCH_1):GND

CAP_A  I106  C9F12  [CAP_A_0402V-1.0UF,6.3V,10%,X6SA]
    1  P1V26_BMC_STBY_V1PLLAV12      A  @BASEBOARD_FAB2_LIB.BASEBOARD_FAB2(SCH_1):P1V26_BMC_STBY_V1PLLAV12
    2  GND                B  @BASEBOARD_FAB2_LIB.BASEBOARD_FAB2(SCH_1):GND

CAP  I7   C9F13  [CAP_0805LF-22UF,4V,20%,X6S,C95A]
    1  P1V538_BMC_STBY      A  @BASEBOARD_FAB2_LIB.BASEBOARD_FAB2(SCH_1):P1V538_BMC_STBY
    2  GND                B  @BASEBOARD_FAB2_LIB.BASEBOARD_FAB2(SCH_1):GND

CAP_A  I105  C9F14  [CAP_A_0402V-0.1UF,16V,10%,X7R,A]
    1  P1V26_BMC_STBY_V1PLLAV12      A  @BASEBOARD_FAB2_LIB.BASEBOARD_FAB2(SCH_1):P1V26_BMC_STBY_V1PLLAV12
    2  GND                B  @BASEBOARD_FAB2_LIB.BASEBOARD_FAB2(SCH_1):GND

CAP_A  I160  C9F15  [CAP_A_0402V-0.1UF,16V,10%,EMPTA]
    1  P1V8_BMC_STBY_PCIEA      A  @BASEBOARD_FAB2_LIB.BASEBOARD_FAB2(SCH_1):P1V8_BMC_STBY_PCIEA
    2  GND                B  @BASEBOARD_FAB2_LIB.BASEBOARD_FAB2(SCH_1):GND

CAP_A  I202  C9F16  [CAP_A_0402V-0.1UF,16V,10%,EMPTA]
    1  P2E_SSB_BMC_RX_DN      A  @BASEBOARD_FAB2_LIB.BASEBOARD_FAB2(SCH_1):P2E_SSB_BMC_RX_DN
    2  P2E_SSB_BMC_RX_C_DN      B  @BASEBOARD_FAB2_LIB.BASEBOARD_FAB2(SCH_1):P2E_SSB_BMC_RX_C_DN

CAP_A  I201  C9F17  [CAP_A_0402V-0.1UF,16V,10%,EMPTA]
    1  P2E_SSB_BMC_RX_DP      A  @BASEBOARD_FAB2_LIB.BASEBOARD_FAB2(SCH_1):P2E_SSB_BMC_RX_DP
    2  P2E_SSB_BMC_RX_C_DP      B  @BASEBOARD_FAB2_LIB.BASEBOARD_FAB2(SCH_1):P2E_SSB_BMC_RX_C_DP

CAP  I104  C9F18  [CAP_0402LF-100.0PF,50V,5%,COG,A]
    1  P1V26_BMC_STBY_V1PLLAV12      A  @BASEBOARD_FAB2_LIB.BASEBOARD_FAB2(SCH_1):P1V26_BMC_STBY_V1PLLAV12
    2  GND                B  @BASEBOARD_FAB2_LIB.BASEBOARD_FAB2(SCH_1):GND

CAP_A  I7   C9F19  [CAP_A_0402V-0.1UF,16V,10%,X7R,A]
    1  P3V3_STBY          A  @BASEBOARD_FAB2_LIB.BASEBOARD_FAB2(SCH_1):P3V3_STBY
    2  GND                B  @BASEBOARD_FAB2_LIB.BASEBOARD_FAB2(SCH_1):GND

CAP  I20  C9F20  [CAP_0402LF-12.0PF,50V,5%,COG,AA]
    1  XTAL_24MHZ_PI7C9X1172_IN      A  @BASEBOARD_FAB2_LIB.BASEBOARD_FAB2(SCH_1):XTAL_24MHZ_PI7C9X1172_IN
    2  GND                B  @BASEBOARD_FAB2_LIB.BASEBOARD_FAB2(SCH_1):GND

CAP  I21  C9F21  [CAP_0402LF-12.0PF,50V,5%,COG,AA]
    1  XTAL_24MHZ_PI7C9X1172_OUT      A  @BASEBOARD_FAB2_LIB.BASEBOARD_FAB2(SCH_1):XTAL_24MHZ_PI7C9X1172_OUT
    2  GND                B  @BASEBOARD_FAB2_LIB.BASEBOARD_FAB2(SCH_1):GND

CAP  I60  C9F22  [CAP_0402LF-470PF,50V,10%,X7R,AA]
    1  LED_LAN_1_N        A  @BASEBOARD_FAB2_LIB.BASEBOARD_FAB2(SCH_1):LED_LAN_1_N
    2  GND                B  @BASEBOARD_FAB2_LIB.BASEBOARD_FAB2(SCH_1):GND

CAP_A  I258  C9F23  [CAP_A_0402V-0.1UF,16V,10%,X7R,A]
    1  P3V3_STBY          A  @BASEBOARD_FAB2_LIB.BASEBOARD_FAB2(SCH_1):P3V3_STBY
    2  GND                B  @BASEBOARD_FAB2_LIB.BASEBOARD_FAB2(SCH_1):GND

CAP  I58  C9G1   [CAP_0402LF-470PF,50V,10%,X7R,AA]
    1  LED_LAN_2_N        A  @BASEBOARD_FAB2_LIB.BASEBOARD_FAB2(SCH_1):LED_LAN_2_N
    2  GND                B  @BASEBOARD_FAB2_LIB.BASEBOARD_FAB2(SCH_1):GND

CAP  I36  C9G2   [CAP_0402LF-470PF,50V,10%,X7R,AA]
    1  P3V3_STBY          A  @BASEBOARD_FAB2_LIB.BASEBOARD_FAB2(SCH_1):P3V3_STBY
    2  GND                B  @BASEBOARD_FAB2_LIB.BASEBOARD_FAB2(SCH_1):GND

CAP  I59  C9G3   [CAP_0402LF-470PF,50V,10%,X7R,AA]
    1  LED_LAN_0_N        A  @BASEBOARD_FAB2_LIB.BASEBOARD_FAB2(SCH_1):LED_LAN_0_N
    2  GND                B  @BASEBOARD_FAB2_LIB.BASEBOARD_FAB2(SCH_1):GND

CAP_A  I46  C9G4   [CAP_A_0402V-0.1UF,16V,10%,X7R,A]
    1  GND_LAN_TRCT1234_C      A  @BASEBOARD_FAB2_LIB.BASEBOARD_FAB2(SCH_1):GND_LAN_TRCT1234_C
    2  GND                B  @BASEBOARD_FAB2_LIB.BASEBOARD_FAB2(SCH_1):GND

CAP_0402  I48  C9G5   [CAP_0402-1.0UF,16V,10%,X7S,G71A]
    1  GND_LAN_TRCT1234_C      A  @BASEBOARD_FAB2_LIB.BASEBOARD_FAB2(SCH_1):GND_LAN_TRCT1234_C
    2  GND                B  @BASEBOARD_FAB2_LIB.BASEBOARD_FAB2(SCH_1):GND

CAP_A  I47  C9G6   [CAP_A_0402V-0.1UF,16V,10%,X7R,A]
    1  GND_LAN_TRCT1234_C      A  @BASEBOARD_FAB2_LIB.BASEBOARD_FAB2(SCH_1):GND_LAN_TRCT1234_C
    2  GND                B  @BASEBOARD_FAB2_LIB.BASEBOARD_FAB2(SCH_1):GND

CAP_A  I33  C9G7   [CAP_A_0402V-0.1UF,16V,10%,X7R,A]
    1  P3V3_STBY          A  @BASEBOARD_FAB2_LIB.BASEBOARD_FAB2(SCH_1):P3V3_STBY
    2  GND                B  @BASEBOARD_FAB2_LIB.BASEBOARD_FAB2(SCH_1):GND

CAP_A  I75  C9G8   [CAP_A_0402V-0.1UF,16V,10%,EMPTA]
    1  P3V3_STBY_BMC_ADCVREFP      A  @BASEBOARD_FAB2_LIB.BASEBOARD_FAB2(SCH_1):P3V3_STBY_BMC_ADCVREFP
    2  P3V3_STBY_BMC_ADCVREFN      B  @BASEBOARD_FAB2_LIB.BASEBOARD_FAB2(SCH_1):P3V3_STBY_BMC_ADCVREFN

CAP  I99  C9G9   [CAP_0402LF-4700PF,50V,10%,EMPTA]
    1  NIC_SER_P_MDI_3_DP      A  @BASEBOARD_FAB2_LIB.BASEBOARD_FAB2(SCH_1):NIC_SER_P_MDI_3_DP
    2  NIC_MDI_MNG_RX_DP      B  @BASEBOARD_FAB2_LIB.BASEBOARD_FAB2(SCH_1):NIC_MDI_MNG_RX_DP

CAP_A  I79  C9G10  [CAP_A_0402V-0.1UF,16V,10%,EMPTA]
    2  P3V3_STBY_BMC_ADCVREFN      B  @BASEBOARD_FAB2_LIB.BASEBOARD_FAB2(SCH_1):P3V3_STBY_BMC_ADCVREFN
    1  GND                A  @BASEBOARD_FAB2_LIB.BASEBOARD_FAB2(SCH_1):GND

CAP_A  I76  C9G11  [CAP_A_0402V-0.1UF,16V,10%,EMPTA]
    2  P3V3_STBY_BMC_ADCVREFP      B  @BASEBOARD_FAB2_LIB.BASEBOARD_FAB2(SCH_1):P3V3_STBY_BMC_ADCVREFP
    1  P3V3_STBY_BMC_ADCAV33      A  @BASEBOARD_FAB2_LIB.BASEBOARD_FAB2(SCH_1):P3V3_STBY_BMC_ADCAV33

CAP  I100  C9G12  [CAP_0402LF-4700PF,50V,10%,EMPTA]
    1  NIC_SER_N_MDI_3_DN      A  @BASEBOARD_FAB2_LIB.BASEBOARD_FAB2(SCH_1):NIC_SER_N_MDI_3_DN
    2  NIC_MDI_MNG_RX_DN      B  @BASEBOARD_FAB2_LIB.BASEBOARD_FAB2(SCH_1):NIC_MDI_MNG_RX_DN

CAP  I102  C9G13  [CAP_0402LF-4700PF,50V,10%,EMPTA]
    1  NIC_SET_N_MDI_2_DN      A  @BASEBOARD_FAB2_LIB.BASEBOARD_FAB2(SCH_1):NIC_SET_N_MDI_2_DN
    2  NIC_MDI_MNG_TX_DN      B  @BASEBOARD_FAB2_LIB.BASEBOARD_FAB2(SCH_1):NIC_MDI_MNG_TX_DN

CAP  I146  C9G14  [CAP_0402LF-47.0PF,50V,5%,COG,AA]
    2  GND                B  @BASEBOARD_FAB2_LIB.BASEBOARD_FAB2(SCH_1):GND
    1  A_P3V3_SCALED      A  @BASEBOARD_FAB2_LIB.BASEBOARD_FAB2(SCH_1):A_P3V3_SCALED

CAP  I139  C9G15  [CAP_0402LF-47.0PF,50V,5%,COG,AA]
    2  GND                B  @BASEBOARD_FAB2_LIB.BASEBOARD_FAB2(SCH_1):GND
    1  A_P5V_SCALED       A  @BASEBOARD_FAB2_LIB.BASEBOARD_FAB2(SCH_1):A_P5V_SCALED

CAP  I101  C9G16  [CAP_0402LF-4700PF,50V,10%,EMPTA]
    1  NIC_SET_P_MDI_2_DP      A  @BASEBOARD_FAB2_LIB.BASEBOARD_FAB2(SCH_1):NIC_SET_P_MDI_2_DP
    2  NIC_MDI_MNG_TX_DP      B  @BASEBOARD_FAB2_LIB.BASEBOARD_FAB2(SCH_1):NIC_MDI_MNG_TX_DP

CAP  I80  C9G17  [CAP_0402LF-47.0PF,50V,5%,COG,AA]
    2  GND                B  @BASEBOARD_FAB2_LIB.BASEBOARD_FAB2(SCH_1):GND
    1  A_P12V_STBY_SCALED      A  @BASEBOARD_FAB2_LIB.BASEBOARD_FAB2(SCH_1):A_P12V_STBY_SCALED

CAP  I153  C9G18  [CAP_0402LF-47.0PF,50V,5%,COG,AA]
    2  GND                B  @BASEBOARD_FAB2_LIB.BASEBOARD_FAB2(SCH_1):GND
    1  A_PVNN_STBY_PCH_SENSOR      A  @BASEBOARD_FAB2_LIB.BASEBOARD_FAB2(SCH_1):A_PVNN_STBY_PCH_SENSOR

CAP_A  I61  C9G19  [CAP_A_0402V-0.1UF,16V,10%,X7R,A]
    1  P3V3_FB_ADC128_VCC      A  @BASEBOARD_FAB2_LIB.BASEBOARD_FAB2(SCH_1):P3V3_FB_ADC128_VCC
    2  GND                B  @BASEBOARD_FAB2_LIB.BASEBOARD_FAB2(SCH_1):GND

CAP  I86  C9G20  [CAP_0402LF-47.0PF,50V,5%,COG,AA]
    2  GND                B  @BASEBOARD_FAB2_LIB.BASEBOARD_FAB2(SCH_1):GND
    1  A_P3V3_STBY_SCALED      A  @BASEBOARD_FAB2_LIB.BASEBOARD_FAB2(SCH_1):A_P3V3_STBY_SCALED

CAP  I68  C9G21  [CAP_0402LF-47.0PF,50V,5%,COG,AA]
    2  GND                B  @BASEBOARD_FAB2_LIB.BASEBOARD_FAB2(SCH_1):GND
    1  A_P5V_STBY_SCALED      A  @BASEBOARD_FAB2_LIB.BASEBOARD_FAB2(SCH_1):A_P5V_STBY_SCALED

CAP  I108  C9G22  [CAP_0402LF-10.0PF,50V,5%,COG,AA]
    2  GND                B  @BASEBOARD_FAB2_LIB.BASEBOARD_FAB2(SCH_1):GND
    1  A_P3V_BAT_SCALED      A  @BASEBOARD_FAB2_LIB.BASEBOARD_FAB2(SCH_1):A_P3V_BAT_SCALED

CAP_A  I177  C9L1   [CAP_A_0402V-0.01UF,25V,10%,X7RA]
    1  M_M_VREF           A  @BASEBOARD_FAB2_LIB.BASEBOARD_FAB2(SCH_1):M_M_VREF
    2  GND                B  @BASEBOARD_FAB2_LIB.BASEBOARD_FAB2(SCH_1):GND

CAPP  I78  C9L2   [CAPP_3018-470UF,2.5V,20%,ALUM,A]
    1  PVDDQ_KLM          A  @BASEBOARD_FAB2_LIB.BASEBOARD_FAB2(SCH_1):PVDDQ_KLM
    2  GND                B  @BASEBOARD_FAB2_LIB.BASEBOARD_FAB2(SCH_1):GND

CAP_A  I46  C9L3   [CAP_A_0402V-0.01UF,25V,10%,X7RA]
    1  M_M_CPU_VREF       A  @BASEBOARD_FAB2_LIB.BASEBOARD_FAB2(SCH_1):M_M_CPU_VREF
    2  GND                B  @BASEBOARD_FAB2_LIB.BASEBOARD_FAB2(SCH_1):GND

CAPP  I77  C9L4   [CAPP_3018-470UF,2.5V,20%,ALUM,A]
    1  PVDDQ_KLM          A  @BASEBOARD_FAB2_LIB.BASEBOARD_FAB2(SCH_1):PVDDQ_KLM
    2  GND                B  @BASEBOARD_FAB2_LIB.BASEBOARD_FAB2(SCH_1):GND

CAP  I80  C9L5   [CAP_0805-10UF,16V,10%,X6S,C953A]
    1  VR_FET_SW_P12V_STBY_PVDDQ_KLM      A  @BASEBOARD_FAB2_LIB.BASEBOARD_FAB2(SCH_1):VR_FET_SW_P12V_STBY_PVDDQ_KLM
    2  GND                B  @BASEBOARD_FAB2_LIB.BASEBOARD_FAB2(SCH_1):GND

CAP  I47  C9L6   [CAP_0805-10UF,16V,10%,X6S,C953A]
    1  VR_FET_SW_P12V_STBY_PVDDQ_KLM      A  @BASEBOARD_FAB2_LIB.BASEBOARD_FAB2(SCH_1):VR_FET_SW_P12V_STBY_PVDDQ_KLM
    2  GND                B  @BASEBOARD_FAB2_LIB.BASEBOARD_FAB2(SCH_1):GND

CAP_A  I181  C9L7   [CAP_A_0402V-0.01UF,25V,10%,X7RA]
    1  M_L_VREF           A  @BASEBOARD_FAB2_LIB.BASEBOARD_FAB2(SCH_1):M_L_VREF
    2  GND                B  @BASEBOARD_FAB2_LIB.BASEBOARD_FAB2(SCH_1):GND

CAP_A  I30  C9L8   [CAP_A_0402V-0.01UF,25V,10%,X7RA]
    1  M_L_CPU_VREF       A  @BASEBOARD_FAB2_LIB.BASEBOARD_FAB2(SCH_1):M_L_CPU_VREF
    2  GND                B  @BASEBOARD_FAB2_LIB.BASEBOARD_FAB2(SCH_1):GND

CAPP  I75  C9L9   [CAPP_3018-470UF,2.5V,20%,ALUM,A]
    1  PVDDQ_KLM          A  @BASEBOARD_FAB2_LIB.BASEBOARD_FAB2(SCH_1):PVDDQ_KLM
    2  GND                B  @BASEBOARD_FAB2_LIB.BASEBOARD_FAB2(SCH_1):GND

CAP  I46  C9L10  [CAP_0805-10UF,16V,10%,X6S,C953A]
    1  VR_FET_SW_P12V_STBY_PVDDQ_KLM      A  @BASEBOARD_FAB2_LIB.BASEBOARD_FAB2(SCH_1):VR_FET_SW_P12V_STBY_PVDDQ_KLM
    2  GND                B  @BASEBOARD_FAB2_LIB.BASEBOARD_FAB2(SCH_1):GND

CAP  I45  C9L11  [CAP_0805-10UF,16V,10%,X6S,C953A]
    1  VR_FET_SW_P12V_STBY_PVDDQ_KLM      A  @BASEBOARD_FAB2_LIB.BASEBOARD_FAB2(SCH_1):VR_FET_SW_P12V_STBY_PVDDQ_KLM
    2  GND                B  @BASEBOARD_FAB2_LIB.BASEBOARD_FAB2(SCH_1):GND

CAPP  I76  C9L12  [CAPP_3018-470UF,2.5V,20%,ALUM,A]
    1  PVDDQ_KLM          A  @BASEBOARD_FAB2_LIB.BASEBOARD_FAB2(SCH_1):PVDDQ_KLM
    2  GND                B  @BASEBOARD_FAB2_LIB.BASEBOARD_FAB2(SCH_1):GND

CAP  I81  C9L13  [CAP_0805-10UF,16V,10%,X6S,C953A]
    1  VR_FET_SW_P12V_STBY_PVDDQ_KLM      A  @BASEBOARD_FAB2_LIB.BASEBOARD_FAB2(SCH_1):VR_FET_SW_P12V_STBY_PVDDQ_KLM
    2  GND                B  @BASEBOARD_FAB2_LIB.BASEBOARD_FAB2(SCH_1):GND

CAP  I84  C9L14  [CAP_0805-10UF,16V,10%,X6S,C953A]
    1  VR_FET_SW_P12V_STBY_PVDDQ_KLM      A  @BASEBOARD_FAB2_LIB.BASEBOARD_FAB2(SCH_1):VR_FET_SW_P12V_STBY_PVDDQ_KLM
    2  GND                B  @BASEBOARD_FAB2_LIB.BASEBOARD_FAB2(SCH_1):GND

CAP_A  I4   C9M1   [CAP_A_0402V-0.01UF,25V,10%,X7RA]
    1  M_K_VREF           A  @BASEBOARD_FAB2_LIB.BASEBOARD_FAB2(SCH_1):M_K_VREF
    2  GND                B  @BASEBOARD_FAB2_LIB.BASEBOARD_FAB2(SCH_1):GND

CAP_A  I15  C9M2   [CAP_A_0402V-0.01UF,25V,10%,X7RA]
    1  M_K_CPU_VREF       A  @BASEBOARD_FAB2_LIB.BASEBOARD_FAB2(SCH_1):M_K_CPU_VREF
    2  GND                B  @BASEBOARD_FAB2_LIB.BASEBOARD_FAB2(SCH_1):GND

CAPP  I99  C9M3   [CAPP_3018-68UF,16V,20%,TANT,72A]
    1  P12V_STBY          A  @BASEBOARD_FAB2_LIB.BASEBOARD_FAB2(SCH_1):P12V_STBY
    2  GND                B  @BASEBOARD_FAB2_LIB.BASEBOARD_FAB2(SCH_1):GND

CAP  I27  C9M4   [CAP_0805-10UF,16V,10%,X6S,C953A]
    1  P12V_FAN           A  @BASEBOARD_FAB2_LIB.BASEBOARD_FAB2(SCH_1):P12V_FAN
    2  GND                B  @BASEBOARD_FAB2_LIB.BASEBOARD_FAB2(SCH_1):GND

CAP_A  I26  C9M5   [CAP_A_0402V-0.1UF,16V,10%,X7R,A]
    1  P12V_FAN           A  @BASEBOARD_FAB2_LIB.BASEBOARD_FAB2(SCH_1):P12V_FAN
    2  GND                B  @BASEBOARD_FAB2_LIB.BASEBOARD_FAB2(SCH_1):GND

CAP_A  I67  C9M6   [CAP_A_0402V-0.1UF,16V,10%,X7R,A]
    1  P5V_STBY           A  @BASEBOARD_FAB2_LIB.BASEBOARD_FAB2(SCH_1):P5V_STBY
    2  GND                B  @BASEBOARD_FAB2_LIB.BASEBOARD_FAB2(SCH_1):GND

CAP_A  I12  C9M7   [CAP_A_0402V-0.1UF,16V,10%,X7R,A]
    1  P3V3_STBY          A  @BASEBOARD_FAB2_LIB.BASEBOARD_FAB2(SCH_1):P3V3_STBY
    2  GND                B  @BASEBOARD_FAB2_LIB.BASEBOARD_FAB2(SCH_1):GND

CAP_A  I10  C9M8   [CAP_A_0402V-0.1UF,16V,10%,X7R,A]
    1  PVCCIO_CPU1        A  @BASEBOARD_FAB2_LIB.BASEBOARD_FAB2(SCH_1):PVCCIO_CPU1
    2  GND                B  @BASEBOARD_FAB2_LIB.BASEBOARD_FAB2(SCH_1):GND

CAP_A  I76  C9M9   [CAP_A_0402V-0.1UF,16V,10%,X7R,A]
    1  P12V_STBY          A  @BASEBOARD_FAB2_LIB.BASEBOARD_FAB2(SCH_1):P12V_STBY
    2  GND                B  @BASEBOARD_FAB2_LIB.BASEBOARD_FAB2(SCH_1):GND

CAP  I74  C9M10  [CAP_0805-10UF,16V,10%,X6S,C953A]
    1  P12V_STBY          A  @BASEBOARD_FAB2_LIB.BASEBOARD_FAB2(SCH_1):P12V_STBY
    2  GND                B  @BASEBOARD_FAB2_LIB.BASEBOARD_FAB2(SCH_1):GND

CAP_A  I92  C9M11  [CAP_A_0402V-0.1UF,16V,10%,X7R,A]
    1  VR_PVDDQ_KLM_AIINSEN      A  @BASEBOARD_FAB2_LIB.BASEBOARD_FAB2(SCH_1):VR_PVDDQ_KLM_AIINSEN
    2  GND                B  @BASEBOARD_FAB2_LIB.BASEBOARD_FAB2(SCH_1):GND

CAP_0402  I14  C9N1   [CAP_0402-0.22UF,16V,10%,X7R,A3A]
    2  P3E_CPU1_PE3_MP_TXP<10>      B  @BASEBOARD_FAB2_LIB.BASEBOARD_FAB2(SCH_1):P3E_CPU1_PE3_MP_TXP<10>
    1  P3E_CPU1_PE3_MP_C_TXP<10>      A  @BASEBOARD_FAB2_LIB.BASEBOARD_FAB2(SCH_1):P3E_CPU1_PE3_MP_C_TXP<10>

CAP_0402  I15  C9N2   [CAP_0402-0.22UF,16V,10%,X7R,A3A]
    2  P3E_CPU1_PE3_MP_TXN<10>      B  @BASEBOARD_FAB2_LIB.BASEBOARD_FAB2(SCH_1):P3E_CPU1_PE3_MP_TXN<10>
    1  P3E_CPU1_PE3_MP_C_TXN<10>      A  @BASEBOARD_FAB2_LIB.BASEBOARD_FAB2(SCH_1):P3E_CPU1_PE3_MP_C_TXN<10>

CAP_0402  I51  C9N3   [CAP_0402-0.22UF,16V,10%,X7R,A3A]
    2  P3E_CPU1_PE3_MP_TXN<11>      B  @BASEBOARD_FAB2_LIB.BASEBOARD_FAB2(SCH_1):P3E_CPU1_PE3_MP_TXN<11>
    1  P3E_CPU1_PE3_MP_C_TXN<11>      A  @BASEBOARD_FAB2_LIB.BASEBOARD_FAB2(SCH_1):P3E_CPU1_PE3_MP_C_TXN<11>

CAP_0402  I55  C9N4   [CAP_0402-0.22UF,16V,10%,X7R,A3A]
    2  P3E_CPU1_PE3_MP_TXP<11>      B  @BASEBOARD_FAB2_LIB.BASEBOARD_FAB2(SCH_1):P3E_CPU1_PE3_MP_TXP<11>
    1  P3E_CPU1_PE3_MP_C_TXP<11>      A  @BASEBOARD_FAB2_LIB.BASEBOARD_FAB2(SCH_1):P3E_CPU1_PE3_MP_C_TXP<11>

CAP_0402  I83  C9N5   [CAP_0402-0.22UF,16V,10%,X7R,A3A]
    2  P3E_CPU1_PE3_MP_TXP<13>      B  @BASEBOARD_FAB2_LIB.BASEBOARD_FAB2(SCH_1):P3E_CPU1_PE3_MP_TXP<13>
    1  P3E_CPU1_PE3_MP_C_TXP<13>      A  @BASEBOARD_FAB2_LIB.BASEBOARD_FAB2(SCH_1):P3E_CPU1_PE3_MP_C_TXP<13>

CAP_0402  I81  C9N6   [CAP_0402-0.22UF,16V,10%,X7R,A3A]
    2  P3E_CPU1_PE3_MP_TXN<13>      B  @BASEBOARD_FAB2_LIB.BASEBOARD_FAB2(SCH_1):P3E_CPU1_PE3_MP_TXN<13>
    1  P3E_CPU1_PE3_MP_C_TXN<13>      A  @BASEBOARD_FAB2_LIB.BASEBOARD_FAB2(SCH_1):P3E_CPU1_PE3_MP_C_TXN<13>

CAP_0402  I54  C9N7   [CAP_0402-0.22UF,16V,10%,X7R,A3A]
    2  P3E_CPU1_PE3_MP_TXP<15>      B  @BASEBOARD_FAB2_LIB.BASEBOARD_FAB2(SCH_1):P3E_CPU1_PE3_MP_TXP<15>
    1  P3E_CPU1_PE3_MP_C_TXP<15>      A  @BASEBOARD_FAB2_LIB.BASEBOARD_FAB2(SCH_1):P3E_CPU1_PE3_MP_C_TXP<15>

CAP_0402  I50  C9N8   [CAP_0402-0.22UF,16V,10%,X7R,A3A]
    2  P3E_CPU1_PE3_MP_TXN<14>      B  @BASEBOARD_FAB2_LIB.BASEBOARD_FAB2(SCH_1):P3E_CPU1_PE3_MP_TXN<14>
    1  P3E_CPU1_PE3_MP_C_TXN<14>      A  @BASEBOARD_FAB2_LIB.BASEBOARD_FAB2(SCH_1):P3E_CPU1_PE3_MP_C_TXN<14>

CAP_0402  I49  C9N9   [CAP_0402-0.22UF,16V,10%,X7R,A3A]
    2  P3E_CPU1_PE3_MP_TXN<15>      B  @BASEBOARD_FAB2_LIB.BASEBOARD_FAB2(SCH_1):P3E_CPU1_PE3_MP_TXN<15>
    1  P3E_CPU1_PE3_MP_C_TXN<15>      A  @BASEBOARD_FAB2_LIB.BASEBOARD_FAB2(SCH_1):P3E_CPU1_PE3_MP_C_TXN<15>

CAP_0402  I53  C9N10  [CAP_0402-0.22UF,16V,10%,X7R,A3A]
    2  P3E_CPU1_PE3_MP_TXP<14>      B  @BASEBOARD_FAB2_LIB.BASEBOARD_FAB2(SCH_1):P3E_CPU1_PE3_MP_TXP<14>
    1  P3E_CPU1_PE3_MP_C_TXP<14>      A  @BASEBOARD_FAB2_LIB.BASEBOARD_FAB2(SCH_1):P3E_CPU1_PE3_MP_C_TXP<14>

CAPP  I12  C9N11  [CAPP_3018-470UF,2.5V,20%,ALUM,A]
    1  PVSA_CPU1          A  @BASEBOARD_FAB2_LIB.BASEBOARD_FAB2(SCH_1):PVSA_CPU1
    2  GND                B  @BASEBOARD_FAB2_LIB.BASEBOARD_FAB2(SCH_1):GND

CAP_0402  I16  C9N12  [CAP_0402-0.22UF,16V,10%,X7R,A3A]
    2  P3E_CPU1_PE3_MP_TXP<9>      B  @BASEBOARD_FAB2_LIB.BASEBOARD_FAB2(SCH_1):P3E_CPU1_PE3_MP_TXP<9>
    1  P3E_CPU1_PE3_MP_C_TXP<9>      A  @BASEBOARD_FAB2_LIB.BASEBOARD_FAB2(SCH_1):P3E_CPU1_PE3_MP_C_TXP<9>

CAP  I35  C9N13  [CAP_0805-10UF,16V,10%,X6S,C953A]
    1  VR_FET_SW_P12V_STBY_PVCCIN_CPU1      A  @BASEBOARD_FAB2_LIB.BASEBOARD_FAB2(SCH_1):VR_FET_SW_P12V_STBY_PVCCIN_CPU1
    2  GND                B  @BASEBOARD_FAB2_LIB.BASEBOARD_FAB2(SCH_1):GND

CAP_0402  I56  C9N14  [CAP_0402-0.22UF,16V,10%,X7R,A3A]
    2  P3E_CPU1_PE3_MP_TXP<12>      B  @BASEBOARD_FAB2_LIB.BASEBOARD_FAB2(SCH_1):P3E_CPU1_PE3_MP_TXP<12>
    1  P3E_CPU1_PE3_MP_C_TXP<12>      A  @BASEBOARD_FAB2_LIB.BASEBOARD_FAB2(SCH_1):P3E_CPU1_PE3_MP_C_TXP<12>

CAP_0402  I13  C9N15  [CAP_0402-0.22UF,16V,10%,X7R,A3A]
    2  P3E_CPU1_PE3_MP_TXN<9>      B  @BASEBOARD_FAB2_LIB.BASEBOARD_FAB2(SCH_1):P3E_CPU1_PE3_MP_TXN<9>
    1  P3E_CPU1_PE3_MP_C_TXN<9>      A  @BASEBOARD_FAB2_LIB.BASEBOARD_FAB2(SCH_1):P3E_CPU1_PE3_MP_C_TXN<9>

CAP_0402  I52  C9N16  [CAP_0402-0.22UF,16V,10%,X7R,A3A]
    2  P3E_CPU1_PE3_MP_TXN<12>      B  @BASEBOARD_FAB2_LIB.BASEBOARD_FAB2(SCH_1):P3E_CPU1_PE3_MP_TXN<12>
    1  P3E_CPU1_PE3_MP_C_TXN<12>      A  @BASEBOARD_FAB2_LIB.BASEBOARD_FAB2(SCH_1):P3E_CPU1_PE3_MP_C_TXN<12>

CAP_0402  I12  C9N17  [CAP_0402-0.22UF,16V,10%,X7R,A3A]
    2  P3E_CPU1_PE3_MP_TXP<8>      B  @BASEBOARD_FAB2_LIB.BASEBOARD_FAB2(SCH_1):P3E_CPU1_PE3_MP_TXP<8>
    1  P3E_CPU1_PE3_MP_C_TXP<8>      A  @BASEBOARD_FAB2_LIB.BASEBOARD_FAB2(SCH_1):P3E_CPU1_PE3_MP_C_TXP<8>

CAP_0402  I9   C9N18  [CAP_0402-0.22UF,16V,10%,X7R,A3A]
    2  P3E_CPU1_PE3_MP_TXN<8>      B  @BASEBOARD_FAB2_LIB.BASEBOARD_FAB2(SCH_1):P3E_CPU1_PE3_MP_TXN<8>
    1  P3E_CPU1_PE3_MP_C_TXN<8>      A  @BASEBOARD_FAB2_LIB.BASEBOARD_FAB2(SCH_1):P3E_CPU1_PE3_MP_C_TXN<8>

CAP  I36  C9N19  [CAP_0805-10UF,16V,10%,X6S,C953A]
    1  VR_FET_SW_P12V_STBY_PVCCIN_CPU1      A  @BASEBOARD_FAB2_LIB.BASEBOARD_FAB2(SCH_1):VR_FET_SW_P12V_STBY_PVCCIN_CPU1
    2  GND                B  @BASEBOARD_FAB2_LIB.BASEBOARD_FAB2(SCH_1):GND

CAPP  I14  C9N20  [CAPP_3018-470UF,2.5V,20%,ALUM,A]
    1  PVSA_CPU1          A  @BASEBOARD_FAB2_LIB.BASEBOARD_FAB2(SCH_1):PVSA_CPU1
    2  GND                B  @BASEBOARD_FAB2_LIB.BASEBOARD_FAB2(SCH_1):GND

CAP  I38  C9N21  [CAP_0805-10UF,16V,10%,X6S,C953A]
    1  VR_FET_SW_P12V_STBY_PVCCIN_CPU1      A  @BASEBOARD_FAB2_LIB.BASEBOARD_FAB2(SCH_1):VR_FET_SW_P12V_STBY_PVCCIN_CPU1
    2  GND                B  @BASEBOARD_FAB2_LIB.BASEBOARD_FAB2(SCH_1):GND

CAP_A  I44  C9N22  [CAP_A_0603V-22.0UF,4V,20%,X6S,A]
    1  PVSA_CPU1          A  @BASEBOARD_FAB2_LIB.BASEBOARD_FAB2(SCH_1):PVSA_CPU1
    2  GND                B  @BASEBOARD_FAB2_LIB.BASEBOARD_FAB2(SCH_1):GND

CAPP  I24  C9N24  [CAPP_3018-470UF,2.5V,20%,ALUM,A]
    1  PVCCIN_CPU1        A  @BASEBOARD_FAB2_LIB.BASEBOARD_FAB2(SCH_1):PVCCIN_CPU1
    2  GND                B  @BASEBOARD_FAB2_LIB.BASEBOARD_FAB2(SCH_1):GND

CAP  I8   C9N25  [CAP_0805-10UF,16V,10%,X6S,C953A]
    1  VR_FET_SW_P12V_STBY_PVCCIN_CPU1      A  @BASEBOARD_FAB2_LIB.BASEBOARD_FAB2(SCH_1):VR_FET_SW_P12V_STBY_PVCCIN_CPU1
    2  GND                B  @BASEBOARD_FAB2_LIB.BASEBOARD_FAB2(SCH_1):GND

CAP  I7   C9N26  [CAP_0805-10UF,16V,10%,X6S,C953A]
    1  VR_FET_SW_P12V_STBY_PVCCIN_CPU1      A  @BASEBOARD_FAB2_LIB.BASEBOARD_FAB2(SCH_1):VR_FET_SW_P12V_STBY_PVCCIN_CPU1
    2  GND                B  @BASEBOARD_FAB2_LIB.BASEBOARD_FAB2(SCH_1):GND

CAP  I5   C9N27  [CAP_0805-10UF,16V,10%,X6S,C953A]
    1  VR_FET_SW_P12V_STBY_PVCCIN_CPU1      A  @BASEBOARD_FAB2_LIB.BASEBOARD_FAB2(SCH_1):VR_FET_SW_P12V_STBY_PVCCIN_CPU1
    2  GND                B  @BASEBOARD_FAB2_LIB.BASEBOARD_FAB2(SCH_1):GND

CAP  I59  C9P1   [CAP_0805-10UF,16V,10%,X6S,C953A]
    1  VR_FET_SW_P12V_STBY_PVCCIN_CPU1      A  @BASEBOARD_FAB2_LIB.BASEBOARD_FAB2(SCH_1):VR_FET_SW_P12V_STBY_PVCCIN_CPU1
    2  GND                B  @BASEBOARD_FAB2_LIB.BASEBOARD_FAB2(SCH_1):GND

CAP  I60  C9P2   [CAP_0805-10UF,16V,10%,X6S,C953A]
    1  VR_FET_SW_P12V_STBY_PVCCIN_CPU1      A  @BASEBOARD_FAB2_LIB.BASEBOARD_FAB2(SCH_1):VR_FET_SW_P12V_STBY_PVCCIN_CPU1
    2  GND                B  @BASEBOARD_FAB2_LIB.BASEBOARD_FAB2(SCH_1):GND

CAP_A  I59  C9P3   [CAP_A_0603V-22.0UF,4V,20%,X6S,A]
    1  PVCCIN_CPU1        A  @BASEBOARD_FAB2_LIB.BASEBOARD_FAB2(SCH_1):PVCCIN_CPU1
    2  GND                B  @BASEBOARD_FAB2_LIB.BASEBOARD_FAB2(SCH_1):GND

CAP  I53  C9P4   [CAP_0805-10UF,16V,10%,X6S,C953A]
    1  VR_FET_SW_P12V_STBY_PVCCIN_CPU1      A  @BASEBOARD_FAB2_LIB.BASEBOARD_FAB2(SCH_1):VR_FET_SW_P12V_STBY_PVCCIN_CPU1
    2  GND                B  @BASEBOARD_FAB2_LIB.BASEBOARD_FAB2(SCH_1):GND

CAPP  I14  C9P5   [CAPP_3018-470UF,2.5V,20%,ALUM,A]
    1  PVCCIN_CPU1        A  @BASEBOARD_FAB2_LIB.BASEBOARD_FAB2(SCH_1):PVCCIN_CPU1
    2  GND                B  @BASEBOARD_FAB2_LIB.BASEBOARD_FAB2(SCH_1):GND

CAP_A  I185  C9P6   [CAP_A_0402V-0.1UF,16V,10%,X7R,A]
    1  P12V_STBY          A  @BASEBOARD_FAB2_LIB.BASEBOARD_FAB2(SCH_1):P12V_STBY
    2  AGND_HSC           B  @BASEBOARD_FAB2_LIB.BASEBOARD_FAB2(SCH_1):AGND_HSC

CAP  I54  C9P7   [CAP_0805-10UF,16V,10%,X6S,C953A]
    1  VR_FET_SW_P12V_STBY_PVCCIN_CPU1      A  @BASEBOARD_FAB2_LIB.BASEBOARD_FAB2(SCH_1):VR_FET_SW_P12V_STBY_PVCCIN_CPU1
    2  GND                B  @BASEBOARD_FAB2_LIB.BASEBOARD_FAB2(SCH_1):GND

CAPP  I12  C9P8   [CAPP_3018-470UF,2.5V,20%,ALUM,A]
    1  PVCCIN_CPU1        A  @BASEBOARD_FAB2_LIB.BASEBOARD_FAB2(SCH_1):PVCCIN_CPU1
    2  GND                B  @BASEBOARD_FAB2_LIB.BASEBOARD_FAB2(SCH_1):GND

CAP  I55  C9P9   [CAP_0805-10UF,16V,10%,X6S,C953A]
    1  VR_FET_SW_P12V_STBY_PVCCIN_CPU1      A  @BASEBOARD_FAB2_LIB.BASEBOARD_FAB2(SCH_1):VR_FET_SW_P12V_STBY_PVCCIN_CPU1
    2  GND                B  @BASEBOARD_FAB2_LIB.BASEBOARD_FAB2(SCH_1):GND

CAP_A  I66  C9P10  [CAP_A_0603V-22.0UF,4V,20%,X6S,A]
    1  PVCCIN_CPU1        A  @BASEBOARD_FAB2_LIB.BASEBOARD_FAB2(SCH_1):PVCCIN_CPU1
    2  GND                B  @BASEBOARD_FAB2_LIB.BASEBOARD_FAB2(SCH_1):GND

CAP_A  I201  C9P11  [CAP_A_0402V-0.1UF,16V,10%,X7R,A]
    1  P3V3_STBY          A  @BASEBOARD_FAB2_LIB.BASEBOARD_FAB2(SCH_1):P3V3_STBY
    2  GND                B  @BASEBOARD_FAB2_LIB.BASEBOARD_FAB2(SCH_1):GND

CAP_A  I67  C9P12  [CAP_A_0402V-0.1UF,16V,10%,EMPTA]
    1  A_HSC_VOUT         A  @BASEBOARD_FAB2_LIB.BASEBOARD_FAB2(SCH_1):A_HSC_VOUT
    2  AGND_HSC           B  @BASEBOARD_FAB2_LIB.BASEBOARD_FAB2(SCH_1):AGND_HSC

CAP  I24  C9P14  [CAP_0603LF-0.033UF,50V,10%,X7RA]
    1  A_HSC_TIMER        A  @BASEBOARD_FAB2_LIB.BASEBOARD_FAB2(SCH_1):A_HSC_TIMER
    2  AGND_HSC           B  @BASEBOARD_FAB2_LIB.BASEBOARD_FAB2(SCH_1):AGND_HSC

CAP_A  I105  C9P15  [CAP_A_0402V-0.1UF,16V,10%,X7R,A]
    1  A_HSC_ISET         A  @BASEBOARD_FAB2_LIB.BASEBOARD_FAB2(SCH_1):A_HSC_ISET
    2  AGND_HSC           B  @BASEBOARD_FAB2_LIB.BASEBOARD_FAB2(SCH_1):AGND_HSC

CAP_A  I40  C9P16  [CAP_A_0402V-0.1UF,16V,10%,EMPTA]
    1  A_HSC_MOP          A  @BASEBOARD_FAB2_LIB.BASEBOARD_FAB2(SCH_1):A_HSC_MOP
    2  AGND_HSC           B  @BASEBOARD_FAB2_LIB.BASEBOARD_FAB2(SCH_1):AGND_HSC

CAP_A  I36  C9P17  [CAP_A_0402V-0.1UF,16V,10%,EMPTA]
    1  A_HSC_MON          A  @BASEBOARD_FAB2_LIB.BASEBOARD_FAB2(SCH_1):A_HSC_MON
    2  AGND_HSC           B  @BASEBOARD_FAB2_LIB.BASEBOARD_FAB2(SCH_1):AGND_HSC

CAPP  I30  C9P18  [CAPP_3018-470UF,2.5V,20%,ALUM,A]
    1  PVCCIN_CPU1        A  @BASEBOARD_FAB2_LIB.BASEBOARD_FAB2(SCH_1):PVCCIN_CPU1
    2  GND                B  @BASEBOARD_FAB2_LIB.BASEBOARD_FAB2(SCH_1):GND

CAP_A  I55  C9P20  [CAP_A_0603V-22.0UF,4V,20%,X6S,A]
    1  PVCCIN_CPU1        A  @BASEBOARD_FAB2_LIB.BASEBOARD_FAB2(SCH_1):PVCCIN_CPU1
    2  GND                B  @BASEBOARD_FAB2_LIB.BASEBOARD_FAB2(SCH_1):GND

CAP  I50  C9P22  [CAP_0805-10UF,16V,10%,X6S,C953A]
    1  VR_FET_SW_P12V_STBY_PVCCIN_CPU1      A  @BASEBOARD_FAB2_LIB.BASEBOARD_FAB2(SCH_1):VR_FET_SW_P12V_STBY_PVCCIN_CPU1
    2  GND                B  @BASEBOARD_FAB2_LIB.BASEBOARD_FAB2(SCH_1):GND

CAPP  I28  C9P23  [CAPP_3018-470UF,2.5V,20%,ALUM,A]
    1  PVCCIN_CPU1        A  @BASEBOARD_FAB2_LIB.BASEBOARD_FAB2(SCH_1):PVCCIN_CPU1
    2  GND                B  @BASEBOARD_FAB2_LIB.BASEBOARD_FAB2(SCH_1):GND

CAP  I58  C9P24  [CAP_0805-10UF,16V,10%,X6S,C953A]
    1  VR_FET_SW_P12V_STBY_PVCCIN_CPU1      A  @BASEBOARD_FAB2_LIB.BASEBOARD_FAB2(SCH_1):VR_FET_SW_P12V_STBY_PVCCIN_CPU1
    2  GND                B  @BASEBOARD_FAB2_LIB.BASEBOARD_FAB2(SCH_1):GND

CAP  I51  C9P25  [CAP_0805-10UF,16V,10%,X6S,C953A]
    1  VR_FET_SW_P12V_STBY_PVCCIN_CPU1      A  @BASEBOARD_FAB2_LIB.BASEBOARD_FAB2(SCH_1):VR_FET_SW_P12V_STBY_PVCCIN_CPU1
    2  GND                B  @BASEBOARD_FAB2_LIB.BASEBOARD_FAB2(SCH_1):GND

CAP  I54  C9P26  [CAP_0805-10UF,16V,10%,X6S,C953A]
    1  VR_FET_SW_P12V_STBY_PVCCIN_CPU1      A  @BASEBOARD_FAB2_LIB.BASEBOARD_FAB2(SCH_1):VR_FET_SW_P12V_STBY_PVCCIN_CPU1
    2  GND                B  @BASEBOARD_FAB2_LIB.BASEBOARD_FAB2(SCH_1):GND

CAP_A  I67  C9R2   [CAP_A_0603V-22.0UF,4V,20%,X6S,A]
    1  PVCCIN_CPU1        A  @BASEBOARD_FAB2_LIB.BASEBOARD_FAB2(SCH_1):PVCCIN_CPU1
    2  GND                B  @BASEBOARD_FAB2_LIB.BASEBOARD_FAB2(SCH_1):GND

CAPP  I26  C9R3   [CAPP_3018-470UF,2.5V,20%,ALUM,A]
    1  PVCCIN_CPU1        A  @BASEBOARD_FAB2_LIB.BASEBOARD_FAB2(SCH_1):PVCCIN_CPU1
    2  GND                B  @BASEBOARD_FAB2_LIB.BASEBOARD_FAB2(SCH_1):GND

CAP  I31  C9R5   [CAP_0805-10UF,16V,10%,X6S,C953A]
    1  P12V_PSU           A  @BASEBOARD_FAB2_LIB.BASEBOARD_FAB2(SCH_1):P12V_PSU
    2  GND                B  @BASEBOARD_FAB2_LIB.BASEBOARD_FAB2(SCH_1):GND

CAP_A  I37  C9R6   [CAP_A_0402V-0.1UF,16V,10%,X7R,A]
    1  P12V_PSU           A  @BASEBOARD_FAB2_LIB.BASEBOARD_FAB2(SCH_1):P12V_PSU
    2  GND                B  @BASEBOARD_FAB2_LIB.BASEBOARD_FAB2(SCH_1):GND

CAP  I43  C9R7   [CAP_0805-10UF,16V,10%,X6S,C953A]
    1  VR_FET_SW_P12V_STBY_PVCCIN_CPU1      A  @BASEBOARD_FAB2_LIB.BASEBOARD_FAB2(SCH_1):VR_FET_SW_P12V_STBY_PVCCIN_CPU1
    2  GND                B  @BASEBOARD_FAB2_LIB.BASEBOARD_FAB2(SCH_1):GND

CAP_A  I8   C9R8   [CAP_A_0603V-22.0UF,4V,20%,X6S,A]
    1  PVCCIN_CPU1        A  @BASEBOARD_FAB2_LIB.BASEBOARD_FAB2(SCH_1):PVCCIN_CPU1
    2  GND                B  @BASEBOARD_FAB2_LIB.BASEBOARD_FAB2(SCH_1):GND

CAPP  I25  C9R9   [CAPP_3018-470UF,2.5V,20%,ALUM,A]
    1  PVCCIN_CPU1        A  @BASEBOARD_FAB2_LIB.BASEBOARD_FAB2(SCH_1):PVCCIN_CPU1
    2  GND                B  @BASEBOARD_FAB2_LIB.BASEBOARD_FAB2(SCH_1):GND

CAP  I44  C9R10  [CAP_0805-10UF,16V,10%,X6S,C953A]
    1  VR_FET_SW_P12V_STBY_PVCCIN_CPU1      A  @BASEBOARD_FAB2_LIB.BASEBOARD_FAB2(SCH_1):VR_FET_SW_P12V_STBY_PVCCIN_CPU1
    2  GND                B  @BASEBOARD_FAB2_LIB.BASEBOARD_FAB2(SCH_1):GND

CAP  I48  C9R11  [CAP_0805-10UF,16V,10%,X6S,C953A]
    1  VR_FET_SW_P12V_STBY_PVCCIN_CPU1      A  @BASEBOARD_FAB2_LIB.BASEBOARD_FAB2(SCH_1):VR_FET_SW_P12V_STBY_PVCCIN_CPU1
    2  GND                B  @BASEBOARD_FAB2_LIB.BASEBOARD_FAB2(SCH_1):GND

CAP_A  I36  C9R12  [CAP_A_0402V-0.1UF,16V,10%,X7R,A]
    1  P12V_PSU           A  @BASEBOARD_FAB2_LIB.BASEBOARD_FAB2(SCH_1):P12V_PSU
    2  GND                B  @BASEBOARD_FAB2_LIB.BASEBOARD_FAB2(SCH_1):GND

CAP_A  I42  C9R13  [CAP_A_0402V-0.1UF,16V,10%,X7R,A]
    1  P3V3_STBY          A  @BASEBOARD_FAB2_LIB.BASEBOARD_FAB2(SCH_1):P3V3_STBY
    2  GND                B  @BASEBOARD_FAB2_LIB.BASEBOARD_FAB2(SCH_1):GND

CAP_A  I41  C9R14  [CAP_A_0402V-0.1UF,16V,10%,X7R,A]
    1  P3V3_STBY          A  @BASEBOARD_FAB2_LIB.BASEBOARD_FAB2(SCH_1):P3V3_STBY
    2  GND                B  @BASEBOARD_FAB2_LIB.BASEBOARD_FAB2(SCH_1):GND

CAP_A  I137  C9T1   [CAP_A_0402V-0.01UF,25V,10%,X7RA]
    2  GND                B  @BASEBOARD_FAB2_LIB.BASEBOARD_FAB2(SCH_1):GND
    1  FAN_TACH1          A  @BASEBOARD_FAB2_LIB.BASEBOARD_FAB2(SCH_1):FAN_TACH1

CAPP  I111  C9T3   [CAPP_3018-68UF,16V,20%,TANT,72A]
    1  P12V_STBY          A  @BASEBOARD_FAB2_LIB.BASEBOARD_FAB2(SCH_1):P12V_STBY
    2  GND                B  @BASEBOARD_FAB2_LIB.BASEBOARD_FAB2(SCH_1):GND

CAP  I47  C9T4   [CAP_0805-10UF,16V,10%,X6S,C953A]
    1  VR_FET_SW_P12V_STBY_PVDDQ_GHJ      A  @BASEBOARD_FAB2_LIB.BASEBOARD_FAB2(SCH_1):VR_FET_SW_P12V_STBY_PVDDQ_GHJ
    2  GND                B  @BASEBOARD_FAB2_LIB.BASEBOARD_FAB2(SCH_1):GND

CAPP  I75  C9T5   [CAPP_3018-470UF,2.5V,20%,ALUM,A]
    1  PVDDQ_GHJ          A  @BASEBOARD_FAB2_LIB.BASEBOARD_FAB2(SCH_1):PVDDQ_GHJ
    2  GND                B  @BASEBOARD_FAB2_LIB.BASEBOARD_FAB2(SCH_1):GND

CAP  I81  C9T6   [CAP_0805-10UF,16V,10%,X6S,C953A]
    1  VR_FET_SW_P12V_STBY_PVDDQ_GHJ      A  @BASEBOARD_FAB2_LIB.BASEBOARD_FAB2(SCH_1):VR_FET_SW_P12V_STBY_PVDDQ_GHJ
    2  GND                B  @BASEBOARD_FAB2_LIB.BASEBOARD_FAB2(SCH_1):GND

CAP_A  I2   C9T7   [CAP_A_0402V-0.01UF,25V,10%,X7RA]
    1  M_G_VREF           A  @BASEBOARD_FAB2_LIB.BASEBOARD_FAB2(SCH_1):M_G_VREF
    2  GND                B  @BASEBOARD_FAB2_LIB.BASEBOARD_FAB2(SCH_1):GND

CAP  I70  C9T8   [CAP_0805-10UF,16V,10%,X7R,G106A]
    1  P12V_NVDIMM_GHJ      A  @BASEBOARD_FAB2_LIB.BASEBOARD_FAB2(SCH_1):P12V_NVDIMM_GHJ
    2  GND                B  @BASEBOARD_FAB2_LIB.BASEBOARD_FAB2(SCH_1):GND

CAP  I84  C9T9   [CAP_0805-10UF,16V,10%,X6S,C953A]
    1  VR_FET_SW_P12V_STBY_PVDDQ_GHJ      A  @BASEBOARD_FAB2_LIB.BASEBOARD_FAB2(SCH_1):VR_FET_SW_P12V_STBY_PVDDQ_GHJ
    2  GND                B  @BASEBOARD_FAB2_LIB.BASEBOARD_FAB2(SCH_1):GND

CAPP  I76  C9U2   [CAPP_3018-470UF,2.5V,20%,ALUM,A]
    1  PVDDQ_GHJ          A  @BASEBOARD_FAB2_LIB.BASEBOARD_FAB2(SCH_1):PVDDQ_GHJ
    2  GND                B  @BASEBOARD_FAB2_LIB.BASEBOARD_FAB2(SCH_1):GND

CAP  I80  C9U3   [CAP_0805-10UF,16V,10%,X6S,C953A]
    1  VR_FET_SW_P12V_STBY_PVDDQ_GHJ      A  @BASEBOARD_FAB2_LIB.BASEBOARD_FAB2(SCH_1):VR_FET_SW_P12V_STBY_PVDDQ_GHJ
    2  GND                B  @BASEBOARD_FAB2_LIB.BASEBOARD_FAB2(SCH_1):GND

CAP  I46  C9U4   [CAP_0805-10UF,16V,10%,X6S,C953A]
    1  VR_FET_SW_P12V_STBY_PVDDQ_GHJ      A  @BASEBOARD_FAB2_LIB.BASEBOARD_FAB2(SCH_1):VR_FET_SW_P12V_STBY_PVDDQ_GHJ
    2  GND                B  @BASEBOARD_FAB2_LIB.BASEBOARD_FAB2(SCH_1):GND

CAPP  I78  C9U5   [CAPP_3018-470UF,2.5V,20%,ALUM,A]
    1  PVDDQ_GHJ          A  @BASEBOARD_FAB2_LIB.BASEBOARD_FAB2(SCH_1):PVDDQ_GHJ
    2  GND                B  @BASEBOARD_FAB2_LIB.BASEBOARD_FAB2(SCH_1):GND

CAP  I45  C9U6   [CAP_0805-10UF,16V,10%,X6S,C953A]
    1  VR_FET_SW_P12V_STBY_PVDDQ_GHJ      A  @BASEBOARD_FAB2_LIB.BASEBOARD_FAB2(SCH_1):VR_FET_SW_P12V_STBY_PVDDQ_GHJ
    2  GND                B  @BASEBOARD_FAB2_LIB.BASEBOARD_FAB2(SCH_1):GND

CAP_A  I178  C9U7   [CAP_A_0402V-0.01UF,25V,10%,X7RA]
    1  M_H_VREF           A  @BASEBOARD_FAB2_LIB.BASEBOARD_FAB2(SCH_1):M_H_VREF
    2  GND                B  @BASEBOARD_FAB2_LIB.BASEBOARD_FAB2(SCH_1):GND

CAP  I76  C9U8   [CAP_0805-10UF,16V,10%,X7R,G106A]
    1  P12V_NVDIMM_GHJ      A  @BASEBOARD_FAB2_LIB.BASEBOARD_FAB2(SCH_1):P12V_NVDIMM_GHJ
    2  GND                B  @BASEBOARD_FAB2_LIB.BASEBOARD_FAB2(SCH_1):GND

CAPP  I77  C9U9   [CAPP_3018-470UF,2.5V,20%,ALUM,A]
    1  PVDDQ_GHJ          A  @BASEBOARD_FAB2_LIB.BASEBOARD_FAB2(SCH_1):PVDDQ_GHJ
    2  GND                B  @BASEBOARD_FAB2_LIB.BASEBOARD_FAB2(SCH_1):GND

CAP_A  I178  C9U10  [CAP_A_0402V-0.01UF,25V,10%,X7RA]
    1  M_J_VREF           A  @BASEBOARD_FAB2_LIB.BASEBOARD_FAB2(SCH_1):M_J_VREF
    2  GND                B  @BASEBOARD_FAB2_LIB.BASEBOARD_FAB2(SCH_1):GND

CAP  I73  C9U11  [CAP_0805-10UF,16V,10%,X7R,G106A]
    1  P12V_NVDIMM_GHJ      A  @BASEBOARD_FAB2_LIB.BASEBOARD_FAB2(SCH_1):P12V_NVDIMM_GHJ
    2  GND                B  @BASEBOARD_FAB2_LIB.BASEBOARD_FAB2(SCH_1):GND

CAP_A  I92  C9U12  [CAP_A_0402V-0.1UF,16V,10%,X7R,A]
    1  VR_PVDDQ_GHJ_AIINSEN      A  @BASEBOARD_FAB2_LIB.BASEBOARD_FAB2(SCH_1):VR_PVDDQ_GHJ_AIINSEN
    2  GND                B  @BASEBOARD_FAB2_LIB.BASEBOARD_FAB2(SCH_1):GND

DIODE_SM  I64  CR1B1  [DIODE_SM-SDMK0340L,EMPTY,H7179A]
    1  P5V_STBY           C  @BASEBOARD_FAB2_LIB.BASEBOARD_FAB2(SCH_1):P5V_STBY
    2  FAN_PWM_OUT_SYS1_R      A  @BASEBOARD_FAB2_LIB.BASEBOARD_FAB2(SCH_1):FAN_PWM_OUT_SYS1_R

DIODE_SM  I62  CR1B2  [DIODE_SM-SDMK0340L,IC,H71799-0A]
    2  FAN_TACH2_CPU1_D2      A  @BASEBOARD_FAB2_LIB.BASEBOARD_FAB2(SCH_1):FAN_TACH2_CPU1_D2
    1  FAN_TACH2_CPU1_D1      C  @BASEBOARD_FAB2_LIB.BASEBOARD_FAB2(SCH_1):FAN_TACH2_CPU1_D1

DIODE_SM  I123  CR1B3  [DIODE_SM-SDMK0340L,IC,H71799-0A]
    2  FAN_TACH3_CPU1_D2      A  @BASEBOARD_FAB2_LIB.BASEBOARD_FAB2(SCH_1):FAN_TACH3_CPU1_D2
    1  FAN_TACH3_CPU1_D1      C  @BASEBOARD_FAB2_LIB.BASEBOARD_FAB2(SCH_1):FAN_TACH3_CPU1_D1

DIODE_SM  I50  CR1E1  [DIODE_SM-SDMK0340L,EMPTY,H7179A]
    1  P5V_STBY           C  @BASEBOARD_FAB2_LIB.BASEBOARD_FAB2(SCH_1):P5V_STBY
    2  FAN_PWM_OUT_SYS0_R      A  @BASEBOARD_FAB2_LIB.BASEBOARD_FAB2(SCH_1):FAN_PWM_OUT_SYS0_R

DIODE_SM  I42  CR1F1  [DIODE_SM-SDMK0340L,IC,H71799-0A]
    2  FAN_TACH0_CPU0_D2      A  @BASEBOARD_FAB2_LIB.BASEBOARD_FAB2(SCH_1):FAN_TACH0_CPU0_D2
    1  FAN_TACH0_CPU0_D1      C  @BASEBOARD_FAB2_LIB.BASEBOARD_FAB2(SCH_1):FAN_TACH0_CPU0_D1

DIODE_SM  I133  CR1F2  [DIODE_SM-SDMK0340L,IC,H71799-0A]
    2  FAN_TACH1_CPU1_D2      A  @BASEBOARD_FAB2_LIB.BASEBOARD_FAB2(SCH_1):FAN_TACH1_CPU1_D2
    1  FAN_TACH1_CPU1_D1      C  @BASEBOARD_FAB2_LIB.BASEBOARD_FAB2(SCH_1):FAN_TACH1_CPU1_D1

DIODE_SM  I180  CR1F3  [DIODE_SM-SDMK0340L,IC,H71799-0A]
    1  FM_MATED_IN_D2_N      C  @BASEBOARD_FAB2_LIB.BASEBOARD_FAB2(SCH_1):FM_MATED_IN_D2_N
    2  FM_MATED_IN_D1_N      A  @BASEBOARD_FAB2_LIB.BASEBOARD_FAB2(SCH_1):FM_MATED_IN_D1_N

DIODE_SM  I178  CR1F4  [DIODE_SM-SDMK0340L,IC,H71799-0A]
    2  FM_MATED_IN_N      A  @BASEBOARD_FAB2_LIB.BASEBOARD_FAB2(SCH_1):FM_MATED_IN_N
    1  FM_MATED_IN_D1_N      C  @BASEBOARD_FAB2_LIB.BASEBOARD_FAB2(SCH_1):FM_MATED_IN_D1_N

DIODE_SM  I220  CR1F5  [DIODE_SM-MBRS340T3G,EMPTY,C819A]
    1  P12V_STBY          C  @BASEBOARD_FAB2_LIB.BASEBOARD_FAB2(SCH_1):P12V_STBY
    2  GND                A  @BASEBOARD_FAB2_LIB.BASEBOARD_FAB2(SCH_1):GND

DIODE_SM  I2   CR1L1  [DIODE_SM-1N4148W,IC,D89194-001]
    1  FM_DB_UART_SEL1_N      C  @BASEBOARD_FAB2_LIB.BASEBOARD_FAB2(SCH_1):FM_DB_UART_SEL1_N
    2  FM_DB_UART_SEL0_N      A  @BASEBOARD_FAB2_LIB.BASEBOARD_FAB2(SCH_1):FM_DB_UART_SEL0_N

DIODE_SM  I3   CR1L2  [DIODE_SM-1N4148W,IC,D89194-001]
    1  FM_DB_UART_SEL2_N      C  @BASEBOARD_FAB2_LIB.BASEBOARD_FAB2(SCH_1):FM_DB_UART_SEL2_N
    2  FM_DB_UART_SEL1_N      A  @BASEBOARD_FAB2_LIB.BASEBOARD_FAB2(SCH_1):FM_DB_UART_SEL1_N

DIODE_SM  I4   CR1L3  [DIODE_SM-1N4148W,IC,D89194-001]
    1  FM_DB_UART_SEL3_N      C  @BASEBOARD_FAB2_LIB.BASEBOARD_FAB2(SCH_1):FM_DB_UART_SEL3_N
    2  FM_DB_UART_SEL2_N      A  @BASEBOARD_FAB2_LIB.BASEBOARD_FAB2(SCH_1):FM_DB_UART_SEL2_N

DIODE_SM  I5   CR1L4  [DIODE_SM-1N4148W,IC,D89194-001]
    1  FM_DB_UART_SEL4_N      C  @BASEBOARD_FAB2_LIB.BASEBOARD_FAB2(SCH_1):FM_DB_UART_SEL4_N
    2  FM_DB_UART_SEL3_N      A  @BASEBOARD_FAB2_LIB.BASEBOARD_FAB2(SCH_1):FM_DB_UART_SEL3_N

DIODEAC_DUAL_ARRAY_SM9  I52  CR1M1  [DIODEAC_DUAL_ARRAY_SM9-ESD3V3UA]
    8  USB3_P01_FB_TXP   OUT1  @BASEBOARD_FAB2_LIB.BASEBOARD_FAB2(SCH_1):USB3_P01_FB_TXP
    2  USB3_P01_FB_TXP    AC1  @BASEBOARD_FAB2_LIB.BASEBOARD_FAB2(SCH_1):USB3_P01_FB_TXP
    9  USB3_P01_FB_TXN   OUT0  @BASEBOARD_FAB2_LIB.BASEBOARD_FAB2(SCH_1):USB3_P01_FB_TXN
    1  USB3_P01_FB_TXN    AC0  @BASEBOARD_FAB2_LIB.BASEBOARD_FAB2(SCH_1):USB3_P01_FB_TXN
    6  USB3_P01_FB_RXP   OUT3  @BASEBOARD_FAB2_LIB.BASEBOARD_FAB2(SCH_1):USB3_P01_FB_RXP
    5  USB3_P01_FB_RXP    AC3  @BASEBOARD_FAB2_LIB.BASEBOARD_FAB2(SCH_1):USB3_P01_FB_RXP
    7  USB3_P01_FB_RXN   OUT2  @BASEBOARD_FAB2_LIB.BASEBOARD_FAB2(SCH_1):USB3_P01_FB_RXN
    4  USB3_P01_FB_RXN    AC2  @BASEBOARD_FAB2_LIB.BASEBOARD_FAB2(SCH_1):USB3_P01_FB_RXN
    3  GND            GND<0>  @BASEBOARD_FAB2_LIB.BASEBOARD_FAB2(SCH_1):GND

DIODEAC_DUAL_ARRAY_SM9  I98  CR1M2  [DIODEAC_DUAL_ARRAY_SM9-ESD3V3UA]
    9  USB2_P01_ESD_DP   OUT0  @BASEBOARD_FAB2_LIB.BASEBOARD_FAB2(SCH_1):USB2_P01_ESD_DP
    1  USB2_P01_ESD_DP    AC0  @BASEBOARD_FAB2_LIB.BASEBOARD_FAB2(SCH_1):USB2_P01_ESD_DP
    8  USB2_P01_ESD_DN   OUT1  @BASEBOARD_FAB2_LIB.BASEBOARD_FAB2(SCH_1):USB2_P01_ESD_DN
    2  USB2_P01_ESD_DN    AC1  @BASEBOARD_FAB2_LIB.BASEBOARD_FAB2(SCH_1):USB2_P01_ESD_DN
    6  TP_USB_ESD_OUT3   OUT3  @BASEBOARD_FAB2_LIB.BASEBOARD_FAB2(SCH_1):TP_USB_ESD_OUT3
    7  TP_USB_ESD_OUT2   OUT2  @BASEBOARD_FAB2_LIB.BASEBOARD_FAB2(SCH_1):TP_USB_ESD_OUT2
    5  TP_USB_ESD_AC3    AC3  @BASEBOARD_FAB2_LIB.BASEBOARD_FAB2(SCH_1):TP_USB_ESD_AC3
    4  TP_USB_ESD_AC2    AC2  @BASEBOARD_FAB2_LIB.BASEBOARD_FAB2(SCH_1):TP_USB_ESD_AC2
    3  GND            GND<0>  @BASEBOARD_FAB2_LIB.BASEBOARD_FAB2(SCH_1):GND

DIODE2A_DUAL  I53  CR2U1  [DIODE2A_DUAL_SMLF-BAS70-05,DIOA]
    1  P3V3_STBY         A1  @BASEBOARD_FAB2_LIB.BASEBOARD_FAB2(SCH_1):P3V3_STBY
    3  P3V3_RTC_STBY      C  @BASEBOARD_FAB2_LIB.BASEBOARD_FAB2(SCH_1):P3V3_RTC_STBY
    2  A_P3V_BAT_R       A2  @BASEBOARD_FAB2_LIB.BASEBOARD_FAB2(SCH_1):A_P3V_BAT_R

DIODE_SMLF  I49  CR3U1  [DIODE_SMLF-1N5819HW,IC,D55839-A]
    1  P3V3_STBY_PLD_D      C  @BASEBOARD_FAB2_LIB.BASEBOARD_FAB2(SCH_1):P3V3_STBY_PLD_D
    2  P3V3_STBY          A  @BASEBOARD_FAB2_LIB.BASEBOARD_FAB2(SCH_1):P3V3_STBY

DIODE_SMLF  I103  CR7E1  [DIODE_SMLF-BAT54WS,IC,C73510-0A]
    1  PWRGD_P3V3_STBY      C  @BASEBOARD_FAB2_LIB.BASEBOARD_FAB2(SCH_1):PWRGD_P3V3_STBY
    2  PWRGD_DSW_PWROK      A  @BASEBOARD_FAB2_LIB.BASEBOARD_FAB2(SCH_1):PWRGD_DSW_PWROK

DIODE_SMLF  I128  CR8E1  [DIODE_SMLF-BAT54WS,IC,C73510-0A]
    2  PWRGD_P12V_HSC_DLY      A  @BASEBOARD_FAB2_LIB.BASEBOARD_FAB2(SCH_1):PWRGD_P12V_HSC_DLY
    1  PWRGD_P12V_HSC      C  @BASEBOARD_FAB2_LIB.BASEBOARD_FAB2(SCH_1):PWRGD_P12V_HSC

DIODE_SMLF  I214  CR9P1  [DIODE_SMLF-BAT54WS,IC,C73510-0A]
    1  IRQ_UV_DETECT_N      C  @BASEBOARD_FAB2_LIB.BASEBOARD_FAB2(SCH_1):IRQ_UV_DETECT_N
    2  FM_DISABLE_FAN_N      A  @BASEBOARD_FAB2_LIB.BASEBOARD_FAB2(SCH_1):FM_DISABLE_FAN_N

DIODE_SMLF  I213  CR9P2  [DIODE_SMLF-BAT54WS,IC,C73510-0A]
    1  FM_UV_ADR_TRIGGER_N      C  @BASEBOARD_FAB2_LIB.BASEBOARD_FAB2(SCH_1):FM_UV_ADR_TRIGGER_N
    2  FM_DISABLE_FAN_N      A  @BASEBOARD_FAB2_LIB.BASEBOARD_FAB2(SCH_1):FM_DISABLE_FAN_N

CAP_A  I70  CTI1   [CAP_A_0402V-0.1UF,16V,10%,X7R,A]
    1  VR_PVCCIN_CPU0_AIREF1      A  @BASEBOARD_FAB2_LIB.BASEBOARD_FAB2(SCH_1):VR_PVCCIN_CPU0_AIREF1
    2  GND                B  @BASEBOARD_FAB2_LIB.BASEBOARD_FAB2(SCH_1):GND

CAP  I78  CTI2   [CAP_0402LF-1000PF,50V,10%,X7R,A]
    2  GND                B  @BASEBOARD_FAB2_LIB.BASEBOARD_FAB2(SCH_1):GND
    1  A_TSENSE_PVCCIN_CPU0      A  @BASEBOARD_FAB2_LIB.BASEBOARD_FAB2(SCH_1):A_TSENSE_PVCCIN_CPU0

SC2K2P50V3KX-GP_SMD-BCG6  I76  CTI3   [SC2K2P50V3KX-GP_SMD-BCG6-SC2K2A]
    1  VR_PVCCIN_CPU0_PHASE1      1  @BASEBOARD_FAB2_LIB.BASEBOARD_FAB2(SCH_1):VR_PVCCIN_CPU0_PHASE1
    2  UNNAMED_202_3D01R5F-GP_I75_2      2  @BASEBOARD_FAB2_LIB.BASEBOARD_FAB2(SCH_1):UNNAMED_202_3D01R5F-GP_I75_2

CAP  I85  CTI4   [CAP_0402LF-1000PF,50V,10%,X7R,A]
    2  GND                B  @BASEBOARD_FAB2_LIB.BASEBOARD_FAB2(SCH_1):GND
    1  A_TSENSE_PVCCIN_CPU0      A  @BASEBOARD_FAB2_LIB.BASEBOARD_FAB2(SCH_1):A_TSENSE_PVCCIN_CPU0

SC2K2P50V3KX-GP_SMD-BCG6  I82  CTI5   [SC2K2P50V3KX-GP_SMD-BCG6-SC2K2A]
    1  VR_PVCCIN_CPU0_PHASE2      1  @BASEBOARD_FAB2_LIB.BASEBOARD_FAB2(SCH_1):VR_PVCCIN_CPU0_PHASE2
    2  UNNAMED_202_3D01R5F-GP_I83_2      2  @BASEBOARD_FAB2_LIB.BASEBOARD_FAB2(SCH_1):UNNAMED_202_3D01R5F-GP_I83_2

CAP_A  I81  CTI6   [CAP_A_0402V-0.1UF,16V,10%,X7R,A]
    1  VR_PVCCIN_CPU0_AIREF2      A  @BASEBOARD_FAB2_LIB.BASEBOARD_FAB2(SCH_1):VR_PVCCIN_CPU0_AIREF2
    2  GND                B  @BASEBOARD_FAB2_LIB.BASEBOARD_FAB2(SCH_1):GND

CAP_A  I109  CTI7   [CAP_A_0402V-0.1UF,16V,10%,X7R,A]
    1  VR_PVDDQ_KLM_AIREF1      A  @BASEBOARD_FAB2_LIB.BASEBOARD_FAB2(SCH_1):VR_PVDDQ_KLM_AIREF1
    2  GND                B  @BASEBOARD_FAB2_LIB.BASEBOARD_FAB2(SCH_1):GND

CAP  I114  CTI8   [CAP_0402LF-1000PF,50V,10%,X7R,A]
    2  GND                B  @BASEBOARD_FAB2_LIB.BASEBOARD_FAB2(SCH_1):GND
    1  A_TSENSE_PVDDQ_KLM      A  @BASEBOARD_FAB2_LIB.BASEBOARD_FAB2(SCH_1):A_TSENSE_PVDDQ_KLM

SC2K2P50V3KX-GP_SMD-BCG6  I111  CTI9   [SC2K2P50V3KX-GP_SMD-BCG6-SC2K2A]
    1  VR_PVDDQ_KLM_PH1_SW      1  @BASEBOARD_FAB2_LIB.BASEBOARD_FAB2(SCH_1):VR_PVDDQ_KLM_PH1_SW
    2  UNNAMED_227_3D01R5F-GP_I125_1      2  @BASEBOARD_FAB2_LIB.BASEBOARD_FAB2(SCH_1):UNNAMED_227_3D01R5F-GP_I125_1

CAP  I119  CTI10  [CAP_0402LF-1000PF,50V,10%,X7R,A]
    2  GND                B  @BASEBOARD_FAB2_LIB.BASEBOARD_FAB2(SCH_1):GND
    1  A_TSENSE_PVDDQ_KLM      A  @BASEBOARD_FAB2_LIB.BASEBOARD_FAB2(SCH_1):A_TSENSE_PVDDQ_KLM

SC2K2P50V3KX-GP_SMD-BCG6  I116  CTI11  [SC2K2P50V3KX-GP_SMD-BCG6-SC2K2A]
    1  VR_PVDDQ_KLM_PH2_SW      1  @BASEBOARD_FAB2_LIB.BASEBOARD_FAB2(SCH_1):VR_PVDDQ_KLM_PH2_SW
    2  UNNAMED_227_3D01R5F-GP_I124_1      2  @BASEBOARD_FAB2_LIB.BASEBOARD_FAB2(SCH_1):UNNAMED_227_3D01R5F-GP_I124_1

CAP_A  I122  CTI12  [CAP_A_0402V-0.1UF,16V,10%,X7R,A]
    1  VR_PVDDQ_KLM_AIREF2      A  @BASEBOARD_FAB2_LIB.BASEBOARD_FAB2(SCH_1):VR_PVDDQ_KLM_AIREF2
    2  GND                B  @BASEBOARD_FAB2_LIB.BASEBOARD_FAB2(SCH_1):GND

CAP_A  I62  CTI13  [CAP_A_0402V-0.1UF,16V,10%,X7R,A]
    1  VR_PVCCIN_CPU1_AIREF5      A  @BASEBOARD_FAB2_LIB.BASEBOARD_FAB2(SCH_1):VR_PVCCIN_CPU1_AIREF5
    2  GND                B  @BASEBOARD_FAB2_LIB.BASEBOARD_FAB2(SCH_1):GND

SC2K2P50V3KX-GP_SMD-BCG6  I64  CTI14  [SC2K2P50V3KX-GP_SMD-BCG6-SC2K2A]
    1  VR_PVCCIN_CPU1_PHASE5      1  @BASEBOARD_FAB2_LIB.BASEBOARD_FAB2(SCH_1):VR_PVCCIN_CPU1_PHASE5
    2  UNNAMED_209_3D01R5F-GP_I66_2      2  @BASEBOARD_FAB2_LIB.BASEBOARD_FAB2(SCH_1):UNNAMED_209_3D01R5F-GP_I66_2

CAP  I67  CTI15  [CAP_0402LF-1000PF,50V,10%,X7R,A]
    2  GND                B  @BASEBOARD_FAB2_LIB.BASEBOARD_FAB2(SCH_1):GND
    1  A_TSENSE_PVCCIN_CPU1      A  @BASEBOARD_FAB2_LIB.BASEBOARD_FAB2(SCH_1):A_TSENSE_PVCCIN_CPU1

CAP_A  I80  CTI16  [CAP_A_0402V-0.1UF,16V,10%,X7R,A]
    1  VR_PVCCIN_CPU1_AIREF3      A  @BASEBOARD_FAB2_LIB.BASEBOARD_FAB2(SCH_1):VR_PVCCIN_CPU1_AIREF3
    2  GND                B  @BASEBOARD_FAB2_LIB.BASEBOARD_FAB2(SCH_1):GND

CAP  I82  CTI17  [CAP_0402LF-1000PF,50V,10%,X7R,A]
    2  GND                B  @BASEBOARD_FAB2_LIB.BASEBOARD_FAB2(SCH_1):GND
    1  A_TSENSE_PVCCIN_CPU1      A  @BASEBOARD_FAB2_LIB.BASEBOARD_FAB2(SCH_1):A_TSENSE_PVCCIN_CPU1

SC2K2P50V3KX-GP_SMD-BCG6  I84  CTI18  [SC2K2P50V3KX-GP_SMD-BCG6-SC2K2A]
    1  VR_PVCCIN_CPU1_PHASE3      1  @BASEBOARD_FAB2_LIB.BASEBOARD_FAB2(SCH_1):VR_PVCCIN_CPU1_PHASE3
    2  UNNAMED_208_3D01R5F-GP_I86_2      2  @BASEBOARD_FAB2_LIB.BASEBOARD_FAB2(SCH_1):UNNAMED_208_3D01R5F-GP_I86_2

CAP  I90  CTI19  [CAP_0402LF-1000PF,50V,10%,X7R,A]
    2  GND                B  @BASEBOARD_FAB2_LIB.BASEBOARD_FAB2(SCH_1):GND
    1  A_TSENSE_PVCCIN_CPU1      A  @BASEBOARD_FAB2_LIB.BASEBOARD_FAB2(SCH_1):A_TSENSE_PVCCIN_CPU1

SC2K2P50V3KX-GP_SMD-BCG6  I92  CTI20  [SC2K2P50V3KX-GP_SMD-BCG6-SC2K2A]
    1  VR_PVCCIN_CPU1_PHASE4      1  @BASEBOARD_FAB2_LIB.BASEBOARD_FAB2(SCH_1):VR_PVCCIN_CPU1_PHASE4
    2  UNNAMED_208_3D01R5F-GP_I94_2      2  @BASEBOARD_FAB2_LIB.BASEBOARD_FAB2(SCH_1):UNNAMED_208_3D01R5F-GP_I94_2

CAP_A  I87  CTI21  [CAP_A_0402V-0.1UF,16V,10%,X7R,A]
    1  VR_PVCCIN_CPU1_AIREF4      A  @BASEBOARD_FAB2_LIB.BASEBOARD_FAB2(SCH_1):VR_PVCCIN_CPU1_AIREF4
    2  GND                B  @BASEBOARD_FAB2_LIB.BASEBOARD_FAB2(SCH_1):GND

CAP  I74  CTI22  [CAP_0402LF-1000PF,50V,10%,X7R,A]
    2  GND                B  @BASEBOARD_FAB2_LIB.BASEBOARD_FAB2(SCH_1):GND
    1  A_TSENSE_PVCCIN_CPU1      A  @BASEBOARD_FAB2_LIB.BASEBOARD_FAB2(SCH_1):A_TSENSE_PVCCIN_CPU1

SC2K2P50V3KX-GP_SMD-BCG6  I77  CTI23  [SC2K2P50V3KX-GP_SMD-BCG6-SC2K2A]
    1  VR_PVCCIN_CPU1_PHASE1      1  @BASEBOARD_FAB2_LIB.BASEBOARD_FAB2(SCH_1):VR_PVCCIN_CPU1_PHASE1
    2  UNNAMED_207_3D01R5F-GP_I76_2      2  @BASEBOARD_FAB2_LIB.BASEBOARD_FAB2(SCH_1):UNNAMED_207_3D01R5F-GP_I76_2

CAP_A  I71  CTI24  [CAP_A_0402V-0.1UF,16V,10%,X7R,A]
    1  VR_PVCCIN_CPU1_AIREF1      A  @BASEBOARD_FAB2_LIB.BASEBOARD_FAB2(SCH_1):VR_PVCCIN_CPU1_AIREF1
    2  GND                B  @BASEBOARD_FAB2_LIB.BASEBOARD_FAB2(SCH_1):GND

CAP_A  I81  CTI25  [CAP_A_0402V-0.1UF,16V,10%,X7R,A]
    1  VR_PVCCIN_CPU1_AIREF2      A  @BASEBOARD_FAB2_LIB.BASEBOARD_FAB2(SCH_1):VR_PVCCIN_CPU1_AIREF2
    2  GND                B  @BASEBOARD_FAB2_LIB.BASEBOARD_FAB2(SCH_1):GND

CAP  I82  CTI26  [CAP_0402LF-1000PF,50V,10%,X7R,A]
    2  GND                B  @BASEBOARD_FAB2_LIB.BASEBOARD_FAB2(SCH_1):GND
    1  A_TSENSE_PVCCIN_CPU1      A  @BASEBOARD_FAB2_LIB.BASEBOARD_FAB2(SCH_1):A_TSENSE_PVCCIN_CPU1

SC2K2P50V3KX-GP_SMD-BCG6  I84  CTI27  [SC2K2P50V3KX-GP_SMD-BCG6-SC2K2A]
    1  VR_PVCCIN_CPU1_PHASE2      1  @BASEBOARD_FAB2_LIB.BASEBOARD_FAB2(SCH_1):VR_PVCCIN_CPU1_PHASE2
    2  UNNAMED_207_3D01R5F-GP_I85_2      2  @BASEBOARD_FAB2_LIB.BASEBOARD_FAB2(SCH_1):UNNAMED_207_3D01R5F-GP_I85_2

CAP  I122  CTI28  [CAP_0402LF-1000PF,50V,10%,X7R,A]
    2  GND                B  @BASEBOARD_FAB2_LIB.BASEBOARD_FAB2(SCH_1):GND
    1  A_TSENSE_PVDDQ_GHJ      A  @BASEBOARD_FAB2_LIB.BASEBOARD_FAB2(SCH_1):A_TSENSE_PVDDQ_GHJ

SC2K2P50V3KX-GP_SMD-BCG6  I121  CTI29  [SC2K2P50V3KX-GP_SMD-BCG6-SC2K2A]
    1  VR_PVDDQ_GHJ_PH1_SW      1  @BASEBOARD_FAB2_LIB.BASEBOARD_FAB2(SCH_1):VR_PVDDQ_GHJ_PH1_SW
    2  UNNAMED_224_3D01R5F-GP_I119_2      2  @BASEBOARD_FAB2_LIB.BASEBOARD_FAB2(SCH_1):UNNAMED_224_3D01R5F-GP_I119_2

CAP_A  I117  CTI30  [CAP_A_0402V-0.1UF,16V,10%,X7R,A]
    1  VR_PVDDQ_GHJ_AIREF1      A  @BASEBOARD_FAB2_LIB.BASEBOARD_FAB2(SCH_1):VR_PVDDQ_GHJ_AIREF1
    2  GND                B  @BASEBOARD_FAB2_LIB.BASEBOARD_FAB2(SCH_1):GND

CAP_A  I124  CTI31  [CAP_A_0402V-0.1UF,16V,10%,X7R,A]
    1  VR_PVDDQ_GHJ_AIREF2      A  @BASEBOARD_FAB2_LIB.BASEBOARD_FAB2(SCH_1):VR_PVDDQ_GHJ_AIREF2
    2  GND                B  @BASEBOARD_FAB2_LIB.BASEBOARD_FAB2(SCH_1):GND

CAP  I130  CTI32  [CAP_0402LF-1000PF,50V,10%,X7R,A]
    2  GND                B  @BASEBOARD_FAB2_LIB.BASEBOARD_FAB2(SCH_1):GND
    1  A_TSENSE_PVDDQ_GHJ      A  @BASEBOARD_FAB2_LIB.BASEBOARD_FAB2(SCH_1):A_TSENSE_PVDDQ_GHJ

SC2K2P50V3KX-GP_SMD-BCG6  I127  CTI33  [SC2K2P50V3KX-GP_SMD-BCG6-SC2K2A]
    1  VR_PVDDQ_GHJ_PH2_SW      1  @BASEBOARD_FAB2_LIB.BASEBOARD_FAB2(SCH_1):VR_PVDDQ_GHJ_PH2_SW
    2  UNNAMED_224_3D01R5F-GP_I129_2      2  @BASEBOARD_FAB2_LIB.BASEBOARD_FAB2(SCH_1):UNNAMED_224_3D01R5F-GP_I129_2

CAP  I88  CTI34  [CAP_0402LF-1000PF,50V,10%,X7R,A]
    2  GND                B  @BASEBOARD_FAB2_LIB.BASEBOARD_FAB2(SCH_1):GND
    1  A_TSENSE_PVCCIN_CPU0      A  @BASEBOARD_FAB2_LIB.BASEBOARD_FAB2(SCH_1):A_TSENSE_PVCCIN_CPU0

SC2K2P50V3KX-GP_SMD-BCG6  I90  CTI35  [SC2K2P50V3KX-GP_SMD-BCG6-SC2K2A]
    1  VR_PVCCIN_CPU0_PHASE5      1  @BASEBOARD_FAB2_LIB.BASEBOARD_FAB2(SCH_1):VR_PVCCIN_CPU0_PHASE5
    2  UNNAMED_204_3D01R5F-GP_I91_2      2  @BASEBOARD_FAB2_LIB.BASEBOARD_FAB2(SCH_1):UNNAMED_204_3D01R5F-GP_I91_2

CAP_A  I85  CTI36  [CAP_A_0402V-0.1UF,16V,10%,X7R,A]
    1  VR_PVCCIN_CPU0_AIREF5      A  @BASEBOARD_FAB2_LIB.BASEBOARD_FAB2(SCH_1):VR_PVCCIN_CPU0_AIREF5
    2  GND                B  @BASEBOARD_FAB2_LIB.BASEBOARD_FAB2(SCH_1):GND

CAP  I99  CTI37  [CAP_0402LF-1000PF,50V,10%,X7R,A]
    2  GND                B  @BASEBOARD_FAB2_LIB.BASEBOARD_FAB2(SCH_1):GND
    1  A_TSENSE_PVCCIN_CPU0      A  @BASEBOARD_FAB2_LIB.BASEBOARD_FAB2(SCH_1):A_TSENSE_PVCCIN_CPU0

SC2K2P50V3KX-GP_SMD-BCG6  I101  CTI38  [SC2K2P50V3KX-GP_SMD-BCG6-SC2K2A]
    1  VR_PVCCIN_CPU0_PHASE3      1  @BASEBOARD_FAB2_LIB.BASEBOARD_FAB2(SCH_1):VR_PVCCIN_CPU0_PHASE3
    2  UNNAMED_203_3D01R5F-GP_I102_2      2  @BASEBOARD_FAB2_LIB.BASEBOARD_FAB2(SCH_1):UNNAMED_203_3D01R5F-GP_I102_2

CAP_A  I96  CTI39  [CAP_A_0402V-0.1UF,16V,10%,X7R,A]
    1  VR_PVCCIN_CPU0_AIREF3      A  @BASEBOARD_FAB2_LIB.BASEBOARD_FAB2(SCH_1):VR_PVCCIN_CPU0_AIREF3
    2  GND                B  @BASEBOARD_FAB2_LIB.BASEBOARD_FAB2(SCH_1):GND

CAP_A  I93  CTI40  [CAP_A_0402V-0.1UF,16V,10%,X7R,A]
    1  VR_PVCCIN_CPU0_AIREF4      A  @BASEBOARD_FAB2_LIB.BASEBOARD_FAB2(SCH_1):VR_PVCCIN_CPU0_AIREF4
    2  GND                B  @BASEBOARD_FAB2_LIB.BASEBOARD_FAB2(SCH_1):GND

SC2K2P50V3KX-GP_SMD-BCG6  I106  CTI41  [SC2K2P50V3KX-GP_SMD-BCG6-SC2K2A]
    1  VR_PVCCIN_CPU0_PHASE4      1  @BASEBOARD_FAB2_LIB.BASEBOARD_FAB2(SCH_1):VR_PVCCIN_CPU0_PHASE4
    2  UNNAMED_203_3D01R5F-GP_I105_2      2  @BASEBOARD_FAB2_LIB.BASEBOARD_FAB2(SCH_1):UNNAMED_203_3D01R5F-GP_I105_2

CAP  I108  CTI42  [CAP_0402LF-1000PF,50V,10%,X7R,A]
    2  GND                B  @BASEBOARD_FAB2_LIB.BASEBOARD_FAB2(SCH_1):GND
    1  A_TSENSE_PVCCIN_CPU0      A  @BASEBOARD_FAB2_LIB.BASEBOARD_FAB2(SCH_1):A_TSENSE_PVCCIN_CPU0

CAP  I124  CTI43  [CAP_0402LF-1000PF,50V,10%,X7R,A]
    2  GND                B  @BASEBOARD_FAB2_LIB.BASEBOARD_FAB2(SCH_1):GND
    1  A_TSENSE_PVDDQ_DEF      A  @BASEBOARD_FAB2_LIB.BASEBOARD_FAB2(SCH_1):A_TSENSE_PVDDQ_DEF

SC2K2P50V3KX-GP_SMD-BCG6  I127  CTI44  [SC2K2P50V3KX-GP_SMD-BCG6-SC2K2A]
    1  VR_PVDDQ_DEF_PH1_SW      1  @BASEBOARD_FAB2_LIB.BASEBOARD_FAB2(SCH_1):VR_PVDDQ_DEF_PH1_SW
    2  UNNAMED_219_3D01R5F-GP_I126_2      2  @BASEBOARD_FAB2_LIB.BASEBOARD_FAB2(SCH_1):UNNAMED_219_3D01R5F-GP_I126_2

CAP_A  I116  CTI45  [CAP_A_0402V-0.1UF,16V,10%,X7R,A]
    1  VR_PVDDQ_DEF_AIREF1      A  @BASEBOARD_FAB2_LIB.BASEBOARD_FAB2(SCH_1):VR_PVDDQ_DEF_AIREF1
    2  GND                B  @BASEBOARD_FAB2_LIB.BASEBOARD_FAB2(SCH_1):GND

CAP_A  I113  CTI46  [CAP_A_0402V-0.1UF,16V,10%,X7R,A]
    1  VR_PVDDQ_DEF_AIREF2      A  @BASEBOARD_FAB2_LIB.BASEBOARD_FAB2(SCH_1):VR_PVDDQ_DEF_AIREF2
    2  GND                B  @BASEBOARD_FAB2_LIB.BASEBOARD_FAB2(SCH_1):GND

SC2K2P50V3KX-GP_SMD-BCG6  I121  CTI47  [SC2K2P50V3KX-GP_SMD-BCG6-SC2K2A]
    1  VR_PVDDQ_DEF_PH2_SW      1  @BASEBOARD_FAB2_LIB.BASEBOARD_FAB2(SCH_1):VR_PVDDQ_DEF_PH2_SW
    2  UNNAMED_219_3D01R5F-GP_I123_2      2  @BASEBOARD_FAB2_LIB.BASEBOARD_FAB2(SCH_1):UNNAMED_219_3D01R5F-GP_I123_2

CAP  I119  CTI48  [CAP_0402LF-1000PF,50V,10%,X7R,A]
    2  GND                B  @BASEBOARD_FAB2_LIB.BASEBOARD_FAB2(SCH_1):GND
    1  A_TSENSE_PVDDQ_DEF      A  @BASEBOARD_FAB2_LIB.BASEBOARD_FAB2(SCH_1):A_TSENSE_PVDDQ_DEF

CAP  I118  CTI49  [CAP_0402LF-1000PF,50V,10%,X7R,A]
    2  GND                B  @BASEBOARD_FAB2_LIB.BASEBOARD_FAB2(SCH_1):GND
    1  A_TSENSE_PVDDQ_ABC      A  @BASEBOARD_FAB2_LIB.BASEBOARD_FAB2(SCH_1):A_TSENSE_PVDDQ_ABC

SC2K2P50V3KX-GP_SMD-BCG6  I124  CTI50  [SC2K2P50V3KX-GP_SMD-BCG6-SC2K2A]
    1  VR_PVDDQ_ABC_PH1_SW      1  @BASEBOARD_FAB2_LIB.BASEBOARD_FAB2(SCH_1):VR_PVDDQ_ABC_PH1_SW
    2  UNNAMED_216_3D01R5F-GP_I114_2      2  @BASEBOARD_FAB2_LIB.BASEBOARD_FAB2(SCH_1):UNNAMED_216_3D01R5F-GP_I114_2

CAP_A  I108  CTI51  [CAP_A_0402V-0.1UF,16V,10%,X7R,A]
    1  VR_PVDDQ_ABC_AIREF1      A  @BASEBOARD_FAB2_LIB.BASEBOARD_FAB2(SCH_1):VR_PVDDQ_ABC_AIREF1
    2  GND                B  @BASEBOARD_FAB2_LIB.BASEBOARD_FAB2(SCH_1):GND

CAP_A  I111  CTI52  [CAP_A_0402V-0.1UF,16V,10%,X7R,A]
    1  VR_PVDDQ_ABC_AIREF2      A  @BASEBOARD_FAB2_LIB.BASEBOARD_FAB2(SCH_1):VR_PVDDQ_ABC_AIREF2
    2  GND                B  @BASEBOARD_FAB2_LIB.BASEBOARD_FAB2(SCH_1):GND

SC2K2P50V3KX-GP_SMD-BCG6  I119  CTI53  [SC2K2P50V3KX-GP_SMD-BCG6-SC2K2A]
    1  VR_PVDDQ_ABC_PH2_SW      1  @BASEBOARD_FAB2_LIB.BASEBOARD_FAB2(SCH_1):VR_PVDDQ_ABC_PH2_SW
    2  UNNAMED_216_3D01R5F-GP_I123_2      2  @BASEBOARD_FAB2_LIB.BASEBOARD_FAB2(SCH_1):UNNAMED_216_3D01R5F-GP_I123_2

CAP  I121  CTI54  [CAP_0402LF-1000PF,50V,10%,X7R,A]
    2  GND                B  @BASEBOARD_FAB2_LIB.BASEBOARD_FAB2(SCH_1):GND
    1  A_TSENSE_PVDDQ_ABC      A  @BASEBOARD_FAB2_LIB.BASEBOARD_FAB2(SCH_1):A_TSENSE_PVDDQ_ABC

CAP  I60  CTI55  [CAP_0402LF-1000PF,50V,10%,X7R,A]
    2  GND                B  @BASEBOARD_FAB2_LIB.BASEBOARD_FAB2(SCH_1):GND
    1  A_TSENSE_PVSA_CPU1      A  @BASEBOARD_FAB2_LIB.BASEBOARD_FAB2(SCH_1):A_TSENSE_PVSA_CPU1

SC2K2P50V3KX-GP_SMD-BCG6  I57  CTI56  [SC2K2P50V3KX-GP_SMD-BCG6-SC2K2A]
    1  VR_PVSA_CPU1_PHASE_SW      1  @BASEBOARD_FAB2_LIB.BASEBOARD_FAB2(SCH_1):VR_PVSA_CPU1_PHASE_SW
    2  UNNAMED_210_3D01R5F-GP_I59_2      2  @BASEBOARD_FAB2_LIB.BASEBOARD_FAB2(SCH_1):UNNAMED_210_3D01R5F-GP_I59_2

CAP_A  I55  CTI57  [CAP_A_0402V-0.1UF,16V,10%,X7R,A]
    1  VR_PVSA_CPU1_BIREF1      A  @BASEBOARD_FAB2_LIB.BASEBOARD_FAB2(SCH_1):VR_PVSA_CPU1_BIREF1
    2  GND                B  @BASEBOARD_FAB2_LIB.BASEBOARD_FAB2(SCH_1):GND

CAP  I65  CTI58  [CAP_0402LF-1000PF,50V,10%,X7R,A]
    2  GND                B  @BASEBOARD_FAB2_LIB.BASEBOARD_FAB2(SCH_1):GND
    1  A_TSENSE_PVSA_CPU0      A  @BASEBOARD_FAB2_LIB.BASEBOARD_FAB2(SCH_1):A_TSENSE_PVSA_CPU0

SC2K2P50V3KX-GP_SMD-BCG6  I64  CTI59  [SC2K2P50V3KX-GP_SMD-BCG6-SC2K2A]
    1  VR_PVSA_CPU0_PHASE_SW      1  @BASEBOARD_FAB2_LIB.BASEBOARD_FAB2(SCH_1):VR_PVSA_CPU0_PHASE_SW
    2  UNNAMED_205_3D01R5F-GP_I68_2      2  @BASEBOARD_FAB2_LIB.BASEBOARD_FAB2(SCH_1):UNNAMED_205_3D01R5F-GP_I68_2

CAP_A  I69  CTI60  [CAP_A_0402V-0.1UF,16V,10%,X7R,A]
    1  VR_PVSA_CPU0_BIREF1      A  @BASEBOARD_FAB2_LIB.BASEBOARD_FAB2(SCH_1):VR_PVSA_CPU0_BIREF1
    2  GND                B  @BASEBOARD_FAB2_LIB.BASEBOARD_FAB2(SCH_1):GND

CAP  I134  CTI61  [CAP_0402LF-1000PF,50V,10%,X7R,A]
    2  GND                B  @BASEBOARD_FAB2_LIB.BASEBOARD_FAB2(SCH_1):GND
    1  A_TSENSE_PVCCIO_CPU1      A  @BASEBOARD_FAB2_LIB.BASEBOARD_FAB2(SCH_1):A_TSENSE_PVCCIO_CPU1

SC2K2P50V3KX-GP_SMD-BCG6  I131  CTI62  [SC2K2P50V3KX-GP_SMD-BCG6-SC2K2A]
    1  VR_PVCCIO_CPU1_PH1_SW      1  @BASEBOARD_FAB2_LIB.BASEBOARD_FAB2(SCH_1):VR_PVCCIO_CPU1_PH1_SW
    2  UNNAMED_214_3D01R5F-GP_I132_2      2  @BASEBOARD_FAB2_LIB.BASEBOARD_FAB2(SCH_1):UNNAMED_214_3D01R5F-GP_I132_2

CAP_A  I137  CTI63  [CAP_A_0402V-0.1UF,16V,10%,X7R,A]
    1  VR_PVCCIO_CPU1_AIREF1      A  @BASEBOARD_FAB2_LIB.BASEBOARD_FAB2(SCH_1):VR_PVCCIO_CPU1_AIREF1
    2  GND                B  @BASEBOARD_FAB2_LIB.BASEBOARD_FAB2(SCH_1):GND

CAP  I136  CTI64  [CAP_0402LF-1000PF,50V,10%,X7R,A]
    2  GND                B  @BASEBOARD_FAB2_LIB.BASEBOARD_FAB2(SCH_1):GND
    1  A_TSENSE_PVNN_PCH_TMON      A  @BASEBOARD_FAB2_LIB.BASEBOARD_FAB2(SCH_1):A_TSENSE_PVNN_PCH_TMON

SC2K2P50V3KX-GP_SMD-BCG6  I131  CTI65  [SC2K2P50V3KX-GP_SMD-BCG6-SC2K2A]
    1  VR_PVNN_PCH_PH1_PHASE_SW      1  @BASEBOARD_FAB2_LIB.BASEBOARD_FAB2(SCH_1):VR_PVNN_PCH_PH1_PHASE_SW
    2  UNNAMED_236_3D01R5F-GP_I132_2      2  @BASEBOARD_FAB2_LIB.BASEBOARD_FAB2(SCH_1):UNNAMED_236_3D01R5F-GP_I132_2

CAP_A  I127  CTI66  [CAP_A_0402V-0.1UF,16V,10%,X7R,A]
    1  VR_PVNN_PCH_AIREF1      A  @BASEBOARD_FAB2_LIB.BASEBOARD_FAB2(SCH_1):VR_PVNN_PCH_AIREF1
    2  GND                B  @BASEBOARD_FAB2_LIB.BASEBOARD_FAB2(SCH_1):GND

CAP_A  I124  CTI67  [CAP_A_0402V-0.1UF,16V,10%,X7R,A]
    1  VR_P1V05_PCH_BIREF1      A  @BASEBOARD_FAB2_LIB.BASEBOARD_FAB2(SCH_1):VR_P1V05_PCH_BIREF1
    2  GND                B  @BASEBOARD_FAB2_LIB.BASEBOARD_FAB2(SCH_1):GND

SC2K2P50V3KX-GP_SMD-BCG6  I140  CTI68  [SC2K2P50V3KX-GP_SMD-BCG6-SC2K2A]
    1  VR_P1V05_PCH_STBY_PH1_PHASE_SW      1  @BASEBOARD_FAB2_LIB.BASEBOARD_FAB2(SCH_1):VR_P1V05_PCH_STBY_PH1_PHASE_SW
    2  UNNAMED_236_3D01R5F-GP_I137_2      2  @BASEBOARD_FAB2_LIB.BASEBOARD_FAB2(SCH_1):UNNAMED_236_3D01R5F-GP_I137_2

CAP  I134  CTI69  [CAP_0402LF-1000PF,50V,10%,X7R,A]
    2  GND                B  @BASEBOARD_FAB2_LIB.BASEBOARD_FAB2(SCH_1):GND
    1  A_TSENSE_P1V05_PCH_STBY_TMON      A  @BASEBOARD_FAB2_LIB.BASEBOARD_FAB2(SCH_1):A_TSENSE_P1V05_PCH_STBY_TMON

CAP_A  I106  CTI70  [CAP_A_0402V-0.1UF,16V,10%,X7R,A]
    1  VR_PVCCIO_CPU0_AIREF1      A  @BASEBOARD_FAB2_LIB.BASEBOARD_FAB2(SCH_1):VR_PVCCIO_CPU0_AIREF1
    2  GND                B  @BASEBOARD_FAB2_LIB.BASEBOARD_FAB2(SCH_1):GND

CAP  I109  CTI71  [CAP_0402LF-1000PF,50V,10%,X7R,A]
    2  GND                B  @BASEBOARD_FAB2_LIB.BASEBOARD_FAB2(SCH_1):GND
    1  A_TSENSE_PVCCIO_CPU0      A  @BASEBOARD_FAB2_LIB.BASEBOARD_FAB2(SCH_1):A_TSENSE_PVCCIO_CPU0

SC2K2P50V3KX-GP_SMD-BCG6  I111  CTI72  [SC2K2P50V3KX-GP_SMD-BCG6-SC2K2A]
    1  VR_PVCCIO_CPU0_PH1_SW      1  @BASEBOARD_FAB2_LIB.BASEBOARD_FAB2(SCH_1):VR_PVCCIO_CPU0_PH1_SW
    2  UNNAMED_212_3D01R5F-GP_I112_2      2  @BASEBOARD_FAB2_LIB.BASEBOARD_FAB2(SCH_1):UNNAMED_212_3D01R5F-GP_I112_2

LED_1NC  I50  DS9A1  [LED_1NC-BLUE,IC,C96565-012]
    2  FP_ID_LED_XOR_R      A  @BASEBOARD_FAB2_LIB.BASEBOARD_FAB2(SCH_1):FP_ID_LED_XOR_R
    1  FP_ID_LED_P5V_STBY_N      C  @BASEBOARD_FAB2_LIB.BASEBOARD_FAB2(SCH_1):FP_ID_LED_P5V_STBY_N

LED_1NCLF  I42  DS9A2  [LED_1NCLF-GREEN,IC,C96565-011]
    2  FP_LED_HDD_ACTIVITY_AND_R_N      A  @BASEBOARD_FAB2_LIB.BASEBOARD_FAB2(SCH_1):FP_LED_HDD_ACTIVITY_AND_R_N
    1  FP_LED_HDD_ACTIVITY_AND_N      C  @BASEBOARD_FAB2_LIB.BASEBOARD_FAB2(SCH_1):FP_LED_HDD_ACTIVITY_AND_N

LED_1NCLF  I67  DS9A3  [LED_1NCLF-YELLOW,IC,C96565-003]
    1  FM_SPEAKER_PCH_N      C  @BASEBOARD_FAB2_LIB.BASEBOARD_FAB2(SCH_1):FM_SPEAKER_PCH_N
    2  FM_BEEP_LED_P      A  @BASEBOARD_FAB2_LIB.BASEBOARD_FAB2(SCH_1):FM_BEEP_LED_P

LED_A1LF  I130  DS9A4  [LED_A1LF-GREEN,IC,D14725-022]
    1  FM_UARTSW_LSB_R_N      A  @BASEBOARD_FAB2_LIB.BASEBOARD_FAB2(SCH_1):FM_UARTSW_LSB_R_N
    2  FM_UARTSW_LSB_N      C  @BASEBOARD_FAB2_LIB.BASEBOARD_FAB2(SCH_1):FM_UARTSW_LSB_N

LED_A1LF  I179  DS9A5  [LED_A1LF-GREEN,IC,C97278-010]
    2  FM_PWR_LED_K       C  @BASEBOARD_FAB2_LIB.BASEBOARD_FAB2(SCH_1):FM_PWR_LED_K
    1  FM_PWR_LED_A       A  @BASEBOARD_FAB2_LIB.BASEBOARD_FAB2(SCH_1):FM_PWR_LED_A

LED_A1LF  I31  DS9A6  [LED_A1LF-GREEN,IC,C97278-010]
    1  LED_P5V_STBY       A  @BASEBOARD_FAB2_LIB.BASEBOARD_FAB2(SCH_1):LED_P5V_STBY
    2  GND                C  @BASEBOARD_FAB2_LIB.BASEBOARD_FAB2(SCH_1):GND

LED_A1LF  I134  DS9A7  [LED_A1LF-GREEN,IC,D14725-022]
    1  FM_UARTSW_MSB_R_N      A  @BASEBOARD_FAB2_LIB.BASEBOARD_FAB2(SCH_1):FM_UARTSW_MSB_R_N
    2  FM_UARTSW_MSB_N      C  @BASEBOARD_FAB2_LIB.BASEBOARD_FAB2(SCH_1):FM_UARTSW_MSB_N

LED_A1LF  I56  DS9E1  [LED_A1LF-GREEN,IC,C97278-010]
    2  FM_HEARTBEAT_LED_K      C  @BASEBOARD_FAB2_LIB.BASEBOARD_FAB2(SCH_1):FM_HEARTBEAT_LED_K
    1  FM_HEARTBEAT_LED_A      A  @BASEBOARD_FAB2_LIB.BASEBOARD_FAB2(SCH_1):FM_HEARTBEAT_LED_A

LED_A1  I71  DS9F1  [LED_A1-RED,IC,D14725-005]
    2  FM_RED_LED_CATHODE      C  @BASEBOARD_FAB2_LIB.BASEBOARD_FAB2(SCH_1):FM_RED_LED_CATHODE
    1  FM_RED_LED_ANODE      A  @BASEBOARD_FAB2_LIB.BASEBOARD_FAB2(SCH_1):FM_RED_LED_ANODE

IR354XX_SM  I102  EU1A1  [IR354XX_SM-IR35411,IC,H73688-0A]
   34  VR_PVDDQ_KLM_PWM2    PWM  @BASEBOARD_FAB2_LIB.BASEBOARD_FAB2(SCH_1):VR_PVDDQ_KLM_PWM2
    3  VR_PVDDQ_KLM_PH2_VCIN    VCC  @BASEBOARD_FAB2_LIB.BASEBOARD_FAB2(SCH_1):VR_PVDDQ_KLM_PH2_VCIN
   10  VR_PVDDQ_KLM_PH2_SW     SW  @BASEBOARD_FAB2_LIB.BASEBOARD_FAB2(SCH_1):VR_PVDDQ_KLM_PH2_SW
   32  VR_PVDDQ_KLM_PH2_PHASE  PHASE  @BASEBOARD_FAB2_LIB.BASEBOARD_FAB2(SCH_1):VR_PVDDQ_KLM_PH2_PHASE
   37  VR_PVDDQ_KLM_PH2_OCSET  OCSET  @BASEBOARD_FAB2_LIB.BASEBOARD_FAB2(SCH_1):VR_PVDDQ_KLM_PH2_OCSET
   33  VR_PVDDQ_KLM_PH2_BOOT_R  BOOST  @BASEBOARD_FAB2_LIB.BASEBOARD_FAB2(SCH_1):VR_PVDDQ_KLM_PH2_BOOT_R
   39  VR_PVDDQ_KLM_AIREF2  REFIN  @BASEBOARD_FAB2_LIB.BASEBOARD_FAB2(SCH_1):VR_PVDDQ_KLM_AIREF2
   30  VR_FET_SW_P12V_STBY_PVDDQ_KLM  VIN<1>  @BASEBOARD_FAB2_LIB.BASEBOARD_FAB2(SCH_1):VR_FET_SW_P12V_STBY_PVDDQ_KLM
   25  VR_FET_SW_P12V_STBY_PVDDQ_KLM  VIN<0>  @BASEBOARD_FAB2_LIB.BASEBOARD_FAB2(SCH_1):VR_FET_SW_P12V_STBY_PVDDQ_KLM
   41  TP_PVDDQ_KLM_PH2_GL_1  GL<1>  @BASEBOARD_FAB2_LIB.BASEBOARD_FAB2(SCH_1):TP_PVDDQ_KLM_PH2_GL_1
    6  TP_PVDDQ_KLM_PH2_GL_0  GL<0>  @BASEBOARD_FAB2_LIB.BASEBOARD_FAB2(SCH_1):TP_PVDDQ_KLM_PH2_GL_0
    1  PVDDQ_KLM        VOS  @BASEBOARD_FAB2_LIB.BASEBOARD_FAB2(SCH_1):PVDDQ_KLM
    4  P5V_STBY        VDRV  @BASEBOARD_FAB2_LIB.BASEBOARD_FAB2(SCH_1):P5V_STBY
   35  P5V_STBY          EN  @BASEBOARD_FAB2_LIB.BASEBOARD_FAB2(SCH_1):P5V_STBY
   31  NC_PVDDQ_KLM_PH2_P31     NC  @BASEBOARD_FAB2_LIB.BASEBOARD_FAB2(SCH_1):NC_PVDDQ_KLM_PH2_P31
   38  ISENSE_PVDDQ_KLM_PH2_IMON   IOUT  @BASEBOARD_FAB2_LIB.BASEBOARD_FAB2(SCH_1):ISENSE_PVDDQ_KLM_PH2_IMON
   40  GND            PGND<2>  @BASEBOARD_FAB2_LIB.BASEBOARD_FAB2(SCH_1):GND
    7  GND            PGND<1>  @BASEBOARD_FAB2_LIB.BASEBOARD_FAB2(SCH_1):GND
    5  GND            PGND<0>  @BASEBOARD_FAB2_LIB.BASEBOARD_FAB2(SCH_1):GND
    2  GND             LGND  @BASEBOARD_FAB2_LIB.BASEBOARD_FAB2(SCH_1):GND
   36  A_TSENSE_PVDDQ_KLM  TOUT_FLT  @BASEBOARD_FAB2_LIB.BASEBOARD_FAB2(SCH_1):A_TSENSE_PVDDQ_KLM

IR354XX_SM  I101  EU1A2  [IR354XX_SM-IR35411,IC,H73688-0A]
   34  VR_PVDDQ_KLM_PWM1    PWM  @BASEBOARD_FAB2_LIB.BASEBOARD_FAB2(SCH_1):VR_PVDDQ_KLM_PWM1
    3  VR_PVDDQ_KLM_PH1_VCIN    VCC  @BASEBOARD_FAB2_LIB.BASEBOARD_FAB2(SCH_1):VR_PVDDQ_KLM_PH1_VCIN
   10  VR_PVDDQ_KLM_PH1_SW     SW  @BASEBOARD_FAB2_LIB.BASEBOARD_FAB2(SCH_1):VR_PVDDQ_KLM_PH1_SW
   32  VR_PVDDQ_KLM_PH1_PHASE  PHASE  @BASEBOARD_FAB2_LIB.BASEBOARD_FAB2(SCH_1):VR_PVDDQ_KLM_PH1_PHASE
   37  VR_PVDDQ_KLM_PH1_OCSET  OCSET  @BASEBOARD_FAB2_LIB.BASEBOARD_FAB2(SCH_1):VR_PVDDQ_KLM_PH1_OCSET
   33  VR_PVDDQ_KLM_PH1_BOOT_R  BOOST  @BASEBOARD_FAB2_LIB.BASEBOARD_FAB2(SCH_1):VR_PVDDQ_KLM_PH1_BOOT_R
   39  VR_PVDDQ_KLM_AIREF1  REFIN  @BASEBOARD_FAB2_LIB.BASEBOARD_FAB2(SCH_1):VR_PVDDQ_KLM_AIREF1
   30  VR_FET_SW_P12V_STBY_PVDDQ_KLM  VIN<1>  @BASEBOARD_FAB2_LIB.BASEBOARD_FAB2(SCH_1):VR_FET_SW_P12V_STBY_PVDDQ_KLM
   25  VR_FET_SW_P12V_STBY_PVDDQ_KLM  VIN<0>  @BASEBOARD_FAB2_LIB.BASEBOARD_FAB2(SCH_1):VR_FET_SW_P12V_STBY_PVDDQ_KLM
   41  TP_PVDDQ_KLM_PH1_GL_1  GL<1>  @BASEBOARD_FAB2_LIB.BASEBOARD_FAB2(SCH_1):TP_PVDDQ_KLM_PH1_GL_1
    6  TP_PVDDQ_KLM_PH1_GL_0  GL<0>  @BASEBOARD_FAB2_LIB.BASEBOARD_FAB2(SCH_1):TP_PVDDQ_KLM_PH1_GL_0
    1  PVDDQ_KLM        VOS  @BASEBOARD_FAB2_LIB.BASEBOARD_FAB2(SCH_1):PVDDQ_KLM
    4  P5V_STBY        VDRV  @BASEBOARD_FAB2_LIB.BASEBOARD_FAB2(SCH_1):P5V_STBY
   35  P5V_STBY          EN  @BASEBOARD_FAB2_LIB.BASEBOARD_FAB2(SCH_1):P5V_STBY
   31  NC_PVDDQ_KLM_PH1_P31     NC  @BASEBOARD_FAB2_LIB.BASEBOARD_FAB2(SCH_1):NC_PVDDQ_KLM_PH1_P31
   38  ISENSE_PVDDQ_KLM_PH1_IMON   IOUT  @BASEBOARD_FAB2_LIB.BASEBOARD_FAB2(SCH_1):ISENSE_PVDDQ_KLM_PH1_IMON
   40  GND            PGND<2>  @BASEBOARD_FAB2_LIB.BASEBOARD_FAB2(SCH_1):GND
    7  GND            PGND<1>  @BASEBOARD_FAB2_LIB.BASEBOARD_FAB2(SCH_1):GND
    5  GND            PGND<0>  @BASEBOARD_FAB2_LIB.BASEBOARD_FAB2(SCH_1):GND
    2  GND             LGND  @BASEBOARD_FAB2_LIB.BASEBOARD_FAB2(SCH_1):GND
   36  A_TSENSE_PVDDQ_KLM  TOUT_FLT  @BASEBOARD_FAB2_LIB.BASEBOARD_FAB2(SCH_1):A_TSENSE_PVDDQ_KLM

PXM1310B_QFN  I90  EU1B1  [PXM1310B_QFN-IC,H89186-001]
   20  VSENSE_PVDDQ_KLM_N  AVREF  @BASEBOARD_FAB2_LIB.BASEBOARD_FAB2(SCH_1):VSENSE_PVDDQ_KLM_N
   33  VR_PVDDQ_KLM_XADDR2  XADDR2  @BASEBOARD_FAB2_LIB.BASEBOARD_FAB2(SCH_1):VR_PVDDQ_KLM_XADDR2
   36  VR_PVDDQ_KLM_XADDR1  XADDR1  @BASEBOARD_FAB2_LIB.BASEBOARD_FAB2(SCH_1):VR_PVDDQ_KLM_XADDR1
   10  VR_PVDDQ_KLM_VREN  AVREN  @BASEBOARD_FAB2_LIB.BASEBOARD_FAB2(SCH_1):VR_PVDDQ_KLM_VREN
   37  VR_PVDDQ_KLM_VINSEN  VINSEN  @BASEBOARD_FAB2_LIB.BASEBOARD_FAB2(SCH_1):VR_PVDDQ_KLM_VINSEN
   39  VR_PVDDQ_KLM_VDD    VDD  @BASEBOARD_FAB2_LIB.BASEBOARD_FAB2(SCH_1):VR_PVDDQ_KLM_VDD
   40  VR_PVDDQ_KLM_VD12   VD12  @BASEBOARD_FAB2_LIB.BASEBOARD_FAB2(SCH_1):VR_PVDDQ_KLM_VD12
    4  VR_PVDDQ_KLM_PWM2  APWM2  @BASEBOARD_FAB2_LIB.BASEBOARD_FAB2(SCH_1):VR_PVDDQ_KLM_PWM2
    5  VR_PVDDQ_KLM_PWM1  APWM1  @BASEBOARD_FAB2_LIB.BASEBOARD_FAB2(SCH_1):VR_PVDDQ_KLM_PWM1
   19  VR_PVDDQ_KLM_AVSP  AVSEN  @BASEBOARD_FAB2_LIB.BASEBOARD_FAB2(SCH_1):VR_PVDDQ_KLM_AVSP
   23  VR_PVDDQ_KLM_AIREF2  AIREF2  @BASEBOARD_FAB2_LIB.BASEBOARD_FAB2(SCH_1):VR_PVDDQ_KLM_AIREF2
   21  VR_PVDDQ_KLM_AIREF1  AIREF1  @BASEBOARD_FAB2_LIB.BASEBOARD_FAB2(SCH_1):VR_PVDDQ_KLM_AIREF1
   38  VR_PVDDQ_KLM_AIINSEN  IINSEN  @BASEBOARD_FAB2_LIB.BASEBOARD_FAB2(SCH_1):VR_PVDDQ_KLM_AIINSEN
    8  TP_PVDDQ_KLM_RESET_N  RESET_N  @BASEBOARD_FAB2_LIB.BASEBOARD_FAB2(SCH_1):TP_PVDDQ_KLM_RESET_N
   25  TP_PVDDQ_KLM_PH3_IMON_REF  AIREF3  @BASEBOARD_FAB2_LIB.BASEBOARD_FAB2(SCH_1):TP_PVDDQ_KLM_PH3_IMON_REF
   26  TP_PVDDQ_KLM_PH3_IMON  AISEN3  @BASEBOARD_FAB2_LIB.BASEBOARD_FAB2(SCH_1):TP_PVDDQ_KLM_PH3_IMON
   29  TP_PVDDQ_KLM_BVSEN  BVSEN  @BASEBOARD_FAB2_LIB.BASEBOARD_FAB2(SCH_1):TP_PVDDQ_KLM_BVSEN
   30  TP_PVDDQ_KLM_BVREF  BVREF  @BASEBOARD_FAB2_LIB.BASEBOARD_FAB2(SCH_1):TP_PVDDQ_KLM_BVREF
   34  TP_PVDDQ_KLM_BTSEN  BTSEN  @BASEBOARD_FAB2_LIB.BASEBOARD_FAB2(SCH_1):TP_PVDDQ_KLM_BTSEN
   31  TP_PVDDQ_KLM_BREF1  BIREF1  @BASEBOARD_FAB2_LIB.BASEBOARD_FAB2(SCH_1):TP_PVDDQ_KLM_BREF1
    1  TP_PVDDQ_KLM_BPWM1  BPWM1  @BASEBOARD_FAB2_LIB.BASEBOARD_FAB2(SCH_1):TP_PVDDQ_KLM_BPWM1
   16  SVID_VDIO_PVDDQ_KLM   VDIO  @BASEBOARD_FAB2_LIB.BASEBOARD_FAB2(SCH_1):SVID_VDIO_PVDDQ_KLM
   15  SVID_CLK_PVDDQ_KLM   VCLK  @BASEBOARD_FAB2_LIB.BASEBOARD_FAB2(SCH_1):SVID_CLK_PVDDQ_KLM
   17  SVID_ALERT_PVDDQ_KLM  VALRT_N  @BASEBOARD_FAB2_LIB.BASEBOARD_FAB2(SCH_1):SVID_ALERT_PVDDQ_KLM
    6  SMB_VR_SDA_VDDQ_KLM    SDA  @BASEBOARD_FAB2_LIB.BASEBOARD_FAB2(SCH_1):SMB_VR_SDA_VDDQ_KLM
    7  SMB_VR_SCL_VDDQ_KLM    SCL  @BASEBOARD_FAB2_LIB.BASEBOARD_FAB2(SCH_1):SMB_VR_SCL_VDDQ_KLM
    9  PWRGD_PVDDQ_KLM_R  AVRRDY  @BASEBOARD_FAB2_LIB.BASEBOARD_FAB2(SCH_1):PWRGD_PVDDQ_KLM_R
   13  PU_VR_PVDDQ_KLM_FAULT1    MP0  @BASEBOARD_FAB2_LIB.BASEBOARD_FAB2(SCH_1):PU_VR_PVDDQ_KLM_FAULT1
    3  NC_PVDDQ_KLM_PWM3  APWM3  @BASEBOARD_FAB2_LIB.BASEBOARD_FAB2(SCH_1):NC_PVDDQ_KLM_PWM3
   12  NC_PVDDQ_KLM_PINALRT_N  PINALRT_N  @BASEBOARD_FAB2_LIB.BASEBOARD_FAB2(SCH_1):NC_PVDDQ_KLM_PINALRT_N
   14  NC_PVDDQ_KLM_GP1    MP1  @BASEBOARD_FAB2_LIB.BASEBOARD_FAB2(SCH_1):NC_PVDDQ_KLM_GP1
   18  NC_PVDDQ_KLM_GP0    MP2  @BASEBOARD_FAB2_LIB.BASEBOARD_FAB2(SCH_1):NC_PVDDQ_KLM_GP0
   28  NC_PVDDQ_KLM_DNC1  DNC<1>  @BASEBOARD_FAB2_LIB.BASEBOARD_FAB2(SCH_1):NC_PVDDQ_KLM_DNC1
    2  NC_PVDDQ_KLM_DNC0  DNC<0>  @BASEBOARD_FAB2_LIB.BASEBOARD_FAB2(SCH_1):NC_PVDDQ_KLM_DNC0
   24  ISENSE_PVDDQ_KLM_PH2_IMON  AISEN2  @BASEBOARD_FAB2_LIB.BASEBOARD_FAB2(SCH_1):ISENSE_PVDDQ_KLM_PH2_IMON
   22  ISENSE_PVDDQ_KLM_PH1_IMON  AISEN1  @BASEBOARD_FAB2_LIB.BASEBOARD_FAB2(SCH_1):ISENSE_PVDDQ_KLM_PH1_IMON
   11  IRQ_PVDDQ_KLM_VRHOT_LVT3_R_N  VRHOT_N  @BASEBOARD_FAB2_LIB.BASEBOARD_FAB2(SCH_1):IRQ_PVDDQ_KLM_VRHOT_LVT3_R_N
   41  GND            THPAD  @BASEBOARD_FAB2_LIB.BASEBOARD_FAB2(SCH_1):GND
   27  GND              GND  @BASEBOARD_FAB2_LIB.BASEBOARD_FAB2(SCH_1):GND
   32  GND            BISEN1  @BASEBOARD_FAB2_LIB.BASEBOARD_FAB2(SCH_1):GND
   35  A_TSENSE_PVDDQ_KLM  ATSEN  @BASEBOARD_FAB2_LIB.BASEBOARD_FAB2(SCH_1):A_TSENSE_PVDDQ_KLM

IR354XX_SM  I51  EU1C1  [IR354XX_SM-IR35412,IC,H73684-0A]
    3  VR_PVSA_CPU1_VCIN    VCC  @BASEBOARD_FAB2_LIB.BASEBOARD_FAB2(SCH_1):VR_PVSA_CPU1_VCIN
   34  VR_PVSA_CPU1_PWM    PWM  @BASEBOARD_FAB2_LIB.BASEBOARD_FAB2(SCH_1):VR_PVSA_CPU1_PWM
   10  VR_PVSA_CPU1_PHASE_SW     SW  @BASEBOARD_FAB2_LIB.BASEBOARD_FAB2(SCH_1):VR_PVSA_CPU1_PHASE_SW
   32  VR_PVSA_CPU1_PHASE  PHASE  @BASEBOARD_FAB2_LIB.BASEBOARD_FAB2(SCH_1):VR_PVSA_CPU1_PHASE
   37  VR_PVSA_CPU1_OCSET  OCSET  @BASEBOARD_FAB2_LIB.BASEBOARD_FAB2(SCH_1):VR_PVSA_CPU1_OCSET
   33  VR_PVSA_CPU1_BOOT_R  BOOST  @BASEBOARD_FAB2_LIB.BASEBOARD_FAB2(SCH_1):VR_PVSA_CPU1_BOOT_R
   39  VR_PVSA_CPU1_BIREF1  REFIN  @BASEBOARD_FAB2_LIB.BASEBOARD_FAB2(SCH_1):VR_PVSA_CPU1_BIREF1
   30  VR_FET_SW_P12V_STBY_PVCCIN_CPU1  VIN<1>  @BASEBOARD_FAB2_LIB.BASEBOARD_FAB2(SCH_1):VR_FET_SW_P12V_STBY_PVCCIN_CPU1
   25  VR_FET_SW_P12V_STBY_PVCCIN_CPU1  VIN<0>  @BASEBOARD_FAB2_LIB.BASEBOARD_FAB2(SCH_1):VR_FET_SW_P12V_STBY_PVCCIN_CPU1
   41  TP_PVSA_CPU1_GL_1  GL<1>  @BASEBOARD_FAB2_LIB.BASEBOARD_FAB2(SCH_1):TP_PVSA_CPU1_GL_1
    6  TP_PVSA_CPU1_GL_0  GL<0>  @BASEBOARD_FAB2_LIB.BASEBOARD_FAB2(SCH_1):TP_PVSA_CPU1_GL_0
    1  PVSA_CPU1        VOS  @BASEBOARD_FAB2_LIB.BASEBOARD_FAB2(SCH_1):PVSA_CPU1
    4  P5V_STBY        VDRV  @BASEBOARD_FAB2_LIB.BASEBOARD_FAB2(SCH_1):P5V_STBY
   35  P5V_STBY          EN  @BASEBOARD_FAB2_LIB.BASEBOARD_FAB2(SCH_1):P5V_STBY
   31  NC_PVSA_CPU1_P31     NC  @BASEBOARD_FAB2_LIB.BASEBOARD_FAB2(SCH_1):NC_PVSA_CPU1_P31
   38  ISENSE_PVSA_CPU1_IMON   IOUT  @BASEBOARD_FAB2_LIB.BASEBOARD_FAB2(SCH_1):ISENSE_PVSA_CPU1_IMON
   40  GND            PGND<2>  @BASEBOARD_FAB2_LIB.BASEBOARD_FAB2(SCH_1):GND
    7  GND            PGND<1>  @BASEBOARD_FAB2_LIB.BASEBOARD_FAB2(SCH_1):GND
    5  GND            PGND<0>  @BASEBOARD_FAB2_LIB.BASEBOARD_FAB2(SCH_1):GND
    2  GND             LGND  @BASEBOARD_FAB2_LIB.BASEBOARD_FAB2(SCH_1):GND
   36  A_TSENSE_PVSA_CPU1  TOUT_FLT  @BASEBOARD_FAB2_LIB.BASEBOARD_FAB2(SCH_1):A_TSENSE_PVSA_CPU1

PXE1610B_QFN  I130  EU1C2  [PXE1610B_QFN-IC,H79206-001]
   36  VSENSE_PVSA_CPU1_N  BVREF  @BASEBOARD_FAB2_LIB.BASEBOARD_FAB2(SCH_1):VSENSE_PVSA_CPU1_N
   35  VSENSE_PVSA_CPU1_BVSP  BVSEN  @BASEBOARD_FAB2_LIB.BASEBOARD_FAB2(SCH_1):VSENSE_PVSA_CPU1_BVSP
   22  VSENSE_PVCCIN_CPU1_N  AVREF  @BASEBOARD_FAB2_LIB.BASEBOARD_FAB2(SCH_1):VSENSE_PVCCIN_CPU1_N
   21  VSENSE_PVCCIN_CPU1_AVSP  AVSEN  @BASEBOARD_FAB2_LIB.BASEBOARD_FAB2(SCH_1):VSENSE_PVCCIN_CPU1_AVSP
   11  VR_VRRDY_PVCCIN_CPU1  AVRRDY  @BASEBOARD_FAB2_LIB.BASEBOARD_FAB2(SCH_1):VR_VRRDY_PVCCIN_CPU1
    1  VR_PVSA_CPU1_PWM  BPWM1  @BASEBOARD_FAB2_LIB.BASEBOARD_FAB2(SCH_1):VR_PVSA_CPU1_PWM
   37  VR_PVSA_CPU1_BIREF1  BIREF1  @BASEBOARD_FAB2_LIB.BASEBOARD_FAB2(SCH_1):VR_PVSA_CPU1_BIREF1
   41  VR_PVCCIN_CPU1_XADDR2  XADDR2  @BASEBOARD_FAB2_LIB.BASEBOARD_FAB2(SCH_1):VR_PVCCIN_CPU1_XADDR2
   44  VR_PVCCIN_CPU1_XADDR1  XADDR1  @BASEBOARD_FAB2_LIB.BASEBOARD_FAB2(SCH_1):VR_PVCCIN_CPU1_XADDR1
   12  VR_PVCCIN_CPU1_VREN  AVREN  @BASEBOARD_FAB2_LIB.BASEBOARD_FAB2(SCH_1):VR_PVCCIN_CPU1_VREN
   47  VR_PVCCIN_CPU1_VDD    VDD  @BASEBOARD_FAB2_LIB.BASEBOARD_FAB2(SCH_1):VR_PVCCIN_CPU1_VDD
   48  VR_PVCCIN_CPU1_VD12   VD12  @BASEBOARD_FAB2_LIB.BASEBOARD_FAB2(SCH_1):VR_PVCCIN_CPU1_VD12
    3  VR_PVCCIN_CPU1_PWM5  APWM5  @BASEBOARD_FAB2_LIB.BASEBOARD_FAB2(SCH_1):VR_PVCCIN_CPU1_PWM5
    4  VR_PVCCIN_CPU1_PWM4  APWM4  @BASEBOARD_FAB2_LIB.BASEBOARD_FAB2(SCH_1):VR_PVCCIN_CPU1_PWM4
    5  VR_PVCCIN_CPU1_PWM3  APWM3  @BASEBOARD_FAB2_LIB.BASEBOARD_FAB2(SCH_1):VR_PVCCIN_CPU1_PWM3
    6  VR_PVCCIN_CPU1_PWM2  APWM2  @BASEBOARD_FAB2_LIB.BASEBOARD_FAB2(SCH_1):VR_PVCCIN_CPU1_PWM2
    7  VR_PVCCIN_CPU1_PWM1  APWM1  @BASEBOARD_FAB2_LIB.BASEBOARD_FAB2(SCH_1):VR_PVCCIN_CPU1_PWM1
   45  VR_PVCCIN_CPU1_AVINSEN  VINSEN  @BASEBOARD_FAB2_LIB.BASEBOARD_FAB2(SCH_1):VR_PVCCIN_CPU1_AVINSEN
   31  VR_PVCCIN_CPU1_AIREF5  AIREF5  @BASEBOARD_FAB2_LIB.BASEBOARD_FAB2(SCH_1):VR_PVCCIN_CPU1_AIREF5
   29  VR_PVCCIN_CPU1_AIREF4  AIREF4  @BASEBOARD_FAB2_LIB.BASEBOARD_FAB2(SCH_1):VR_PVCCIN_CPU1_AIREF4
   27  VR_PVCCIN_CPU1_AIREF3  AIREF3  @BASEBOARD_FAB2_LIB.BASEBOARD_FAB2(SCH_1):VR_PVCCIN_CPU1_AIREF3
   25  VR_PVCCIN_CPU1_AIREF2  AIREF2  @BASEBOARD_FAB2_LIB.BASEBOARD_FAB2(SCH_1):VR_PVCCIN_CPU1_AIREF2
   23  VR_PVCCIN_CPU1_AIREF1  AIREF1  @BASEBOARD_FAB2_LIB.BASEBOARD_FAB2(SCH_1):VR_PVCCIN_CPU1_AIREF1
   10  TP_PVCCIN_CPU1_RESET_N  RESET_N  @BASEBOARD_FAB2_LIB.BASEBOARD_FAB2(SCH_1):TP_PVCCIN_CPU1_RESET_N
   16  TP_PVCCIN_CPU1_GP1    MP1  @BASEBOARD_FAB2_LIB.BASEBOARD_FAB2(SCH_1):TP_PVCCIN_CPU1_GP1
   40  TP_PVCCIN_CPU1_FAULT1_20    MP4  @BASEBOARD_FAB2_LIB.BASEBOARD_FAB2(SCH_1):TP_PVCCIN_CPU1_FAULT1_20
    2  TP_PVCCIN_CPU1_APWM6  APWM6  @BASEBOARD_FAB2_LIB.BASEBOARD_FAB2(SCH_1):TP_PVCCIN_CPU1_APWM6
   34  TP_PVCCIN_CPU1_AISEN6  AISEN6  @BASEBOARD_FAB2_LIB.BASEBOARD_FAB2(SCH_1):TP_PVCCIN_CPU1_AISEN6
   33  TP_PVCCIN_CPU1_AIREF6  AIREF6  @BASEBOARD_FAB2_LIB.BASEBOARD_FAB2(SCH_1):TP_PVCCIN_CPU1_AIREF6
   18  SVID_VDIO_PVCCIN_CPU1   VDIO  @BASEBOARD_FAB2_LIB.BASEBOARD_FAB2(SCH_1):SVID_VDIO_PVCCIN_CPU1
   17  SVID_VCLK_PVCCIN_CPU1   VCLK  @BASEBOARD_FAB2_LIB.BASEBOARD_FAB2(SCH_1):SVID_VCLK_PVCCIN_CPU1
   19  SVID_VALERT_VCCIN_CPU1  VALRT_N  @BASEBOARD_FAB2_LIB.BASEBOARD_FAB2(SCH_1):SVID_VALERT_VCCIN_CPU1
    8  SMB_VR_SDA_R1    SDA  @BASEBOARD_FAB2_LIB.BASEBOARD_FAB2(SCH_1):SMB_VR_SDA_R1
    9  SMB_VR_SCL_R1    SCL  @BASEBOARD_FAB2_LIB.BASEBOARD_FAB2(SCH_1):SMB_VR_SCL_R1
   15  PWRGD_PVSA_CPU1_R    MP0  @BASEBOARD_FAB2_LIB.BASEBOARD_FAB2(SCH_1):PWRGD_PVSA_CPU1_R
   46  PVCCIN_PVSA_CPU1_IINSEN  IINSEN  @BASEBOARD_FAB2_LIB.BASEBOARD_FAB2(SCH_1):PVCCIN_PVSA_CPU1_IINSEN
   39  PU_VR_PVCCIN_CPU1_IMON    MP3  @BASEBOARD_FAB2_LIB.BASEBOARD_FAB2(SCH_1):PU_VR_PVCCIN_CPU1_IMON
   20  PU_VR_PVCCIN_CPU1_FLT1_SMBALT_N    MP2  @BASEBOARD_FAB2_LIB.BASEBOARD_FAB2(SCH_1):PU_VR_PVCCIN_CPU1_FLT1_SMBALT_N_IMON
   38  ISENSE_PVSA_CPU1_IMON  BISEN1  @BASEBOARD_FAB2_LIB.BASEBOARD_FAB2(SCH_1):ISENSE_PVSA_CPU1_IMON
   32  ISENSE_PVCCIN_CPU1_PH5_IMON  AISEN5  @BASEBOARD_FAB2_LIB.BASEBOARD_FAB2(SCH_1):ISENSE_PVCCIN_CPU1_PH5_IMON
   30  ISENSE_PVCCIN_CPU1_PH4_IMON  AISEN4  @BASEBOARD_FAB2_LIB.BASEBOARD_FAB2(SCH_1):ISENSE_PVCCIN_CPU1_PH4_IMON
   28  ISENSE_PVCCIN_CPU1_PH3_IMON  AISEN3  @BASEBOARD_FAB2_LIB.BASEBOARD_FAB2(SCH_1):ISENSE_PVCCIN_CPU1_PH3_IMON
   26  ISENSE_PVCCIN_CPU1_PH2_IMON  AISEN2  @BASEBOARD_FAB2_LIB.BASEBOARD_FAB2(SCH_1):ISENSE_PVCCIN_CPU1_PH2_IMON
   24  ISENSE_PVCCIN_CPU1_PH1_IMON  AISEN1  @BASEBOARD_FAB2_LIB.BASEBOARD_FAB2(SCH_1):ISENSE_PVCCIN_CPU1_PH1_IMON
   13  IRQ_PVCCIN_CPU1_VRHOT_LVC3_R_N  VRHOT_N  @BASEBOARD_FAB2_LIB.BASEBOARD_FAB2(SCH_1):IRQ_PVCCIN_CPU1_VRHOT_LVC3_R_N
   49  GND            THPAD  @BASEBOARD_FAB2_LIB.BASEBOARD_FAB2(SCH_1):GND
   14  FM_PVCCIN_CPU1_PWR_IN_ALERT_N  PINALRT_N  @BASEBOARD_FAB2_LIB.BASEBOARD_FAB2(SCH_1):FM_PVCCIN_CPU1_PWR_IN_ALERT_N
   42  A_TSENSE_PVSA_CPU1  BTSEN  @BASEBOARD_FAB2_LIB.BASEBOARD_FAB2(SCH_1):A_TSENSE_PVSA_CPU1
   43  A_TSENSE_PVCCIN_CPU1  ATSEN  @BASEBOARD_FAB2_LIB.BASEBOARD_FAB2(SCH_1):A_TSENSE_PVCCIN_CPU1

IR354XX_SM  I56  EU1C3  [IR354XX_SM-IR35411,IC,H73688-0A]
   34  VR_PVCCIN_CPU1_PWM5    PWM  @BASEBOARD_FAB2_LIB.BASEBOARD_FAB2(SCH_1):VR_PVCCIN_CPU1_PWM5
   10  VR_PVCCIN_CPU1_PHASE5     SW  @BASEBOARD_FAB2_LIB.BASEBOARD_FAB2(SCH_1):VR_PVCCIN_CPU1_PHASE5
    3  VR_PVCCIN_CPU1_PH5_VCIN    VCC  @BASEBOARD_FAB2_LIB.BASEBOARD_FAB2(SCH_1):VR_PVCCIN_CPU1_PH5_VCIN
   32  VR_PVCCIN_CPU1_PH5_PHASE  PHASE  @BASEBOARD_FAB2_LIB.BASEBOARD_FAB2(SCH_1):VR_PVCCIN_CPU1_PH5_PHASE
   37  VR_PVCCIN_CPU1_PH5_OCSET  OCSET  @BASEBOARD_FAB2_LIB.BASEBOARD_FAB2(SCH_1):VR_PVCCIN_CPU1_PH5_OCSET
   33  VR_PVCCIN_CPU1_PH5_BOOT_R  BOOST  @BASEBOARD_FAB2_LIB.BASEBOARD_FAB2(SCH_1):VR_PVCCIN_CPU1_PH5_BOOT_R
   39  VR_PVCCIN_CPU1_AIREF5  REFIN  @BASEBOARD_FAB2_LIB.BASEBOARD_FAB2(SCH_1):VR_PVCCIN_CPU1_AIREF5
   30  VR_FET_SW_P12V_STBY_PVCCIN_CPU1  VIN<1>  @BASEBOARD_FAB2_LIB.BASEBOARD_FAB2(SCH_1):VR_FET_SW_P12V_STBY_PVCCIN_CPU1
   25  VR_FET_SW_P12V_STBY_PVCCIN_CPU1  VIN<0>  @BASEBOARD_FAB2_LIB.BASEBOARD_FAB2(SCH_1):VR_FET_SW_P12V_STBY_PVCCIN_CPU1
   41  TP_PVCCIN_CPU1_PH5_GL_1  GL<1>  @BASEBOARD_FAB2_LIB.BASEBOARD_FAB2(SCH_1):TP_PVCCIN_CPU1_PH5_GL_1
    6  TP_PVCCIN_CPU1_PH5_GL_0  GL<0>  @BASEBOARD_FAB2_LIB.BASEBOARD_FAB2(SCH_1):TP_PVCCIN_CPU1_PH5_GL_0
    1  PVCCIN_CPU1      VOS  @BASEBOARD_FAB2_LIB.BASEBOARD_FAB2(SCH_1):PVCCIN_CPU1
    4  P5V_STBY        VDRV  @BASEBOARD_FAB2_LIB.BASEBOARD_FAB2(SCH_1):P5V_STBY
   35  P5V_STBY          EN  @BASEBOARD_FAB2_LIB.BASEBOARD_FAB2(SCH_1):P5V_STBY
   31  NC_PVCCIN_CPU1_PH5_P31     NC  @BASEBOARD_FAB2_LIB.BASEBOARD_FAB2(SCH_1):NC_PVCCIN_CPU1_PH5_P31
   38  ISENSE_PVCCIN_CPU1_PH5_IMON   IOUT  @BASEBOARD_FAB2_LIB.BASEBOARD_FAB2(SCH_1):ISENSE_PVCCIN_CPU1_PH5_IMON
   40  GND            PGND<2>  @BASEBOARD_FAB2_LIB.BASEBOARD_FAB2(SCH_1):GND
    7  GND            PGND<1>  @BASEBOARD_FAB2_LIB.BASEBOARD_FAB2(SCH_1):GND
    5  GND            PGND<0>  @BASEBOARD_FAB2_LIB.BASEBOARD_FAB2(SCH_1):GND
    2  GND             LGND  @BASEBOARD_FAB2_LIB.BASEBOARD_FAB2(SCH_1):GND
   36  A_TSENSE_PVCCIN_CPU1  TOUT_FLT  @BASEBOARD_FAB2_LIB.BASEBOARD_FAB2(SCH_1):A_TSENSE_PVCCIN_CPU1

IR354XX_SM  I71  EU1D1  [IR354XX_SM-IR35411,IC,H73688-0A]
   34  VR_PVCCIN_CPU1_PWM4    PWM  @BASEBOARD_FAB2_LIB.BASEBOARD_FAB2(SCH_1):VR_PVCCIN_CPU1_PWM4
   10  VR_PVCCIN_CPU1_PHASE4     SW  @BASEBOARD_FAB2_LIB.BASEBOARD_FAB2(SCH_1):VR_PVCCIN_CPU1_PHASE4
    3  VR_PVCCIN_CPU1_PH4_VCIN    VCC  @BASEBOARD_FAB2_LIB.BASEBOARD_FAB2(SCH_1):VR_PVCCIN_CPU1_PH4_VCIN
   32  VR_PVCCIN_CPU1_PH4_PHASE  PHASE  @BASEBOARD_FAB2_LIB.BASEBOARD_FAB2(SCH_1):VR_PVCCIN_CPU1_PH4_PHASE
   37  VR_PVCCIN_CPU1_PH4_OCSET  OCSET  @BASEBOARD_FAB2_LIB.BASEBOARD_FAB2(SCH_1):VR_PVCCIN_CPU1_PH4_OCSET
   33  VR_PVCCIN_CPU1_PH4_BOOT_R  BOOST  @BASEBOARD_FAB2_LIB.BASEBOARD_FAB2(SCH_1):VR_PVCCIN_CPU1_PH4_BOOT_R
   39  VR_PVCCIN_CPU1_AIREF4  REFIN  @BASEBOARD_FAB2_LIB.BASEBOARD_FAB2(SCH_1):VR_PVCCIN_CPU1_AIREF4
   30  VR_FET_SW_P12V_STBY_PVCCIN_CPU1  VIN<1>  @BASEBOARD_FAB2_LIB.BASEBOARD_FAB2(SCH_1):VR_FET_SW_P12V_STBY_PVCCIN_CPU1
   25  VR_FET_SW_P12V_STBY_PVCCIN_CPU1  VIN<0>  @BASEBOARD_FAB2_LIB.BASEBOARD_FAB2(SCH_1):VR_FET_SW_P12V_STBY_PVCCIN_CPU1
   41  TP_PVCCIN_CPU1_PH4_GL_1  GL<1>  @BASEBOARD_FAB2_LIB.BASEBOARD_FAB2(SCH_1):TP_PVCCIN_CPU1_PH4_GL_1
    6  TP_PVCCIN_CPU1_PH4_GL_0  GL<0>  @BASEBOARD_FAB2_LIB.BASEBOARD_FAB2(SCH_1):TP_PVCCIN_CPU1_PH4_GL_0
    1  PVCCIN_CPU1      VOS  @BASEBOARD_FAB2_LIB.BASEBOARD_FAB2(SCH_1):PVCCIN_CPU1
    4  P5V_STBY        VDRV  @BASEBOARD_FAB2_LIB.BASEBOARD_FAB2(SCH_1):P5V_STBY
   35  P5V_STBY          EN  @BASEBOARD_FAB2_LIB.BASEBOARD_FAB2(SCH_1):P5V_STBY
   31  NC_PVCCIN_CPU1_PH4_P31     NC  @BASEBOARD_FAB2_LIB.BASEBOARD_FAB2(SCH_1):NC_PVCCIN_CPU1_PH4_P31
   38  ISENSE_PVCCIN_CPU1_PH4_IMON   IOUT  @BASEBOARD_FAB2_LIB.BASEBOARD_FAB2(SCH_1):ISENSE_PVCCIN_CPU1_PH4_IMON
   40  GND            PGND<2>  @BASEBOARD_FAB2_LIB.BASEBOARD_FAB2(SCH_1):GND
    7  GND            PGND<1>  @BASEBOARD_FAB2_LIB.BASEBOARD_FAB2(SCH_1):GND
    5  GND            PGND<0>  @BASEBOARD_FAB2_LIB.BASEBOARD_FAB2(SCH_1):GND
    2  GND             LGND  @BASEBOARD_FAB2_LIB.BASEBOARD_FAB2(SCH_1):GND
   36  A_TSENSE_PVCCIN_CPU1  TOUT_FLT  @BASEBOARD_FAB2_LIB.BASEBOARD_FAB2(SCH_1):A_TSENSE_PVCCIN_CPU1

ADM1278_SM  I10  EU1D2  [ADM1278_SM-IC,G99251-001]
    9  TP_HSC_SPISSN  SPISS_N  @BASEBOARD_FAB2_LIB.BASEBOARD_FAB2(SCH_1):TP_HSC_SPISSN
   11  TP_HSC_MDAT     MDAT  @BASEBOARD_FAB2_LIB.BASEBOARD_FAB2(SCH_1):TP_HSC_MDAT
   10  TP_HSC_MCLK     MCLK  @BASEBOARD_FAB2_LIB.BASEBOARD_FAB2(SCH_1):TP_HSC_MCLK
   14  TP_HSC_ALERT2_N  GPO2_ALERT2_N  @BASEBOARD_FAB2_LIB.BASEBOARD_FAB2(SCH_1):TP_HSC_ALERT2_N
   15  SMB_3V3SB_HSC_SDA_R    SDA  @BASEBOARD_FAB2_LIB.BASEBOARD_FAB2(SCH_1):SMB_3V3SB_HSC_SDA_R
   16  SMB_3V3SB_HSC_SCL_R    SCL  @BASEBOARD_FAB2_LIB.BASEBOARD_FAB2(SCH_1):SMB_3V3SB_HSC_SCL_R
   18  PWRGD_P12V_R   PWRGD  @BASEBOARD_FAB2_LIB.BASEBOARD_FAB2(SCH_1):PWRGD_P12V_R
   17  PD_HSC_RETRY_N  RETRY_N  @BASEBOARD_FAB2_LIB.BASEBOARD_FAB2(SCH_1):PD_HSC_RETRY_N
   30  P12V_HSC_VCC     VCC  @BASEBOARD_FAB2_LIB.BASEBOARD_FAB2(SCH_1):P12V_HSC_VCC
   13  IRQ_SML1_PMBUS_ALERT_R_N  GPO1_ALERT1_N_CONV  @BASEBOARD_FAB2_LIB.BASEBOARD_FAB2(SCH_1):IRQ_SML1_PMBUS_ALERT_R_N
    6  IRQ_HSC_FAULT_R_N  FAULT_N  @BASEBOARD_FAB2_LIB.BASEBOARD_FAB2(SCH_1):IRQ_HSC_FAULT_R_N
   23  GND             PGND  @BASEBOARD_FAB2_LIB.BASEBOARD_FAB2(SCH_1):GND
    8  FM_P12V_HSC_ADR2   ADR2  @BASEBOARD_FAB2_LIB.BASEBOARD_FAB2(SCH_1):FM_P12V_HSC_ADR2
    7  FM_P12V_HSC_ADR1   ADR1  @BASEBOARD_FAB2_LIB.BASEBOARD_FAB2(SCH_1):FM_P12V_HSC_ADR1
   12  FM_P12V_HOTSWAP0_EN  ENABLE  @BASEBOARD_FAB2_LIB.BASEBOARD_FAB2(SCH_1):FM_P12V_HOTSWAP0_EN
   20  A_HSC_VOUT      VOUT  @BASEBOARD_FAB2_LIB.BASEBOARD_FAB2(SCH_1):A_HSC_VOUT
    2  A_HSC_VCAP      VCAP  @BASEBOARD_FAB2_LIB.BASEBOARD_FAB2(SCH_1):A_HSC_VCAP
   31  A_HSC_UV          UV  @BASEBOARD_FAB2_LIB.BASEBOARD_FAB2(SCH_1):A_HSC_UV
    5  A_HSC_TIMER    TIMER  @BASEBOARD_FAB2_LIB.BASEBOARD_FAB2(SCH_1):A_HSC_TIMER
   25  A_HSC_TEMP      TEMP  @BASEBOARD_FAB2_LIB.BASEBOARD_FAB2(SCH_1):A_HSC_TEMP
   21  A_HSC_PWGIN    PWGIN  @BASEBOARD_FAB2_LIB.BASEBOARD_FAB2(SCH_1):A_HSC_PWGIN
    1  A_HSC_PSET      PSET  @BASEBOARD_FAB2_LIB.BASEBOARD_FAB2(SCH_1):A_HSC_PSET
   32  A_HSC_OV          OV  @BASEBOARD_FAB2_LIB.BASEBOARD_FAB2(SCH_1):A_HSC_OV
   29  A_HSC_MOP        MOP  @BASEBOARD_FAB2_LIB.BASEBOARD_FAB2(SCH_1):A_HSC_MOP
   26  A_HSC_MON        MON  @BASEBOARD_FAB2_LIB.BASEBOARD_FAB2(SCH_1):A_HSC_MON
    4  A_HSC_ISTART   ISTART  @BASEBOARD_FAB2_LIB.BASEBOARD_FAB2(SCH_1):A_HSC_ISTART
    3  A_HSC_ISET      ISET  @BASEBOARD_FAB2_LIB.BASEBOARD_FAB2(SCH_1):A_HSC_ISET
   28  A_HSC_HSP        HSP  @BASEBOARD_FAB2_LIB.BASEBOARD_FAB2(SCH_1):A_HSC_HSP
   27  A_HSC_HSN        HSN  @BASEBOARD_FAB2_LIB.BASEBOARD_FAB2(SCH_1):A_HSC_HSN
   24  A_HSC_GATE      GATE  @BASEBOARD_FAB2_LIB.BASEBOARD_FAB2(SCH_1):A_HSC_GATE
   19  A_HSC_CSOUT    CSOUT  @BASEBOARD_FAB2_LIB.BASEBOARD_FAB2(SCH_1):A_HSC_CSOUT
   22  AGND_HSC         GND  @BASEBOARD_FAB2_LIB.BASEBOARD_FAB2(SCH_1):AGND_HSC
   33  AGND_HSC          EP  @BASEBOARD_FAB2_LIB.BASEBOARD_FAB2(SCH_1):AGND_HSC

IR354XX_SM  I27  EU1D3  [IR354XX_SM-IR35411,IC,H73688-0A]
   34  VR_PVCCIN_CPU1_PWM3    PWM  @BASEBOARD_FAB2_LIB.BASEBOARD_FAB2(SCH_1):VR_PVCCIN_CPU1_PWM3
   10  VR_PVCCIN_CPU1_PHASE3     SW  @BASEBOARD_FAB2_LIB.BASEBOARD_FAB2(SCH_1):VR_PVCCIN_CPU1_PHASE3
    3  VR_PVCCIN_CPU1_PH3_VCIN    VCC  @BASEBOARD_FAB2_LIB.BASEBOARD_FAB2(SCH_1):VR_PVCCIN_CPU1_PH3_VCIN
   32  VR_PVCCIN_CPU1_PH3_PHASE  PHASE  @BASEBOARD_FAB2_LIB.BASEBOARD_FAB2(SCH_1):VR_PVCCIN_CPU1_PH3_PHASE
   37  VR_PVCCIN_CPU1_PH3_OCSET  OCSET  @BASEBOARD_FAB2_LIB.BASEBOARD_FAB2(SCH_1):VR_PVCCIN_CPU1_PH3_OCSET
   33  VR_PVCCIN_CPU1_PH3_BOOT_R  BOOST  @BASEBOARD_FAB2_LIB.BASEBOARD_FAB2(SCH_1):VR_PVCCIN_CPU1_PH3_BOOT_R
   39  VR_PVCCIN_CPU1_AIREF3  REFIN  @BASEBOARD_FAB2_LIB.BASEBOARD_FAB2(SCH_1):VR_PVCCIN_CPU1_AIREF3
   30  VR_FET_SW_P12V_STBY_PVCCIN_CPU1  VIN<1>  @BASEBOARD_FAB2_LIB.BASEBOARD_FAB2(SCH_1):VR_FET_SW_P12V_STBY_PVCCIN_CPU1
   25  VR_FET_SW_P12V_STBY_PVCCIN_CPU1  VIN<0>  @BASEBOARD_FAB2_LIB.BASEBOARD_FAB2(SCH_1):VR_FET_SW_P12V_STBY_PVCCIN_CPU1
   41  TP_PVCCIN_CPU1_PH3_GL_1  GL<1>  @BASEBOARD_FAB2_LIB.BASEBOARD_FAB2(SCH_1):TP_PVCCIN_CPU1_PH3_GL_1
    6  TP_PVCCIN_CPU1_PH3_GL_0  GL<0>  @BASEBOARD_FAB2_LIB.BASEBOARD_FAB2(SCH_1):TP_PVCCIN_CPU1_PH3_GL_0
    1  PVCCIN_CPU1      VOS  @BASEBOARD_FAB2_LIB.BASEBOARD_FAB2(SCH_1):PVCCIN_CPU1
    4  P5V_STBY        VDRV  @BASEBOARD_FAB2_LIB.BASEBOARD_FAB2(SCH_1):P5V_STBY
   35  P5V_STBY          EN  @BASEBOARD_FAB2_LIB.BASEBOARD_FAB2(SCH_1):P5V_STBY
   31  NC_PVCCIN_CPU1_PH3_P31     NC  @BASEBOARD_FAB2_LIB.BASEBOARD_FAB2(SCH_1):NC_PVCCIN_CPU1_PH3_P31
   38  ISENSE_PVCCIN_CPU1_PH3_IMON   IOUT  @BASEBOARD_FAB2_LIB.BASEBOARD_FAB2(SCH_1):ISENSE_PVCCIN_CPU1_PH3_IMON
   40  GND            PGND<2>  @BASEBOARD_FAB2_LIB.BASEBOARD_FAB2(SCH_1):GND
    7  GND            PGND<1>  @BASEBOARD_FAB2_LIB.BASEBOARD_FAB2(SCH_1):GND
    5  GND            PGND<0>  @BASEBOARD_FAB2_LIB.BASEBOARD_FAB2(SCH_1):GND
    2  GND             LGND  @BASEBOARD_FAB2_LIB.BASEBOARD_FAB2(SCH_1):GND
   36  A_TSENSE_PVCCIN_CPU1  TOUT_FLT  @BASEBOARD_FAB2_LIB.BASEBOARD_FAB2(SCH_1):A_TSENSE_PVCCIN_CPU1

IR354XX_SM  I24  EU1D4  [IR354XX_SM-IR35411,IC,H73688-0A]
   34  VR_PVCCIN_CPU1_PWM2    PWM  @BASEBOARD_FAB2_LIB.BASEBOARD_FAB2(SCH_1):VR_PVCCIN_CPU1_PWM2
   10  VR_PVCCIN_CPU1_PHASE2     SW  @BASEBOARD_FAB2_LIB.BASEBOARD_FAB2(SCH_1):VR_PVCCIN_CPU1_PHASE2
    3  VR_PVCCIN_CPU1_PH2_VCIN    VCC  @BASEBOARD_FAB2_LIB.BASEBOARD_FAB2(SCH_1):VR_PVCCIN_CPU1_PH2_VCIN
   32  VR_PVCCIN_CPU1_PH2_PHASE  PHASE  @BASEBOARD_FAB2_LIB.BASEBOARD_FAB2(SCH_1):VR_PVCCIN_CPU1_PH2_PHASE
   37  VR_PVCCIN_CPU1_PH2_OCSET  OCSET  @BASEBOARD_FAB2_LIB.BASEBOARD_FAB2(SCH_1):VR_PVCCIN_CPU1_PH2_OCSET
   33  VR_PVCCIN_CPU1_PH2_BOOT_R  BOOST  @BASEBOARD_FAB2_LIB.BASEBOARD_FAB2(SCH_1):VR_PVCCIN_CPU1_PH2_BOOT_R
   39  VR_PVCCIN_CPU1_AIREF2  REFIN  @BASEBOARD_FAB2_LIB.BASEBOARD_FAB2(SCH_1):VR_PVCCIN_CPU1_AIREF2
   30  VR_FET_SW_P12V_STBY_PVCCIN_CPU1  VIN<1>  @BASEBOARD_FAB2_LIB.BASEBOARD_FAB2(SCH_1):VR_FET_SW_P12V_STBY_PVCCIN_CPU1
   25  VR_FET_SW_P12V_STBY_PVCCIN_CPU1  VIN<0>  @BASEBOARD_FAB2_LIB.BASEBOARD_FAB2(SCH_1):VR_FET_SW_P12V_STBY_PVCCIN_CPU1
   41  TP_PVCCINC_CPU1_PH2_GL_1  GL<1>  @BASEBOARD_FAB2_LIB.BASEBOARD_FAB2(SCH_1):TP_PVCCINC_CPU1_PH2_GL_1
    6  TP_PVCCINC_CPU1_PH2_GL_0  GL<0>  @BASEBOARD_FAB2_LIB.BASEBOARD_FAB2(SCH_1):TP_PVCCINC_CPU1_PH2_GL_0
    1  PVCCIN_CPU1      VOS  @BASEBOARD_FAB2_LIB.BASEBOARD_FAB2(SCH_1):PVCCIN_CPU1
    4  P5V_STBY        VDRV  @BASEBOARD_FAB2_LIB.BASEBOARD_FAB2(SCH_1):P5V_STBY
   35  P5V_STBY          EN  @BASEBOARD_FAB2_LIB.BASEBOARD_FAB2(SCH_1):P5V_STBY
   31  NC_PVCCIN_CPU1_PH2_P31     NC  @BASEBOARD_FAB2_LIB.BASEBOARD_FAB2(SCH_1):NC_PVCCIN_CPU1_PH2_P31
   38  ISENSE_PVCCIN_CPU1_PH2_IMON   IOUT  @BASEBOARD_FAB2_LIB.BASEBOARD_FAB2(SCH_1):ISENSE_PVCCIN_CPU1_PH2_IMON
   40  GND            PGND<2>  @BASEBOARD_FAB2_LIB.BASEBOARD_FAB2(SCH_1):GND
    7  GND            PGND<1>  @BASEBOARD_FAB2_LIB.BASEBOARD_FAB2(SCH_1):GND
    5  GND            PGND<0>  @BASEBOARD_FAB2_LIB.BASEBOARD_FAB2(SCH_1):GND
    2  GND             LGND  @BASEBOARD_FAB2_LIB.BASEBOARD_FAB2(SCH_1):GND
   36  A_TSENSE_PVCCIN_CPU1  TOUT_FLT  @BASEBOARD_FAB2_LIB.BASEBOARD_FAB2(SCH_1):A_TSENSE_PVCCIN_CPU1

MOSFETN_1D3S_SOT5  I59  EU1E1  [MOSFETN_1D3S_SOT5-IC,G68777-001]
    3  P12V_STBY         S3  @BASEBOARD_FAB2_LIB.BASEBOARD_FAB2(SCH_1):P12V_STBY
    2  P12V_STBY         S2  @BASEBOARD_FAB2_LIB.BASEBOARD_FAB2(SCH_1):P12V_STBY
    1  P12V_STBY         S1  @BASEBOARD_FAB2_LIB.BASEBOARD_FAB2(SCH_1):P12V_STBY
    5  P12V_MB0_SW        D  @BASEBOARD_FAB2_LIB.BASEBOARD_FAB2(SCH_1):P12V_MB0_SW
    4  A_HSC_GATE3_R      G  @BASEBOARD_FAB2_LIB.BASEBOARD_FAB2(SCH_1):A_HSC_GATE3_R

IR354XX_SM  I20  EU1E2  [IR354XX_SM-IR35411,IC,H73688-0A]
   34  VR_PVCCIN_CPU1_PWM1    PWM  @BASEBOARD_FAB2_LIB.BASEBOARD_FAB2(SCH_1):VR_PVCCIN_CPU1_PWM1
   10  VR_PVCCIN_CPU1_PHASE1     SW  @BASEBOARD_FAB2_LIB.BASEBOARD_FAB2(SCH_1):VR_PVCCIN_CPU1_PHASE1
    3  VR_PVCCIN_CPU1_PH1_VCIN    VCC  @BASEBOARD_FAB2_LIB.BASEBOARD_FAB2(SCH_1):VR_PVCCIN_CPU1_PH1_VCIN
   32  VR_PVCCIN_CPU1_PH1_PHASE  PHASE  @BASEBOARD_FAB2_LIB.BASEBOARD_FAB2(SCH_1):VR_PVCCIN_CPU1_PH1_PHASE
   37  VR_PVCCIN_CPU1_PH1_OCSET  OCSET  @BASEBOARD_FAB2_LIB.BASEBOARD_FAB2(SCH_1):VR_PVCCIN_CPU1_PH1_OCSET
   33  VR_PVCCIN_CPU1_PH1_BOOT_R  BOOST  @BASEBOARD_FAB2_LIB.BASEBOARD_FAB2(SCH_1):VR_PVCCIN_CPU1_PH1_BOOT_R
   39  VR_PVCCIN_CPU1_AIREF1  REFIN  @BASEBOARD_FAB2_LIB.BASEBOARD_FAB2(SCH_1):VR_PVCCIN_CPU1_AIREF1
   30  VR_FET_SW_P12V_STBY_PVCCIN_CPU1  VIN<1>  @BASEBOARD_FAB2_LIB.BASEBOARD_FAB2(SCH_1):VR_FET_SW_P12V_STBY_PVCCIN_CPU1
   25  VR_FET_SW_P12V_STBY_PVCCIN_CPU1  VIN<0>  @BASEBOARD_FAB2_LIB.BASEBOARD_FAB2(SCH_1):VR_FET_SW_P12V_STBY_PVCCIN_CPU1
   41  TP_PVCCINC_CPU1_PH1_GL_1  GL<1>  @BASEBOARD_FAB2_LIB.BASEBOARD_FAB2(SCH_1):TP_PVCCINC_CPU1_PH1_GL_1
    6  TP_PVCCINC_CPU1_PH1_GL_0  GL<0>  @BASEBOARD_FAB2_LIB.BASEBOARD_FAB2(SCH_1):TP_PVCCINC_CPU1_PH1_GL_0
    1  PVCCIN_CPU1      VOS  @BASEBOARD_FAB2_LIB.BASEBOARD_FAB2(SCH_1):PVCCIN_CPU1
    4  P5V_STBY        VDRV  @BASEBOARD_FAB2_LIB.BASEBOARD_FAB2(SCH_1):P5V_STBY
   35  P5V_STBY          EN  @BASEBOARD_FAB2_LIB.BASEBOARD_FAB2(SCH_1):P5V_STBY
   31  NC_PVCCIN_CPU1_PH1_P31     NC  @BASEBOARD_FAB2_LIB.BASEBOARD_FAB2(SCH_1):NC_PVCCIN_CPU1_PH1_P31
   38  ISENSE_PVCCIN_CPU1_PH1_IMON   IOUT  @BASEBOARD_FAB2_LIB.BASEBOARD_FAB2(SCH_1):ISENSE_PVCCIN_CPU1_PH1_IMON
   40  GND            PGND<2>  @BASEBOARD_FAB2_LIB.BASEBOARD_FAB2(SCH_1):GND
    7  GND            PGND<1>  @BASEBOARD_FAB2_LIB.BASEBOARD_FAB2(SCH_1):GND
    5  GND            PGND<0>  @BASEBOARD_FAB2_LIB.BASEBOARD_FAB2(SCH_1):GND
    2  GND             LGND  @BASEBOARD_FAB2_LIB.BASEBOARD_FAB2(SCH_1):GND
   36  A_TSENSE_PVCCIN_CPU1  TOUT_FLT  @BASEBOARD_FAB2_LIB.BASEBOARD_FAB2(SCH_1):A_TSENSE_PVCCIN_CPU1

MOSFETN_1D3S_SOT5  I54  EU1E3  [MOSFETN_1D3S_SOT5-IC,G68777-001]
    3  P12V_STBY         S3  @BASEBOARD_FAB2_LIB.BASEBOARD_FAB2(SCH_1):P12V_STBY
    2  P12V_STBY         S2  @BASEBOARD_FAB2_LIB.BASEBOARD_FAB2(SCH_1):P12V_STBY
    1  P12V_STBY         S1  @BASEBOARD_FAB2_LIB.BASEBOARD_FAB2(SCH_1):P12V_STBY
    5  P12V_MB0_SW        D  @BASEBOARD_FAB2_LIB.BASEBOARD_FAB2(SCH_1):P12V_MB0_SW
    4  A_HSC_GATE1_R      G  @BASEBOARD_FAB2_LIB.BASEBOARD_FAB2(SCH_1):A_HSC_GATE1_R

IR354XX_SM  I111  EU1F1  [IR354XX_SM-IR35411,IC,H73688-0A]
   34  VR_PVDDQ_GHJ_PWM2    PWM  @BASEBOARD_FAB2_LIB.BASEBOARD_FAB2(SCH_1):VR_PVDDQ_GHJ_PWM2
    3  VR_PVDDQ_GHJ_PH2_VCIN    VCC  @BASEBOARD_FAB2_LIB.BASEBOARD_FAB2(SCH_1):VR_PVDDQ_GHJ_PH2_VCIN
   10  VR_PVDDQ_GHJ_PH2_SW     SW  @BASEBOARD_FAB2_LIB.BASEBOARD_FAB2(SCH_1):VR_PVDDQ_GHJ_PH2_SW
   32  VR_PVDDQ_GHJ_PH2_PHASE  PHASE  @BASEBOARD_FAB2_LIB.BASEBOARD_FAB2(SCH_1):VR_PVDDQ_GHJ_PH2_PHASE
   37  VR_PVDDQ_GHJ_PH2_OCSET  OCSET  @BASEBOARD_FAB2_LIB.BASEBOARD_FAB2(SCH_1):VR_PVDDQ_GHJ_PH2_OCSET
   33  VR_PVDDQ_GHJ_PH2_BOOT_R  BOOST  @BASEBOARD_FAB2_LIB.BASEBOARD_FAB2(SCH_1):VR_PVDDQ_GHJ_PH2_BOOT_R
   39  VR_PVDDQ_GHJ_AIREF2  REFIN  @BASEBOARD_FAB2_LIB.BASEBOARD_FAB2(SCH_1):VR_PVDDQ_GHJ_AIREF2
   30  VR_FET_SW_P12V_STBY_PVDDQ_GHJ  VIN<1>  @BASEBOARD_FAB2_LIB.BASEBOARD_FAB2(SCH_1):VR_FET_SW_P12V_STBY_PVDDQ_GHJ
   25  VR_FET_SW_P12V_STBY_PVDDQ_GHJ  VIN<0>  @BASEBOARD_FAB2_LIB.BASEBOARD_FAB2(SCH_1):VR_FET_SW_P12V_STBY_PVDDQ_GHJ
   41  TP_PVDDQ_GHJ_PH2_GL_1  GL<1>  @BASEBOARD_FAB2_LIB.BASEBOARD_FAB2(SCH_1):TP_PVDDQ_GHJ_PH2_GL_1
    6  TP_PVDDQ_GHJ_PH2_GL_0  GL<0>  @BASEBOARD_FAB2_LIB.BASEBOARD_FAB2(SCH_1):TP_PVDDQ_GHJ_PH2_GL_0
    1  PVDDQ_GHJ        VOS  @BASEBOARD_FAB2_LIB.BASEBOARD_FAB2(SCH_1):PVDDQ_GHJ
    4  P5V_STBY        VDRV  @BASEBOARD_FAB2_LIB.BASEBOARD_FAB2(SCH_1):P5V_STBY
   35  P5V_STBY          EN  @BASEBOARD_FAB2_LIB.BASEBOARD_FAB2(SCH_1):P5V_STBY
   31  NC_PVDDQ_GHJ_PH2_P31     NC  @BASEBOARD_FAB2_LIB.BASEBOARD_FAB2(SCH_1):NC_PVDDQ_GHJ_PH2_P31
   38  ISENSE_PVDDQ_GHJ_PH2_IMON   IOUT  @BASEBOARD_FAB2_LIB.BASEBOARD_FAB2(SCH_1):ISENSE_PVDDQ_GHJ_PH2_IMON
   40  GND            PGND<2>  @BASEBOARD_FAB2_LIB.BASEBOARD_FAB2(SCH_1):GND
    7  GND            PGND<1>  @BASEBOARD_FAB2_LIB.BASEBOARD_FAB2(SCH_1):GND
    5  GND            PGND<0>  @BASEBOARD_FAB2_LIB.BASEBOARD_FAB2(SCH_1):GND
    2  GND             LGND  @BASEBOARD_FAB2_LIB.BASEBOARD_FAB2(SCH_1):GND
   36  A_TSENSE_PVDDQ_GHJ  TOUT_FLT  @BASEBOARD_FAB2_LIB.BASEBOARD_FAB2(SCH_1):A_TSENSE_PVDDQ_GHJ

IR354XX_SM  I110  EU1G1  [IR354XX_SM-IR35411,IC,H73688-0A]
   34  VR_PVDDQ_GHJ_PWM1    PWM  @BASEBOARD_FAB2_LIB.BASEBOARD_FAB2(SCH_1):VR_PVDDQ_GHJ_PWM1
    3  VR_PVDDQ_GHJ_PH1_VCIN    VCC  @BASEBOARD_FAB2_LIB.BASEBOARD_FAB2(SCH_1):VR_PVDDQ_GHJ_PH1_VCIN
   10  VR_PVDDQ_GHJ_PH1_SW     SW  @BASEBOARD_FAB2_LIB.BASEBOARD_FAB2(SCH_1):VR_PVDDQ_GHJ_PH1_SW
   32  VR_PVDDQ_GHJ_PH1_PHASE  PHASE  @BASEBOARD_FAB2_LIB.BASEBOARD_FAB2(SCH_1):VR_PVDDQ_GHJ_PH1_PHASE
   37  VR_PVDDQ_GHJ_PH1_OCSET  OCSET  @BASEBOARD_FAB2_LIB.BASEBOARD_FAB2(SCH_1):VR_PVDDQ_GHJ_PH1_OCSET
   33  VR_PVDDQ_GHJ_PH1_BOOT_R  BOOST  @BASEBOARD_FAB2_LIB.BASEBOARD_FAB2(SCH_1):VR_PVDDQ_GHJ_PH1_BOOT_R
   39  VR_PVDDQ_GHJ_AIREF1  REFIN  @BASEBOARD_FAB2_LIB.BASEBOARD_FAB2(SCH_1):VR_PVDDQ_GHJ_AIREF1
   30  VR_FET_SW_P12V_STBY_PVDDQ_GHJ  VIN<1>  @BASEBOARD_FAB2_LIB.BASEBOARD_FAB2(SCH_1):VR_FET_SW_P12V_STBY_PVDDQ_GHJ
   25  VR_FET_SW_P12V_STBY_PVDDQ_GHJ  VIN<0>  @BASEBOARD_FAB2_LIB.BASEBOARD_FAB2(SCH_1):VR_FET_SW_P12V_STBY_PVDDQ_GHJ
   41  TP_PVDDQ_GHJ_PH1_GL_1  GL<1>  @BASEBOARD_FAB2_LIB.BASEBOARD_FAB2(SCH_1):TP_PVDDQ_GHJ_PH1_GL_1
    6  TP_PVDDQ_GHJ_PH1_GL_0  GL<0>  @BASEBOARD_FAB2_LIB.BASEBOARD_FAB2(SCH_1):TP_PVDDQ_GHJ_PH1_GL_0
    1  PVDDQ_GHJ        VOS  @BASEBOARD_FAB2_LIB.BASEBOARD_FAB2(SCH_1):PVDDQ_GHJ
    4  P5V_STBY        VDRV  @BASEBOARD_FAB2_LIB.BASEBOARD_FAB2(SCH_1):P5V_STBY
   35  P5V_STBY          EN  @BASEBOARD_FAB2_LIB.BASEBOARD_FAB2(SCH_1):P5V_STBY
   31  NC_PVDDQ_GHJ_PH1_P31     NC  @BASEBOARD_FAB2_LIB.BASEBOARD_FAB2(SCH_1):NC_PVDDQ_GHJ_PH1_P31
   38  ISENSE_PVDDQ_GHJ_PH1_IMON   IOUT  @BASEBOARD_FAB2_LIB.BASEBOARD_FAB2(SCH_1):ISENSE_PVDDQ_GHJ_PH1_IMON
   40  GND            PGND<2>  @BASEBOARD_FAB2_LIB.BASEBOARD_FAB2(SCH_1):GND
    7  GND            PGND<1>  @BASEBOARD_FAB2_LIB.BASEBOARD_FAB2(SCH_1):GND
    5  GND            PGND<0>  @BASEBOARD_FAB2_LIB.BASEBOARD_FAB2(SCH_1):GND
    2  GND             LGND  @BASEBOARD_FAB2_LIB.BASEBOARD_FAB2(SCH_1):GND
   36  A_TSENSE_PVDDQ_GHJ  TOUT_FLT  @BASEBOARD_FAB2_LIB.BASEBOARD_FAB2(SCH_1):A_TSENSE_PVDDQ_GHJ

PXM1310B_QFN  I90  EU1G2  [PXM1310B_QFN-IC,H89186-001]
   20  VSENSE_PVDDQ_GHJ_N  AVREF  @BASEBOARD_FAB2_LIB.BASEBOARD_FAB2(SCH_1):VSENSE_PVDDQ_GHJ_N
   33  VR_PVDDQ_GHJ_XADDR2  XADDR2  @BASEBOARD_FAB2_LIB.BASEBOARD_FAB2(SCH_1):VR_PVDDQ_GHJ_XADDR2
   36  VR_PVDDQ_GHJ_XADDR1  XADDR1  @BASEBOARD_FAB2_LIB.BASEBOARD_FAB2(SCH_1):VR_PVDDQ_GHJ_XADDR1
   10  VR_PVDDQ_GHJ_VREN  AVREN  @BASEBOARD_FAB2_LIB.BASEBOARD_FAB2(SCH_1):VR_PVDDQ_GHJ_VREN
   37  VR_PVDDQ_GHJ_VINSEN  VINSEN  @BASEBOARD_FAB2_LIB.BASEBOARD_FAB2(SCH_1):VR_PVDDQ_GHJ_VINSEN
   39  VR_PVDDQ_GHJ_VDD    VDD  @BASEBOARD_FAB2_LIB.BASEBOARD_FAB2(SCH_1):VR_PVDDQ_GHJ_VDD
   40  VR_PVDDQ_GHJ_VD12   VD12  @BASEBOARD_FAB2_LIB.BASEBOARD_FAB2(SCH_1):VR_PVDDQ_GHJ_VD12
    4  VR_PVDDQ_GHJ_PWM2  APWM2  @BASEBOARD_FAB2_LIB.BASEBOARD_FAB2(SCH_1):VR_PVDDQ_GHJ_PWM2
    5  VR_PVDDQ_GHJ_PWM1  APWM1  @BASEBOARD_FAB2_LIB.BASEBOARD_FAB2(SCH_1):VR_PVDDQ_GHJ_PWM1
   19  VR_PVDDQ_GHJ_AVSP  AVSEN  @BASEBOARD_FAB2_LIB.BASEBOARD_FAB2(SCH_1):VR_PVDDQ_GHJ_AVSP
   23  VR_PVDDQ_GHJ_AIREF2  AIREF2  @BASEBOARD_FAB2_LIB.BASEBOARD_FAB2(SCH_1):VR_PVDDQ_GHJ_AIREF2
   21  VR_PVDDQ_GHJ_AIREF1  AIREF1  @BASEBOARD_FAB2_LIB.BASEBOARD_FAB2(SCH_1):VR_PVDDQ_GHJ_AIREF1
   38  VR_PVDDQ_GHJ_AIINSEN  IINSEN  @BASEBOARD_FAB2_LIB.BASEBOARD_FAB2(SCH_1):VR_PVDDQ_GHJ_AIINSEN
    8  TP_PVDDQ_GHJ_RESET_N  RESET_N  @BASEBOARD_FAB2_LIB.BASEBOARD_FAB2(SCH_1):TP_PVDDQ_GHJ_RESET_N
    3  TP_PVDDQ_GHJ_PWM3  APWM3  @BASEBOARD_FAB2_LIB.BASEBOARD_FAB2(SCH_1):TP_PVDDQ_GHJ_PWM3
   25  TP_PVDDQ_GHJ_PH3_IMON_REF  AIREF3  @BASEBOARD_FAB2_LIB.BASEBOARD_FAB2(SCH_1):TP_PVDDQ_GHJ_PH3_IMON_REF
   26  TP_PVDDQ_GHJ_PH3_IMON  AISEN3  @BASEBOARD_FAB2_LIB.BASEBOARD_FAB2(SCH_1):TP_PVDDQ_GHJ_PH3_IMON
   18  TP_PVDDQ_GHJ_MP2    MP2  @BASEBOARD_FAB2_LIB.BASEBOARD_FAB2(SCH_1):TP_PVDDQ_GHJ_MP2
   14  TP_PVDDQ_GHJ_MP1    MP1  @BASEBOARD_FAB2_LIB.BASEBOARD_FAB2(SCH_1):TP_PVDDQ_GHJ_MP1
   29  TP_PVDDQ_GHJ_BVSEN  BVSEN  @BASEBOARD_FAB2_LIB.BASEBOARD_FAB2(SCH_1):TP_PVDDQ_GHJ_BVSEN
   30  TP_PVDDQ_GHJ_BVREF  BVREF  @BASEBOARD_FAB2_LIB.BASEBOARD_FAB2(SCH_1):TP_PVDDQ_GHJ_BVREF
   34  TP_PVDDQ_GHJ_BTSEN  BTSEN  @BASEBOARD_FAB2_LIB.BASEBOARD_FAB2(SCH_1):TP_PVDDQ_GHJ_BTSEN
   31  TP_PVDDQ_GHJ_BREF1  BIREF1  @BASEBOARD_FAB2_LIB.BASEBOARD_FAB2(SCH_1):TP_PVDDQ_GHJ_BREF1
    1  TP_PVDDQ_GHJ_BPWM1  BPWM1  @BASEBOARD_FAB2_LIB.BASEBOARD_FAB2(SCH_1):TP_PVDDQ_GHJ_BPWM1
   16  SVID_VDIO_PVDDQ_GHJ   VDIO  @BASEBOARD_FAB2_LIB.BASEBOARD_FAB2(SCH_1):SVID_VDIO_PVDDQ_GHJ
   15  SVID_CLK_PVDDQ_GHJ   VCLK  @BASEBOARD_FAB2_LIB.BASEBOARD_FAB2(SCH_1):SVID_CLK_PVDDQ_GHJ
   17  SVID_ALERT_PVDDQ_GHJ  VALRT_N  @BASEBOARD_FAB2_LIB.BASEBOARD_FAB2(SCH_1):SVID_ALERT_PVDDQ_GHJ
    6  SMB_VR_SDA_VDDQ_GHJ    SDA  @BASEBOARD_FAB2_LIB.BASEBOARD_FAB2(SCH_1):SMB_VR_SDA_VDDQ_GHJ
    7  SMB_VR_SCL_VDDQ_GHJ    SCL  @BASEBOARD_FAB2_LIB.BASEBOARD_FAB2(SCH_1):SMB_VR_SCL_VDDQ_GHJ
    9  PWRGD_PVDDQ_GHJ_R  AVRRDY  @BASEBOARD_FAB2_LIB.BASEBOARD_FAB2(SCH_1):PWRGD_PVDDQ_GHJ_R
   13  PU_VR_PVDDQ_GHJ_FAULT1    MP0  @BASEBOARD_FAB2_LIB.BASEBOARD_FAB2(SCH_1):PU_VR_PVDDQ_GHJ_FAULT1
   12  NC_PVDDQ_GHJ_PINALRT_N  PINALRT_N  @BASEBOARD_FAB2_LIB.BASEBOARD_FAB2(SCH_1):NC_PVDDQ_GHJ_PINALRT_N
   28  NC_PVDDQ_GHJ_DNC1  DNC<1>  @BASEBOARD_FAB2_LIB.BASEBOARD_FAB2(SCH_1):NC_PVDDQ_GHJ_DNC1
    2  NC_PVDDQ_GHJ_DNC0  DNC<0>  @BASEBOARD_FAB2_LIB.BASEBOARD_FAB2(SCH_1):NC_PVDDQ_GHJ_DNC0
   24  ISENSE_PVDDQ_GHJ_PH2_IMON  AISEN2  @BASEBOARD_FAB2_LIB.BASEBOARD_FAB2(SCH_1):ISENSE_PVDDQ_GHJ_PH2_IMON
   22  ISENSE_PVDDQ_GHJ_PH1_IMON  AISEN1  @BASEBOARD_FAB2_LIB.BASEBOARD_FAB2(SCH_1):ISENSE_PVDDQ_GHJ_PH1_IMON
   11  IRQ_PVDDQ_GHJ_VRHOT_LVT3_R_N  VRHOT_N  @BASEBOARD_FAB2_LIB.BASEBOARD_FAB2(SCH_1):IRQ_PVDDQ_GHJ_VRHOT_LVT3_R_N
   41  GND            THPAD  @BASEBOARD_FAB2_LIB.BASEBOARD_FAB2(SCH_1):GND
   27  GND              GND  @BASEBOARD_FAB2_LIB.BASEBOARD_FAB2(SCH_1):GND
   32  GND            BISEN1  @BASEBOARD_FAB2_LIB.BASEBOARD_FAB2(SCH_1):GND
   35  A_TSENSE_PVDDQ_GHJ  ATSEN  @BASEBOARD_FAB2_LIB.BASEBOARD_FAB2(SCH_1):A_TSENSE_PVDDQ_GHJ

SLG55021_SM  I1   EU2T1  [SLG55021_SM-IC,G56246-001]
    8  TP_SLG55021_P3V3_8     PG  @BASEBOARD_FAB2_LIB.BASEBOARD_FAB2(SCH_1):TP_SLG55021_P3V3_8
    1  P5V_STBY         VCC  @BASEBOARD_FAB2_LIB.BASEBOARD_FAB2(SCH_1):P5V_STBY
    3  P5V_STBY       SHDN_N  @BASEBOARD_FAB2_LIB.BASEBOARD_FAB2(SCH_1):P5V_STBY
    7  P3V3_SWITCH_G      G  @BASEBOARD_FAB2_LIB.BASEBOARD_FAB2(SCH_1):P3V3_SWITCH_G
    5  P3V3_STBY          D  @BASEBOARD_FAB2_LIB.BASEBOARD_FAB2(SCH_1):P3V3_STBY
    6  P3V3               S  @BASEBOARD_FAB2_LIB.BASEBOARD_FAB2(SCH_1):P3V3
    9  GND            THPAD  @BASEBOARD_FAB2_LIB.BASEBOARD_FAB2(SCH_1):GND
    4  GND              GND  @BASEBOARD_FAB2_LIB.BASEBOARD_FAB2(SCH_1):GND
    2  FM_P3V3_CPLD_EN     ON  @BASEBOARD_FAB2_LIB.BASEBOARD_FAB2(SCH_1):FM_P3V3_CPLD_EN

PXE1110B_QFN  I93  EU3P1  [PXE1110B_QFN-IC,H89187-001]
   20  VSENSE_PVCCIO_CPU0_AVSN  AVREF  @BASEBOARD_FAB2_LIB.BASEBOARD_FAB2(SCH_1):VSENSE_PVCCIO_CPU0_AVSN
   33  VR_PVCCIO_CPU0_XADDR2  XADDR2  @BASEBOARD_FAB2_LIB.BASEBOARD_FAB2(SCH_1):VR_PVCCIO_CPU0_XADDR2
   36  VR_PVCCIO_CPU0_XADDR1  XADDR1  @BASEBOARD_FAB2_LIB.BASEBOARD_FAB2(SCH_1):VR_PVCCIO_CPU0_XADDR1
   37  VR_PVCCIO_CPU0_VINSEN  VINSEN  @BASEBOARD_FAB2_LIB.BASEBOARD_FAB2(SCH_1):VR_PVCCIO_CPU0_VINSEN
   39  VR_PVCCIO_CPU0_VDD    VDD  @BASEBOARD_FAB2_LIB.BASEBOARD_FAB2(SCH_1):VR_PVCCIO_CPU0_VDD
   40  VR_PVCCIO_CPU0_VD12   VD12  @BASEBOARD_FAB2_LIB.BASEBOARD_FAB2(SCH_1):VR_PVCCIO_CPU0_VD12
    5  VR_PVCCIO_CPU0_PWM1  APWM1  @BASEBOARD_FAB2_LIB.BASEBOARD_FAB2(SCH_1):VR_PVCCIO_CPU0_PWM1
   10  VR_PVCCIO_CPU0_EN  AVREN  @BASEBOARD_FAB2_LIB.BASEBOARD_FAB2(SCH_1):VR_PVCCIO_CPU0_EN
   19  VR_PVCCIO_CPU0_AVSP  AVSEN  @BASEBOARD_FAB2_LIB.BASEBOARD_FAB2(SCH_1):VR_PVCCIO_CPU0_AVSP
   21  VR_PVCCIO_CPU0_AIREF1  AIREF1  @BASEBOARD_FAB2_LIB.BASEBOARD_FAB2(SCH_1):VR_PVCCIO_CPU0_AIREF1
   31  TP_VR_PVCCIO_CPU0_MP3    MP3  @BASEBOARD_FAB2_LIB.BASEBOARD_FAB2(SCH_1):TP_VR_PVCCIO_CPU0_MP3
   18  TP_VR_PVCCIO_CPU0_MP2    MP2  @BASEBOARD_FAB2_LIB.BASEBOARD_FAB2(SCH_1):TP_VR_PVCCIO_CPU0_MP2
   14  TP_VR_PVCCIO_CPU0_MP1    MP1  @BASEBOARD_FAB2_LIB.BASEBOARD_FAB2(SCH_1):TP_VR_PVCCIO_CPU0_MP1
   13  TP_VR_PVCCIO_CPU0_MP0    MP0  @BASEBOARD_FAB2_LIB.BASEBOARD_FAB2(SCH_1):TP_VR_PVCCIO_CPU0_MP0
   38  TP_VR_PVCCIO_CPU0_AIINSEN  IINSEN  @BASEBOARD_FAB2_LIB.BASEBOARD_FAB2(SCH_1):TP_VR_PVCCIO_CPU0_AIINSEN
    8  TP_PVCCIO_CPU0_RESET_N  RESET_N  @BASEBOARD_FAB2_LIB.BASEBOARD_FAB2(SCH_1):TP_PVCCIO_CPU0_RESET_N
   12  TP_PVCCIO_CPU0_PINALRT_N  PINALRT_N  @BASEBOARD_FAB2_LIB.BASEBOARD_FAB2(SCH_1):TP_PVCCIO_CPU0_PINALRT_N
   29  TP_PVCCIO_CPU0_BVSEN  BVSEN  @BASEBOARD_FAB2_LIB.BASEBOARD_FAB2(SCH_1):TP_PVCCIO_CPU0_BVSEN
   30  TP_PVCCIO_CPU0_BVREF  BVREF  @BASEBOARD_FAB2_LIB.BASEBOARD_FAB2(SCH_1):TP_PVCCIO_CPU0_BVREF
   34  TP_PVCCIO_CPU0_BTSEN  BTSEN  @BASEBOARD_FAB2_LIB.BASEBOARD_FAB2(SCH_1):TP_PVCCIO_CPU0_BTSEN
    3  TP_PVCCIO_CPU0_BPWM1  BPWM1  @BASEBOARD_FAB2_LIB.BASEBOARD_FAB2(SCH_1):TP_PVCCIO_CPU0_BPWM1
   25  TP_PVCCIO_CPU0_BIREF1  BIREF1  @BASEBOARD_FAB2_LIB.BASEBOARD_FAB2(SCH_1):TP_PVCCIO_CPU0_BIREF1
   16  SVID_VDIO_PVCCIO_CPU0   VDIO  @BASEBOARD_FAB2_LIB.BASEBOARD_FAB2(SCH_1):SVID_VDIO_PVCCIO_CPU0
   15  SVID_CLK_PVCCIO_CPU0   VCLK  @BASEBOARD_FAB2_LIB.BASEBOARD_FAB2(SCH_1):SVID_CLK_PVCCIO_CPU0
   17  SVID_ALERT_PVCCIO_CPU0  VALRT_N  @BASEBOARD_FAB2_LIB.BASEBOARD_FAB2(SCH_1):SVID_ALERT_PVCCIO_CPU0
    6  SMB_VR_SDA_PVCCIO_CPU0    SDA  @BASEBOARD_FAB2_LIB.BASEBOARD_FAB2(SCH_1):SMB_VR_SDA_PVCCIO_CPU0
    7  SMB_VR_SCL_PVCCIO_CPU0    SCL  @BASEBOARD_FAB2_LIB.BASEBOARD_FAB2(SCH_1):SMB_VR_SCL_PVCCIO_CPU0
    9  PWRGD_PVCCIO_CPU0_R  AVRRDY  @BASEBOARD_FAB2_LIB.BASEBOARD_FAB2(SCH_1):PWRGD_PVCCIO_CPU0_R
   32  PU_VR_PVCCIO_CPU0_FAULT1    MP4  @BASEBOARD_FAB2_LIB.BASEBOARD_FAB2(SCH_1):PU_VR_PVCCIO_CPU0_FAULT1
   28  NC_PVCCIO_CPU0_DNC4  DNC<4>  @BASEBOARD_FAB2_LIB.BASEBOARD_FAB2(SCH_1):NC_PVCCIO_CPU0_DNC4
   24  NC_PVCCIO_CPU0_DNC3  DNC<3>  @BASEBOARD_FAB2_LIB.BASEBOARD_FAB2(SCH_1):NC_PVCCIO_CPU0_DNC3
    4  NC_PVCCIO_CPU0_DNC2  DNC<2>  @BASEBOARD_FAB2_LIB.BASEBOARD_FAB2(SCH_1):NC_PVCCIO_CPU0_DNC2
    2  NC_PVCCIO_CPU0_DNC1  DNC<1>  @BASEBOARD_FAB2_LIB.BASEBOARD_FAB2(SCH_1):NC_PVCCIO_CPU0_DNC1
    1  NC_PVCCIO_CPU0_DNC0  DNC<0>  @BASEBOARD_FAB2_LIB.BASEBOARD_FAB2(SCH_1):NC_PVCCIO_CPU0_DNC0
   22  ISENSE_PVCCIO_CPU0_PH1_IMON  AISEN1  @BASEBOARD_FAB2_LIB.BASEBOARD_FAB2(SCH_1):ISENSE_PVCCIO_CPU0_PH1_IMON
   11  IRQ_PVCCIO_CPU0_VRHOT_N  VRHOT_N  @BASEBOARD_FAB2_LIB.BASEBOARD_FAB2(SCH_1):IRQ_PVCCIO_CPU0_VRHOT_N
   41  GND            THPAD  @BASEBOARD_FAB2_LIB.BASEBOARD_FAB2(SCH_1):GND
   23  GND            GND<1>  @BASEBOARD_FAB2_LIB.BASEBOARD_FAB2(SCH_1):GND
   27  GND            GND<0>  @BASEBOARD_FAB2_LIB.BASEBOARD_FAB2(SCH_1):GND
   26  GND            BISEN1  @BASEBOARD_FAB2_LIB.BASEBOARD_FAB2(SCH_1):GND
   35  A_TSENSE_PVCCIO_CPU0  ATSEN  @BASEBOARD_FAB2_LIB.BASEBOARD_FAB2(SCH_1):A_TSENSE_PVCCIO_CPU0

MIC5166_DFN  I31  EU4A1  [MIC5166_DFN-IC,H55101-001]
    4  VSENSE_PVDDQ_DEF_VTT   VDDQ  @BASEBOARD_FAB2_LIB.BASEBOARD_FAB2(SCH_1):VSENSE_PVDDQ_DEF_VTT
    1  VR_PVTT_DEF_VREF   VREF  @BASEBOARD_FAB2_LIB.BASEBOARD_FAB2(SCH_1):VR_PVTT_DEF_VREF
    6  VR_PVTT_DEF_SNS    SNS  @BASEBOARD_FAB2_LIB.BASEBOARD_FAB2(SCH_1):VR_PVTT_DEF_SNS
    2  VR_PVTT_DEF_BIAS   BIAS  @BASEBOARD_FAB2_LIB.BASEBOARD_FAB2(SCH_1):VR_PVTT_DEF_BIAS
    5  PWRGD_PVTT_DEF_CPU0_R     PG  @BASEBOARD_FAB2_LIB.BASEBOARD_FAB2(SCH_1):PWRGD_PVTT_DEF_CPU0_R
    9  PVTT_DEF         VTT  @BASEBOARD_FAB2_LIB.BASEBOARD_FAB2(SCH_1):PVTT_DEF
   10  PVDDQ_DEF        VIN  @BASEBOARD_FAB2_LIB.BASEBOARD_FAB2(SCH_1):PVDDQ_DEF
   11  GND            THPAD  @BASEBOARD_FAB2_LIB.BASEBOARD_FAB2(SCH_1):GND
    8  GND             PGND  @BASEBOARD_FAB2_LIB.BASEBOARD_FAB2(SCH_1):GND
    3  GND             AGND  @BASEBOARD_FAB2_LIB.BASEBOARD_FAB2(SCH_1):GND
    7  FM_PVTT_DEF_EN_R     EN  @BASEBOARD_FAB2_LIB.BASEBOARD_FAB2(SCH_1):FM_PVTT_DEF_EN_R

MIC5166_DFN  I31  EU4A2  [MIC5166_DFN-IC,H55101-001]
    4  VSENSE_PVDDQ_KLM_VTT   VDDQ  @BASEBOARD_FAB2_LIB.BASEBOARD_FAB2(SCH_1):VSENSE_PVDDQ_KLM_VTT
    1  VR_PVTT_KLM_VREF   VREF  @BASEBOARD_FAB2_LIB.BASEBOARD_FAB2(SCH_1):VR_PVTT_KLM_VREF
    6  VR_PVTT_KLM_SNS    SNS  @BASEBOARD_FAB2_LIB.BASEBOARD_FAB2(SCH_1):VR_PVTT_KLM_SNS
    2  VR_PVTT_KLM_BIAS   BIAS  @BASEBOARD_FAB2_LIB.BASEBOARD_FAB2(SCH_1):VR_PVTT_KLM_BIAS
    5  PWRGD_PVTT_KLM_CPU1_R     PG  @BASEBOARD_FAB2_LIB.BASEBOARD_FAB2(SCH_1):PWRGD_PVTT_KLM_CPU1_R
    9  PVTT_KLM         VTT  @BASEBOARD_FAB2_LIB.BASEBOARD_FAB2(SCH_1):PVTT_KLM
   10  PVDDQ_KLM        VIN  @BASEBOARD_FAB2_LIB.BASEBOARD_FAB2(SCH_1):PVDDQ_KLM
   11  GND            THPAD  @BASEBOARD_FAB2_LIB.BASEBOARD_FAB2(SCH_1):GND
    8  GND             PGND  @BASEBOARD_FAB2_LIB.BASEBOARD_FAB2(SCH_1):GND
    3  GND             AGND  @BASEBOARD_FAB2_LIB.BASEBOARD_FAB2(SCH_1):GND
    7  FM_PVTT_KLM_EN_R     EN  @BASEBOARD_FAB2_LIB.BASEBOARD_FAB2(SCH_1):FM_PVTT_KLM_EN_R

NCP3232L_SM  I184  EU4A3  [NCP3232L_SM-IC,H86355-001]
   38  VR_VB_PVPP_KLM     VB  @BASEBOARD_FAB2_LIB.BASEBOARD_FAB2(SCH_1):VR_VB_PVPP_KLM
    1  VR_PVPP_KLM_SS     SS  @BASEBOARD_FAB2_LIB.BASEBOARD_FAB2(SCH_1):VR_PVPP_KLM_SS
   43  VR_PVPP_KLM_PHASE  VSWH<7>  @BASEBOARD_FAB2_LIB.BASEBOARD_FAB2(SCH_1):VR_PVPP_KLM_PHASE
   34  VR_PVPP_KLM_PHASE  VSWH<6>  @BASEBOARD_FAB2_LIB.BASEBOARD_FAB2(SCH_1):VR_PVPP_KLM_PHASE
   33  VR_PVPP_KLM_PHASE  VSWH<5>  @BASEBOARD_FAB2_LIB.BASEBOARD_FAB2(SCH_1):VR_PVPP_KLM_PHASE
   32  VR_PVPP_KLM_PHASE  VSWH<4>  @BASEBOARD_FAB2_LIB.BASEBOARD_FAB2(SCH_1):VR_PVPP_KLM_PHASE
   31  VR_PVPP_KLM_PHASE  VSWH<3>  @BASEBOARD_FAB2_LIB.BASEBOARD_FAB2(SCH_1):VR_PVPP_KLM_PHASE
   30  VR_PVPP_KLM_PHASE  VSWH<2>  @BASEBOARD_FAB2_LIB.BASEBOARD_FAB2(SCH_1):VR_PVPP_KLM_PHASE
   29  VR_PVPP_KLM_PHASE  VSWH<1>  @BASEBOARD_FAB2_LIB.BASEBOARD_FAB2(SCH_1):VR_PVPP_KLM_PHASE
   15  VR_PVPP_KLM_PHASE  VSWH<0>  @BASEBOARD_FAB2_LIB.BASEBOARD_FAB2(SCH_1):VR_PVPP_KLM_PHASE
   35  VR_PVPP_KLM_PHASE    VSW  @BASEBOARD_FAB2_LIB.BASEBOARD_FAB2(SCH_1):VR_PVPP_KLM_PHASE
    4  VR_PVPP_KLM_ISET   ISET  @BASEBOARD_FAB2_LIB.BASEBOARD_FAB2(SCH_1):VR_PVPP_KLM_ISET
   36  VR_PVPP_KLM_BOOT    BST  @BASEBOARD_FAB2_LIB.BASEBOARD_FAB2(SCH_1):VR_PVPP_KLM_BOOT
   42  VR_FET_SW_P12V_STBY_PVPP_KLM  VIN<7>  @BASEBOARD_FAB2_LIB.BASEBOARD_FAB2(SCH_1):VR_FET_SW_P12V_STBY_PVPP_KLM
   14  VR_FET_SW_P12V_STBY_PVPP_KLM  VIN<6>  @BASEBOARD_FAB2_LIB.BASEBOARD_FAB2(SCH_1):VR_FET_SW_P12V_STBY_PVPP_KLM
   13  VR_FET_SW_P12V_STBY_PVPP_KLM  VIN<5>  @BASEBOARD_FAB2_LIB.BASEBOARD_FAB2(SCH_1):VR_FET_SW_P12V_STBY_PVPP_KLM
   12  VR_FET_SW_P12V_STBY_PVPP_KLM  VIN<4>  @BASEBOARD_FAB2_LIB.BASEBOARD_FAB2(SCH_1):VR_FET_SW_P12V_STBY_PVPP_KLM
   11  VR_FET_SW_P12V_STBY_PVPP_KLM  VIN<3>  @BASEBOARD_FAB2_LIB.BASEBOARD_FAB2(SCH_1):VR_FET_SW_P12V_STBY_PVPP_KLM
   10  VR_FET_SW_P12V_STBY_PVPP_KLM  VIN<2>  @BASEBOARD_FAB2_LIB.BASEBOARD_FAB2(SCH_1):VR_FET_SW_P12V_STBY_PVPP_KLM
    9  VR_FET_SW_P12V_STBY_PVPP_KLM  VIN<1>  @BASEBOARD_FAB2_LIB.BASEBOARD_FAB2(SCH_1):VR_FET_SW_P12V_STBY_PVPP_KLM
    8  VR_FET_SW_P12V_STBY_PVPP_KLM  VIN<0>  @BASEBOARD_FAB2_LIB.BASEBOARD_FAB2(SCH_1):VR_FET_SW_P12V_STBY_PVPP_KLM
   39  VR_FET_SW_P12V_STBY_PVPP_KLM    VCC  @BASEBOARD_FAB2_LIB.BASEBOARD_FAB2(SCH_1):VR_FET_SW_P12V_STBY_PVPP_KLM
    2  VR_FB_PVPP_KLM     FB  @BASEBOARD_FAB2_LIB.BASEBOARD_FAB2(SCH_1):VR_FB_PVPP_KLM
    3  VR_COMP_PVPP_KLM_3   COMP  @BASEBOARD_FAB2_LIB.BASEBOARD_FAB2(SCH_1):VR_COMP_PVPP_KLM_3
    7  PWRGD_PVPP_KLM_R     PG  @BASEBOARD_FAB2_LIB.BASEBOARD_FAB2(SCH_1):PWRGD_PVPP_KLM_R
   37  GND            PGND<13>  @BASEBOARD_FAB2_LIB.BASEBOARD_FAB2(SCH_1):GND
   28  GND            PGND<12>  @BASEBOARD_FAB2_LIB.BASEBOARD_FAB2(SCH_1):GND
   27  GND            PGND<11>  @BASEBOARD_FAB2_LIB.BASEBOARD_FAB2(SCH_1):GND
   26  GND            PGND<10>  @BASEBOARD_FAB2_LIB.BASEBOARD_FAB2(SCH_1):GND
   25  GND            PGND<9>  @BASEBOARD_FAB2_LIB.BASEBOARD_FAB2(SCH_1):GND
   24  GND            PGND<8>  @BASEBOARD_FAB2_LIB.BASEBOARD_FAB2(SCH_1):GND
   23  GND            PGND<7>  @BASEBOARD_FAB2_LIB.BASEBOARD_FAB2(SCH_1):GND
   22  GND            PGND<6>  @BASEBOARD_FAB2_LIB.BASEBOARD_FAB2(SCH_1):GND
   21  GND            PGND<5>  @BASEBOARD_FAB2_LIB.BASEBOARD_FAB2(SCH_1):GND
   20  GND            PGND<4>  @BASEBOARD_FAB2_LIB.BASEBOARD_FAB2(SCH_1):GND
   19  GND            PGND<3>  @BASEBOARD_FAB2_LIB.BASEBOARD_FAB2(SCH_1):GND
   18  GND            PGND<2>  @BASEBOARD_FAB2_LIB.BASEBOARD_FAB2(SCH_1):GND
   17  GND            PGND<1>  @BASEBOARD_FAB2_LIB.BASEBOARD_FAB2(SCH_1):GND
   16  GND            PGND<0>  @BASEBOARD_FAB2_LIB.BASEBOARD_FAB2(SCH_1):GND
   41  GND              GND  @BASEBOARD_FAB2_LIB.BASEBOARD_FAB2(SCH_1):GND
   40  FM_PVPP_PVDDQ_CPU1_EN_KLM     EN  @BASEBOARD_FAB2_LIB.BASEBOARD_FAB2(SCH_1):FM_PVPP_PVDDQ_CPU1_EN_KLM
    6  AGND_PVPP_KLM    OTS  @BASEBOARD_FAB2_LIB.BASEBOARD_FAB2(SCH_1):AGND_PVPP_KLM
    5  AGND_PVPP_KLM   AGND  @BASEBOARD_FAB2_LIB.BASEBOARD_FAB2(SCH_1):AGND_PVPP_KLM

IR354XX_SM  I46  EU4C1  [IR354XX_SM-IR35412,IC,H73684-0A]
    3  VR_PVSA_CPU0_VCIN    VCC  @BASEBOARD_FAB2_LIB.BASEBOARD_FAB2(SCH_1):VR_PVSA_CPU0_VCIN
   34  VR_PVSA_CPU0_PWM    PWM  @BASEBOARD_FAB2_LIB.BASEBOARD_FAB2(SCH_1):VR_PVSA_CPU0_PWM
   10  VR_PVSA_CPU0_PHASE_SW     SW  @BASEBOARD_FAB2_LIB.BASEBOARD_FAB2(SCH_1):VR_PVSA_CPU0_PHASE_SW
   32  VR_PVSA_CPU0_PHASE  PHASE  @BASEBOARD_FAB2_LIB.BASEBOARD_FAB2(SCH_1):VR_PVSA_CPU0_PHASE
   37  VR_PVSA_CPU0_OCSET  OCSET  @BASEBOARD_FAB2_LIB.BASEBOARD_FAB2(SCH_1):VR_PVSA_CPU0_OCSET
   33  VR_PVSA_CPU0_BOOT_R  BOOST  @BASEBOARD_FAB2_LIB.BASEBOARD_FAB2(SCH_1):VR_PVSA_CPU0_BOOT_R
   39  VR_PVSA_CPU0_BIREF1  REFIN  @BASEBOARD_FAB2_LIB.BASEBOARD_FAB2(SCH_1):VR_PVSA_CPU0_BIREF1
   30  VR_FET_SW_P12V_STBY_PVCCIN_CPU0  VIN<1>  @BASEBOARD_FAB2_LIB.BASEBOARD_FAB2(SCH_1):VR_FET_SW_P12V_STBY_PVCCIN_CPU0
   25  VR_FET_SW_P12V_STBY_PVCCIN_CPU0  VIN<0>  @BASEBOARD_FAB2_LIB.BASEBOARD_FAB2(SCH_1):VR_FET_SW_P12V_STBY_PVCCIN_CPU0
   41  TP_PVSA_CPU0_GL_1  GL<1>  @BASEBOARD_FAB2_LIB.BASEBOARD_FAB2(SCH_1):TP_PVSA_CPU0_GL_1
    6  TP_PVSA_CPU0_GL_0  GL<0>  @BASEBOARD_FAB2_LIB.BASEBOARD_FAB2(SCH_1):TP_PVSA_CPU0_GL_0
    1  PVSA_CPU0        VOS  @BASEBOARD_FAB2_LIB.BASEBOARD_FAB2(SCH_1):PVSA_CPU0
    4  P5V_STBY        VDRV  @BASEBOARD_FAB2_LIB.BASEBOARD_FAB2(SCH_1):P5V_STBY
   35  P5V_STBY          EN  @BASEBOARD_FAB2_LIB.BASEBOARD_FAB2(SCH_1):P5V_STBY
   31  NC_PVSA_CPU0_P31     NC  @BASEBOARD_FAB2_LIB.BASEBOARD_FAB2(SCH_1):NC_PVSA_CPU0_P31
   38  ISENSE_PVSA_CPU0_IMON   IOUT  @BASEBOARD_FAB2_LIB.BASEBOARD_FAB2(SCH_1):ISENSE_PVSA_CPU0_IMON
   40  GND            PGND<2>  @BASEBOARD_FAB2_LIB.BASEBOARD_FAB2(SCH_1):GND
    7  GND            PGND<1>  @BASEBOARD_FAB2_LIB.BASEBOARD_FAB2(SCH_1):GND
    5  GND            PGND<0>  @BASEBOARD_FAB2_LIB.BASEBOARD_FAB2(SCH_1):GND
    2  GND             LGND  @BASEBOARD_FAB2_LIB.BASEBOARD_FAB2(SCH_1):GND
   36  A_TSENSE_PVSA_CPU0  TOUT_FLT  @BASEBOARD_FAB2_LIB.BASEBOARD_FAB2(SCH_1):A_TSENSE_PVSA_CPU0

IR354XX_SM  I71  EU4C2  [IR354XX_SM-IR35411,IC,H73688-0A]
   34  VR_PVCCIN_CPU0_PWM5    PWM  @BASEBOARD_FAB2_LIB.BASEBOARD_FAB2(SCH_1):VR_PVCCIN_CPU0_PWM5
   10  VR_PVCCIN_CPU0_PHASE5     SW  @BASEBOARD_FAB2_LIB.BASEBOARD_FAB2(SCH_1):VR_PVCCIN_CPU0_PHASE5
    3  VR_PVCCIN_CPU0_PH5_VCIN    VCC  @BASEBOARD_FAB2_LIB.BASEBOARD_FAB2(SCH_1):VR_PVCCIN_CPU0_PH5_VCIN
   32  VR_PVCCIN_CPU0_PH5_PHASE  PHASE  @BASEBOARD_FAB2_LIB.BASEBOARD_FAB2(SCH_1):VR_PVCCIN_CPU0_PH5_PHASE
   37  VR_PVCCIN_CPU0_PH5_OCSET  OCSET  @BASEBOARD_FAB2_LIB.BASEBOARD_FAB2(SCH_1):VR_PVCCIN_CPU0_PH5_OCSET
   33  VR_PVCCIN_CPU0_PH5_BOOT_R  BOOST  @BASEBOARD_FAB2_LIB.BASEBOARD_FAB2(SCH_1):VR_PVCCIN_CPU0_PH5_BOOT_R
   39  VR_PVCCIN_CPU0_AIREF5  REFIN  @BASEBOARD_FAB2_LIB.BASEBOARD_FAB2(SCH_1):VR_PVCCIN_CPU0_AIREF5
   30  VR_FET_SW_P12V_STBY_PVCCIN_CPU0  VIN<1>  @BASEBOARD_FAB2_LIB.BASEBOARD_FAB2(SCH_1):VR_FET_SW_P12V_STBY_PVCCIN_CPU0
   25  VR_FET_SW_P12V_STBY_PVCCIN_CPU0  VIN<0>  @BASEBOARD_FAB2_LIB.BASEBOARD_FAB2(SCH_1):VR_FET_SW_P12V_STBY_PVCCIN_CPU0
   41  TP_PVCCIN_CPU0_PH5_GL_1  GL<1>  @BASEBOARD_FAB2_LIB.BASEBOARD_FAB2(SCH_1):TP_PVCCIN_CPU0_PH5_GL_1
    6  TP_PVCCIN_CPU0_PH5_GL_0  GL<0>  @BASEBOARD_FAB2_LIB.BASEBOARD_FAB2(SCH_1):TP_PVCCIN_CPU0_PH5_GL_0
    1  PVCCIN_CPU0      VOS  @BASEBOARD_FAB2_LIB.BASEBOARD_FAB2(SCH_1):PVCCIN_CPU0
    4  P5V_STBY        VDRV  @BASEBOARD_FAB2_LIB.BASEBOARD_FAB2(SCH_1):P5V_STBY
   35  P5V_STBY          EN  @BASEBOARD_FAB2_LIB.BASEBOARD_FAB2(SCH_1):P5V_STBY
   31  NC_PVCCIN_CPU0_PH5_P31     NC  @BASEBOARD_FAB2_LIB.BASEBOARD_FAB2(SCH_1):NC_PVCCIN_CPU0_PH5_P31
   38  ISENSE_PVCCIN_CPU0_PH5_IMON   IOUT  @BASEBOARD_FAB2_LIB.BASEBOARD_FAB2(SCH_1):ISENSE_PVCCIN_CPU0_PH5_IMON
   40  GND            PGND<2>  @BASEBOARD_FAB2_LIB.BASEBOARD_FAB2(SCH_1):GND
    7  GND            PGND<1>  @BASEBOARD_FAB2_LIB.BASEBOARD_FAB2(SCH_1):GND
    5  GND            PGND<0>  @BASEBOARD_FAB2_LIB.BASEBOARD_FAB2(SCH_1):GND
    2  GND             LGND  @BASEBOARD_FAB2_LIB.BASEBOARD_FAB2(SCH_1):GND
   36  A_TSENSE_PVCCIN_CPU0  TOUT_FLT  @BASEBOARD_FAB2_LIB.BASEBOARD_FAB2(SCH_1):A_TSENSE_PVCCIN_CPU0

IR354XX_SM  I71  EU4D1  [IR354XX_SM-IR35411,IC,H73688-0A]
   34  VR_PVCCIN_CPU0_PWM4    PWM  @BASEBOARD_FAB2_LIB.BASEBOARD_FAB2(SCH_1):VR_PVCCIN_CPU0_PWM4
   10  VR_PVCCIN_CPU0_PHASE4     SW  @BASEBOARD_FAB2_LIB.BASEBOARD_FAB2(SCH_1):VR_PVCCIN_CPU0_PHASE4
    3  VR_PVCCIN_CPU0_PH4_VCIN    VCC  @BASEBOARD_FAB2_LIB.BASEBOARD_FAB2(SCH_1):VR_PVCCIN_CPU0_PH4_VCIN
   32  VR_PVCCIN_CPU0_PH4_PHASE  PHASE  @BASEBOARD_FAB2_LIB.BASEBOARD_FAB2(SCH_1):VR_PVCCIN_CPU0_PH4_PHASE
   37  VR_PVCCIN_CPU0_PH4_OCSET  OCSET  @BASEBOARD_FAB2_LIB.BASEBOARD_FAB2(SCH_1):VR_PVCCIN_CPU0_PH4_OCSET
   33  VR_PVCCIN_CPU0_PH4_BOOT_R  BOOST  @BASEBOARD_FAB2_LIB.BASEBOARD_FAB2(SCH_1):VR_PVCCIN_CPU0_PH4_BOOT_R
   39  VR_PVCCIN_CPU0_AIREF4  REFIN  @BASEBOARD_FAB2_LIB.BASEBOARD_FAB2(SCH_1):VR_PVCCIN_CPU0_AIREF4
   30  VR_FET_SW_P12V_STBY_PVCCIN_CPU0  VIN<1>  @BASEBOARD_FAB2_LIB.BASEBOARD_FAB2(SCH_1):VR_FET_SW_P12V_STBY_PVCCIN_CPU0
   25  VR_FET_SW_P12V_STBY_PVCCIN_CPU0  VIN<0>  @BASEBOARD_FAB2_LIB.BASEBOARD_FAB2(SCH_1):VR_FET_SW_P12V_STBY_PVCCIN_CPU0
   41  TP_PVCCIN_CPU0_PH4_GL_1  GL<1>  @BASEBOARD_FAB2_LIB.BASEBOARD_FAB2(SCH_1):TP_PVCCIN_CPU0_PH4_GL_1
    6  TP_PVCCIN_CPU0_PH4_GL_0  GL<0>  @BASEBOARD_FAB2_LIB.BASEBOARD_FAB2(SCH_1):TP_PVCCIN_CPU0_PH4_GL_0
    1  PVCCIN_CPU0      VOS  @BASEBOARD_FAB2_LIB.BASEBOARD_FAB2(SCH_1):PVCCIN_CPU0
    4  P5V_STBY        VDRV  @BASEBOARD_FAB2_LIB.BASEBOARD_FAB2(SCH_1):P5V_STBY
   35  P5V_STBY          EN  @BASEBOARD_FAB2_LIB.BASEBOARD_FAB2(SCH_1):P5V_STBY
   31  NC_PVCCIN_CPU0_PH4_P31     NC  @BASEBOARD_FAB2_LIB.BASEBOARD_FAB2(SCH_1):NC_PVCCIN_CPU0_PH4_P31
   38  ISENSE_PVCCIN_CPU0_PH4_IMON   IOUT  @BASEBOARD_FAB2_LIB.BASEBOARD_FAB2(SCH_1):ISENSE_PVCCIN_CPU0_PH4_IMON
   40  GND            PGND<2>  @BASEBOARD_FAB2_LIB.BASEBOARD_FAB2(SCH_1):GND
    7  GND            PGND<1>  @BASEBOARD_FAB2_LIB.BASEBOARD_FAB2(SCH_1):GND
    5  GND            PGND<0>  @BASEBOARD_FAB2_LIB.BASEBOARD_FAB2(SCH_1):GND
    2  GND             LGND  @BASEBOARD_FAB2_LIB.BASEBOARD_FAB2(SCH_1):GND
   36  A_TSENSE_PVCCIN_CPU0  TOUT_FLT  @BASEBOARD_FAB2_LIB.BASEBOARD_FAB2(SCH_1):A_TSENSE_PVCCIN_CPU0

NB3W1200L_LCC  I1   EU4D2  [NB3W1200L_LCC-IC,H13585-001]
   12  SMB_HOST_STBY_LVC3_SDA_R2    SDA  @BASEBOARD_FAB2_LIB.BASEBOARD_FAB2(SCH_1):SMB_HOST_STBY_LVC3_SDA_R2
   13  SMB_HOST_STBY_LVC3_SCL_R2    SCL  @BASEBOARD_FAB2_LIB.BASEBOARD_FAB2(SCH_1):SMB_HOST_STBY_LVC3_SCL_R2
    8  P3V3_DB1200_R   VDDR  @BASEBOARD_FAB2_LIB.BASEBOARD_FAB2(SCH_1):P3V3_DB1200_R
    1  P3V3_DB1200_A   VDDA  @BASEBOARD_FAB2_LIB.BASEBOARD_FAB2(SCH_1):P3V3_DB1200_A
   56  P3V3_DB1200    VDDIO<3>  @BASEBOARD_FAB2_LIB.BASEBOARD_FAB2(SCH_1):P3V3_DB1200
   49  P3V3_DB1200    VDDIO<2>  @BASEBOARD_FAB2_LIB.BASEBOARD_FAB2(SCH_1):P3V3_DB1200
   32  P3V3_DB1200    VDDIO<1>  @BASEBOARD_FAB2_LIB.BASEBOARD_FAB2(SCH_1):P3V3_DB1200
   25  P3V3_DB1200    VDDIO<0>  @BASEBOARD_FAB2_LIB.BASEBOARD_FAB2(SCH_1):P3V3_DB1200
   57  P3V3_DB1200    VDD<2>  @BASEBOARD_FAB2_LIB.BASEBOARD_FAB2(SCH_1):P3V3_DB1200
   40  P3V3_DB1200    VDD<1>  @BASEBOARD_FAB2_LIB.BASEBOARD_FAB2(SCH_1):P3V3_DB1200
   24  P3V3_DB1200    VDD<0>  @BASEBOARD_FAB2_LIB.BASEBOARD_FAB2(SCH_1):P3V3_DB1200
   15  NC_DB1200ZL<2>  NC<2>  @BASEBOARD_FAB2_LIB.BASEBOARD_FAB2(SCH_1):NC_DB1200ZL<2>
   16  NC_DB1200ZL<1>  NC<1>  @BASEBOARD_FAB2_LIB.BASEBOARD_FAB2(SCH_1):NC_DB1200ZL<1>
    3  NC_DB1200ZL<0>  NC<0>  @BASEBOARD_FAB2_LIB.BASEBOARD_FAB2(SCH_1):NC_DB1200ZL<0>
   65  GND            THPAD  @BASEBOARD_FAB2_LIB.BASEBOARD_FAB2(SCH_1):GND
    2  GND             GNDA  @BASEBOARD_FAB2_LIB.BASEBOARD_FAB2(SCH_1):GND
   58  GND            GND<5>  @BASEBOARD_FAB2_LIB.BASEBOARD_FAB2(SCH_1):GND
   48  GND            GND<4>  @BASEBOARD_FAB2_LIB.BASEBOARD_FAB2(SCH_1):GND
   41  GND            GND<3>  @BASEBOARD_FAB2_LIB.BASEBOARD_FAB2(SCH_1):GND
   33  GND            GND<2>  @BASEBOARD_FAB2_LIB.BASEBOARD_FAB2(SCH_1):GND
   23  GND            GND<1>  @BASEBOARD_FAB2_LIB.BASEBOARD_FAB2(SCH_1):GND
    7  GND            GND<0>  @BASEBOARD_FAB2_LIB.BASEBOARD_FAB2(SCH_1):GND
    5  FM_HBW_BYPASS_LOWBW_N  HBW_BYPASS_LOBW_N  @BASEBOARD_FAB2_LIB.BASEBOARD_FAB2(SCH_1):FM_HBW_BYPASS_LOWBW_N
   14  FM_DB1200_SMB_SA1   SA_1  @BASEBOARD_FAB2_LIB.BASEBOARD_FAB2(SCH_1):FM_DB1200_SMB_SA1
   11  FM_DB1200_SMB_SA0   SA_0  @BASEBOARD_FAB2_LIB.BASEBOARD_FAB2(SCH_1):FM_DB1200_SMB_SA0
    6  FM_DB1200_PWRGD  PWRGD_PWRDN_N  @BASEBOARD_FAB2_LIB.BASEBOARD_FAB2(SCH_1):FM_DB1200_PWRGD
   52  FM_DB1200ZL_BCLKS_EN_N  OE_8_N  @BASEBOARD_FAB2_LIB.BASEBOARD_FAB2(SCH_1):FM_DB1200ZL_BCLKS_EN_N
   45  FM_DB1200ZL_BCLKS_EN_N  OE_7_N  @BASEBOARD_FAB2_LIB.BASEBOARD_FAB2(SCH_1):FM_DB1200ZL_BCLKS_EN_N
   44  FM_DB1200ZL_BCLKS_EN_N  OE_6_N  @BASEBOARD_FAB2_LIB.BASEBOARD_FAB2(SCH_1):FM_DB1200ZL_BCLKS_EN_N
   28  FM_DB1200ZL_BCLKS_EN_N  OE_2_N  @BASEBOARD_FAB2_LIB.BASEBOARD_FAB2(SCH_1):FM_DB1200ZL_BCLKS_EN_N
   20  FM_DB1200ZL_BCLKS_EN_N  OE_1_N  @BASEBOARD_FAB2_LIB.BASEBOARD_FAB2(SCH_1):FM_DB1200ZL_BCLKS_EN_N
   19  FM_DB1200ZL_BCLKS_EN_N  OE_0_N  @BASEBOARD_FAB2_LIB.BASEBOARD_FAB2(SCH_1):FM_DB1200ZL_BCLKS_EN_N
   62  FM_CPU1_MCP_CLK_EN_N  OE_11_N  @BASEBOARD_FAB2_LIB.BASEBOARD_FAB2(SCH_1):FM_CPU1_MCP_CLK_EN_N
   61  FM_CPU1_MCP_CLK_EN_N  OE_10_N  @BASEBOARD_FAB2_LIB.BASEBOARD_FAB2(SCH_1):FM_CPU1_MCP_CLK_EN_N
   53  FM_CPU1_MCP_CLK_EN_N  OE_9_N  @BASEBOARD_FAB2_LIB.BASEBOARD_FAB2(SCH_1):FM_CPU1_MCP_CLK_EN_N
   37  FM_CPU0_MCP_CLK_EN_N  OE_5_N  @BASEBOARD_FAB2_LIB.BASEBOARD_FAB2(SCH_1):FM_CPU0_MCP_CLK_EN_N
   36  FM_CPU0_MCP_CLK_EN_N  OE_4_N  @BASEBOARD_FAB2_LIB.BASEBOARD_FAB2(SCH_1):FM_CPU0_MCP_CLK_EN_N
   29  FM_CPU0_MCP_CLK_EN_N  OE_3_N  @BASEBOARD_FAB2_LIB.BASEBOARD_FAB2(SCH_1):FM_CPU0_MCP_CLK_EN_N
    4  FM_100M_N      100M_133M_N  @BASEBOARD_FAB2_LIB.BASEBOARD_FAB2(SCH_1):FM_100M_N
    9  CLK_100M_DB1200_DP  CLK_INP  @BASEBOARD_FAB2_LIB.BASEBOARD_FAB2(SCH_1):CLK_100M_DB1200_DP
   10  CLK_100M_DB1200_DN  CLK_INN  @BASEBOARD_FAB2_LIB.BASEBOARD_FAB2(SCH_1):CLK_100M_DB1200_DN
   63  CLK_100M_CPU1_RC_REFCLK1_R_DP  DIF_11P  @BASEBOARD_FAB2_LIB.BASEBOARD_FAB2(SCH_1):CLK_100M_CPU1_RC_REFCLK1_R_DP
   64  CLK_100M_CPU1_RC_REFCLK1_R_DN  DIF_11N  @BASEBOARD_FAB2_LIB.BASEBOARD_FAB2(SCH_1):CLK_100M_CPU1_RC_REFCLK1_R_DN
   59  CLK_100M_CPU1_RC_REFCLK0_R_DP  DIF_10P  @BASEBOARD_FAB2_LIB.BASEBOARD_FAB2(SCH_1):CLK_100M_CPU1_RC_REFCLK0_R_DP
   60  CLK_100M_CPU1_RC_REFCLK0_R_DN  DIF_10N  @BASEBOARD_FAB2_LIB.BASEBOARD_FAB2(SCH_1):CLK_100M_CPU1_RC_REFCLK0_R_DN
   54  CLK_100M_CPU1_PE_REFCLK_R_DP  DIF_9P  @BASEBOARD_FAB2_LIB.BASEBOARD_FAB2(SCH_1):CLK_100M_CPU1_PE_REFCLK_R_DP
   55  CLK_100M_CPU1_PE_REFCLK_R_DN  DIF_9N  @BASEBOARD_FAB2_LIB.BASEBOARD_FAB2(SCH_1):CLK_100M_CPU1_PE_REFCLK_R_DN
   50  CLK_100M_CPU1_BCLK2_R_DP  DIF_8P  @BASEBOARD_FAB2_LIB.BASEBOARD_FAB2(SCH_1):CLK_100M_CPU1_BCLK2_R_DP
   51  CLK_100M_CPU1_BCLK2_R_DN  DIF_8N  @BASEBOARD_FAB2_LIB.BASEBOARD_FAB2(SCH_1):CLK_100M_CPU1_BCLK2_R_DN
   46  CLK_100M_CPU1_BCLK1_R_DP  DIF_7P  @BASEBOARD_FAB2_LIB.BASEBOARD_FAB2(SCH_1):CLK_100M_CPU1_BCLK1_R_DP
   47  CLK_100M_CPU1_BCLK1_R_DN  DIF_7N  @BASEBOARD_FAB2_LIB.BASEBOARD_FAB2(SCH_1):CLK_100M_CPU1_BCLK1_R_DN
   42  CLK_100M_CPU1_BCLK0_R_DP  DIF_6P  @BASEBOARD_FAB2_LIB.BASEBOARD_FAB2(SCH_1):CLK_100M_CPU1_BCLK0_R_DP
   43  CLK_100M_CPU1_BCLK0_R_DN  DIF_6N  @BASEBOARD_FAB2_LIB.BASEBOARD_FAB2(SCH_1):CLK_100M_CPU1_BCLK0_R_DN
   38  CLK_100M_CPU0_RC_REFCLK1_R_DP  DIF_5P  @BASEBOARD_FAB2_LIB.BASEBOARD_FAB2(SCH_1):CLK_100M_CPU0_RC_REFCLK1_R_DP
   39  CLK_100M_CPU0_RC_REFCLK1_R_DN  DIF_5N  @BASEBOARD_FAB2_LIB.BASEBOARD_FAB2(SCH_1):CLK_100M_CPU0_RC_REFCLK1_R_DN
   34  CLK_100M_CPU0_RC_REFCLK0_R_DP  DIF_4P  @BASEBOARD_FAB2_LIB.BASEBOARD_FAB2(SCH_1):CLK_100M_CPU0_RC_REFCLK0_R_DP
   35  CLK_100M_CPU0_RC_REFCLK0_R_DN  DIF_4N  @BASEBOARD_FAB2_LIB.BASEBOARD_FAB2(SCH_1):CLK_100M_CPU0_RC_REFCLK0_R_DN
   30  CLK_100M_CPU0_PE_REFCLK_R_DP  DIF_3P  @BASEBOARD_FAB2_LIB.BASEBOARD_FAB2(SCH_1):CLK_100M_CPU0_PE_REFCLK_R_DP
   31  CLK_100M_CPU0_PE_REFCLK_R_DN  DIF_3N  @BASEBOARD_FAB2_LIB.BASEBOARD_FAB2(SCH_1):CLK_100M_CPU0_PE_REFCLK_R_DN
   26  CLK_100M_CPU0_BCLK2_R_DP  DIF_2P  @BASEBOARD_FAB2_LIB.BASEBOARD_FAB2(SCH_1):CLK_100M_CPU0_BCLK2_R_DP
   27  CLK_100M_CPU0_BCLK2_R_DN  DIF_2N  @BASEBOARD_FAB2_LIB.BASEBOARD_FAB2(SCH_1):CLK_100M_CPU0_BCLK2_R_DN
   21  CLK_100M_CPU0_BCLK1_R_DP  DIF_1P  @BASEBOARD_FAB2_LIB.BASEBOARD_FAB2(SCH_1):CLK_100M_CPU0_BCLK1_R_DP
   22  CLK_100M_CPU0_BCLK1_R_DN  DIF_1N  @BASEBOARD_FAB2_LIB.BASEBOARD_FAB2(SCH_1):CLK_100M_CPU0_BCLK1_R_DN
   17  CLK_100M_CPU0_BCLK0_R_DP  DIF_0P  @BASEBOARD_FAB2_LIB.BASEBOARD_FAB2(SCH_1):CLK_100M_CPU0_BCLK0_R_DP
   18  CLK_100M_CPU0_BCLK0_R_DN  DIF_0N  @BASEBOARD_FAB2_LIB.BASEBOARD_FAB2(SCH_1):CLK_100M_CPU0_BCLK0_R_DN

IR354XX_SM  I70  EU4D3  [IR354XX_SM-IR35411,IC,H73688-0A]
   34  VR_PVCCIN_CPU0_PWM3    PWM  @BASEBOARD_FAB2_LIB.BASEBOARD_FAB2(SCH_1):VR_PVCCIN_CPU0_PWM3
   10  VR_PVCCIN_CPU0_PHASE3     SW  @BASEBOARD_FAB2_LIB.BASEBOARD_FAB2(SCH_1):VR_PVCCIN_CPU0_PHASE3
    3  VR_PVCCIN_CPU0_PH3_VCIN    VCC  @BASEBOARD_FAB2_LIB.BASEBOARD_FAB2(SCH_1):VR_PVCCIN_CPU0_PH3_VCIN
   32  VR_PVCCIN_CPU0_PH3_PHASE  PHASE  @BASEBOARD_FAB2_LIB.BASEBOARD_FAB2(SCH_1):VR_PVCCIN_CPU0_PH3_PHASE
   37  VR_PVCCIN_CPU0_PH3_OCSET  OCSET  @BASEBOARD_FAB2_LIB.BASEBOARD_FAB2(SCH_1):VR_PVCCIN_CPU0_PH3_OCSET
   33  VR_PVCCIN_CPU0_PH3_BOOT_R  BOOST  @BASEBOARD_FAB2_LIB.BASEBOARD_FAB2(SCH_1):VR_PVCCIN_CPU0_PH3_BOOT_R
   39  VR_PVCCIN_CPU0_AIREF3  REFIN  @BASEBOARD_FAB2_LIB.BASEBOARD_FAB2(SCH_1):VR_PVCCIN_CPU0_AIREF3
   30  VR_FET_SW_P12V_STBY_PVCCIN_CPU0  VIN<1>  @BASEBOARD_FAB2_LIB.BASEBOARD_FAB2(SCH_1):VR_FET_SW_P12V_STBY_PVCCIN_CPU0
   25  VR_FET_SW_P12V_STBY_PVCCIN_CPU0  VIN<0>  @BASEBOARD_FAB2_LIB.BASEBOARD_FAB2(SCH_1):VR_FET_SW_P12V_STBY_PVCCIN_CPU0
   41  TP_PVCCIN_CPU0_PH3_GL_1  GL<1>  @BASEBOARD_FAB2_LIB.BASEBOARD_FAB2(SCH_1):TP_PVCCIN_CPU0_PH3_GL_1
    6  TP_PVCCIN_CPU0_PH3_GL_0  GL<0>  @BASEBOARD_FAB2_LIB.BASEBOARD_FAB2(SCH_1):TP_PVCCIN_CPU0_PH3_GL_0
    1  PVCCIN_CPU0      VOS  @BASEBOARD_FAB2_LIB.BASEBOARD_FAB2(SCH_1):PVCCIN_CPU0
    4  P5V_STBY        VDRV  @BASEBOARD_FAB2_LIB.BASEBOARD_FAB2(SCH_1):P5V_STBY
   35  P5V_STBY          EN  @BASEBOARD_FAB2_LIB.BASEBOARD_FAB2(SCH_1):P5V_STBY
   31  NC_PVCCIN_CPU0_PH3_P31     NC  @BASEBOARD_FAB2_LIB.BASEBOARD_FAB2(SCH_1):NC_PVCCIN_CPU0_PH3_P31
   38  ISENSE_PVCCIN_CPU0_PH3_IMON   IOUT  @BASEBOARD_FAB2_LIB.BASEBOARD_FAB2(SCH_1):ISENSE_PVCCIN_CPU0_PH3_IMON
   40  GND            PGND<2>  @BASEBOARD_FAB2_LIB.BASEBOARD_FAB2(SCH_1):GND
    7  GND            PGND<1>  @BASEBOARD_FAB2_LIB.BASEBOARD_FAB2(SCH_1):GND
    5  GND            PGND<0>  @BASEBOARD_FAB2_LIB.BASEBOARD_FAB2(SCH_1):GND
    2  GND             LGND  @BASEBOARD_FAB2_LIB.BASEBOARD_FAB2(SCH_1):GND
   36  A_TSENSE_PVCCIN_CPU0  TOUT_FLT  @BASEBOARD_FAB2_LIB.BASEBOARD_FAB2(SCH_1):A_TSENSE_PVCCIN_CPU0

PXE1610B_QFN  I155  EU4D4  [PXE1610B_QFN-IC,H79206-001]
   36  VSENSE_PVSA_CPU0_N  BVREF  @BASEBOARD_FAB2_LIB.BASEBOARD_FAB2(SCH_1):VSENSE_PVSA_CPU0_N
   35  VSENSE_PVSA_CPU0_BVSP  BVSEN  @BASEBOARD_FAB2_LIB.BASEBOARD_FAB2(SCH_1):VSENSE_PVSA_CPU0_BVSP
   22  VSENSE_PVCCIN_CPU0_N  AVREF  @BASEBOARD_FAB2_LIB.BASEBOARD_FAB2(SCH_1):VSENSE_PVCCIN_CPU0_N
   21  VSENSE_PVCCIN_CPU0_AVSP  AVSEN  @BASEBOARD_FAB2_LIB.BASEBOARD_FAB2(SCH_1):VSENSE_PVCCIN_CPU0_AVSP
   11  VR_VRRDY_PVCCIN_CPU0  AVRRDY  @BASEBOARD_FAB2_LIB.BASEBOARD_FAB2(SCH_1):VR_VRRDY_PVCCIN_CPU0
    1  VR_PVSA_CPU0_PWM  BPWM1  @BASEBOARD_FAB2_LIB.BASEBOARD_FAB2(SCH_1):VR_PVSA_CPU0_PWM
   37  VR_PVSA_CPU0_BIREF1  BIREF1  @BASEBOARD_FAB2_LIB.BASEBOARD_FAB2(SCH_1):VR_PVSA_CPU0_BIREF1
   41  VR_PVCCIN_CPU0_XADDR2  XADDR2  @BASEBOARD_FAB2_LIB.BASEBOARD_FAB2(SCH_1):VR_PVCCIN_CPU0_XADDR2
   44  VR_PVCCIN_CPU0_XADDR1  XADDR1  @BASEBOARD_FAB2_LIB.BASEBOARD_FAB2(SCH_1):VR_PVCCIN_CPU0_XADDR1
   12  VR_PVCCIN_CPU0_VREN  AVREN  @BASEBOARD_FAB2_LIB.BASEBOARD_FAB2(SCH_1):VR_PVCCIN_CPU0_VREN
   47  VR_PVCCIN_CPU0_VDD    VDD  @BASEBOARD_FAB2_LIB.BASEBOARD_FAB2(SCH_1):VR_PVCCIN_CPU0_VDD
   48  VR_PVCCIN_CPU0_VD12   VD12  @BASEBOARD_FAB2_LIB.BASEBOARD_FAB2(SCH_1):VR_PVCCIN_CPU0_VD12
    3  VR_PVCCIN_CPU0_PWM5  APWM5  @BASEBOARD_FAB2_LIB.BASEBOARD_FAB2(SCH_1):VR_PVCCIN_CPU0_PWM5
    4  VR_PVCCIN_CPU0_PWM4  APWM4  @BASEBOARD_FAB2_LIB.BASEBOARD_FAB2(SCH_1):VR_PVCCIN_CPU0_PWM4
    5  VR_PVCCIN_CPU0_PWM3  APWM3  @BASEBOARD_FAB2_LIB.BASEBOARD_FAB2(SCH_1):VR_PVCCIN_CPU0_PWM3
    6  VR_PVCCIN_CPU0_PWM2  APWM2  @BASEBOARD_FAB2_LIB.BASEBOARD_FAB2(SCH_1):VR_PVCCIN_CPU0_PWM2
    7  VR_PVCCIN_CPU0_PWM1  APWM1  @BASEBOARD_FAB2_LIB.BASEBOARD_FAB2(SCH_1):VR_PVCCIN_CPU0_PWM1
   45  VR_PVCCIN_CPU0_AVINSEN  VINSEN  @BASEBOARD_FAB2_LIB.BASEBOARD_FAB2(SCH_1):VR_PVCCIN_CPU0_AVINSEN
   31  VR_PVCCIN_CPU0_AIREF5  AIREF5  @BASEBOARD_FAB2_LIB.BASEBOARD_FAB2(SCH_1):VR_PVCCIN_CPU0_AIREF5
   29  VR_PVCCIN_CPU0_AIREF4  AIREF4  @BASEBOARD_FAB2_LIB.BASEBOARD_FAB2(SCH_1):VR_PVCCIN_CPU0_AIREF4
   27  VR_PVCCIN_CPU0_AIREF3  AIREF3  @BASEBOARD_FAB2_LIB.BASEBOARD_FAB2(SCH_1):VR_PVCCIN_CPU0_AIREF3
   25  VR_PVCCIN_CPU0_AIREF2  AIREF2  @BASEBOARD_FAB2_LIB.BASEBOARD_FAB2(SCH_1):VR_PVCCIN_CPU0_AIREF2
   23  VR_PVCCIN_CPU0_AIREF1  AIREF1  @BASEBOARD_FAB2_LIB.BASEBOARD_FAB2(SCH_1):VR_PVCCIN_CPU0_AIREF1
   10  TP_PVCCIN_CPU0_RESET  RESET_N  @BASEBOARD_FAB2_LIB.BASEBOARD_FAB2(SCH_1):TP_PVCCIN_CPU0_RESET
   16  TP_PVCCIN_CPU0_GP1    MP1  @BASEBOARD_FAB2_LIB.BASEBOARD_FAB2(SCH_1):TP_PVCCIN_CPU0_GP1
   40  TP_PVCCIN_CPU0_FAULT1_20    MP4  @BASEBOARD_FAB2_LIB.BASEBOARD_FAB2(SCH_1):TP_PVCCIN_CPU0_FAULT1_20
    2  TP_PVCCIN_CPU0_APWM6  APWM6  @BASEBOARD_FAB2_LIB.BASEBOARD_FAB2(SCH_1):TP_PVCCIN_CPU0_APWM6
   34  TP_PVCCIN_CPU0_AISEN6  AISEN6  @BASEBOARD_FAB2_LIB.BASEBOARD_FAB2(SCH_1):TP_PVCCIN_CPU0_AISEN6
   33  TP_PVCCIN_CPU0_AIREF6  AIREF6  @BASEBOARD_FAB2_LIB.BASEBOARD_FAB2(SCH_1):TP_PVCCIN_CPU0_AIREF6
   18  SVID_VDIO_PVCCIN_CPU0   VDIO  @BASEBOARD_FAB2_LIB.BASEBOARD_FAB2(SCH_1):SVID_VDIO_PVCCIN_CPU0
   17  SVID_VCLK_PVCCIN_CPU0   VCLK  @BASEBOARD_FAB2_LIB.BASEBOARD_FAB2(SCH_1):SVID_VCLK_PVCCIN_CPU0
   19  SVID_VALERT_VCCIN_CPU0  VALRT_N  @BASEBOARD_FAB2_LIB.BASEBOARD_FAB2(SCH_1):SVID_VALERT_VCCIN_CPU0
    8  SMB_VR_SDA_R     SDA  @BASEBOARD_FAB2_LIB.BASEBOARD_FAB2(SCH_1):SMB_VR_SDA_R
    9  SMB_VR_SCL_R     SCL  @BASEBOARD_FAB2_LIB.BASEBOARD_FAB2(SCH_1):SMB_VR_SCL_R
   15  PWRGD_PVSA_CPU0_R    MP0  @BASEBOARD_FAB2_LIB.BASEBOARD_FAB2(SCH_1):PWRGD_PVSA_CPU0_R
   46  PVCCIN_PVSA_CPU0_IINSEN  IINSEN  @BASEBOARD_FAB2_LIB.BASEBOARD_FAB2(SCH_1):PVCCIN_PVSA_CPU0_IINSEN
   39  PU_VR_PVCCIN_CPU0_IMON    MP3  @BASEBOARD_FAB2_LIB.BASEBOARD_FAB2(SCH_1):PU_VR_PVCCIN_CPU0_IMON
   20  PU_VR_PVCCIN_CPU0_FLT1_SMBALT_N    MP2  @BASEBOARD_FAB2_LIB.BASEBOARD_FAB2(SCH_1):PU_VR_PVCCIN_CPU0_FLT1_SMBALT_N_IMON
   38  ISENSE_PVSA_CPU0_IMON  BISEN1  @BASEBOARD_FAB2_LIB.BASEBOARD_FAB2(SCH_1):ISENSE_PVSA_CPU0_IMON
   32  ISENSE_PVCCIN_CPU0_PH5_IMON  AISEN5  @BASEBOARD_FAB2_LIB.BASEBOARD_FAB2(SCH_1):ISENSE_PVCCIN_CPU0_PH5_IMON
   30  ISENSE_PVCCIN_CPU0_PH4_IMON  AISEN4  @BASEBOARD_FAB2_LIB.BASEBOARD_FAB2(SCH_1):ISENSE_PVCCIN_CPU0_PH4_IMON
   28  ISENSE_PVCCIN_CPU0_PH3_IMON  AISEN3  @BASEBOARD_FAB2_LIB.BASEBOARD_FAB2(SCH_1):ISENSE_PVCCIN_CPU0_PH3_IMON
   26  ISENSE_PVCCIN_CPU0_PH2_IMON  AISEN2  @BASEBOARD_FAB2_LIB.BASEBOARD_FAB2(SCH_1):ISENSE_PVCCIN_CPU0_PH2_IMON
   24  ISENSE_PVCCIN_CPU0_PH1_IMON  AISEN1  @BASEBOARD_FAB2_LIB.BASEBOARD_FAB2(SCH_1):ISENSE_PVCCIN_CPU0_PH1_IMON
   13  IRQ_PVCCIN_CPU0_VRHOT_LVC3_R_N  VRHOT_N  @BASEBOARD_FAB2_LIB.BASEBOARD_FAB2(SCH_1):IRQ_PVCCIN_CPU0_VRHOT_LVC3_R_N
   49  GND            THPAD  @BASEBOARD_FAB2_LIB.BASEBOARD_FAB2(SCH_1):GND
   14  FM_PVCCIN_CPU0_PWR_IN_ALERT_N  PINALRT_N  @BASEBOARD_FAB2_LIB.BASEBOARD_FAB2(SCH_1):FM_PVCCIN_CPU0_PWR_IN_ALERT_N
   42  A_TSENSE_PVSA_CPU0  BTSEN  @BASEBOARD_FAB2_LIB.BASEBOARD_FAB2(SCH_1):A_TSENSE_PVSA_CPU0
   43  A_TSENSE_PVCCIN_CPU0  ATSEN  @BASEBOARD_FAB2_LIB.BASEBOARD_FAB2(SCH_1):A_TSENSE_PVCCIN_CPU0

PXE1110B_QFN  I96  EU4D5  [PXE1110B_QFN-IC,H89187-001]
   20  VSENSE_PVCCIO_CPU1_AVSN  AVREF  @BASEBOARD_FAB2_LIB.BASEBOARD_FAB2(SCH_1):VSENSE_PVCCIO_CPU1_AVSN
   33  VR_PVCCIO_CPU1_XADDR2  XADDR2  @BASEBOARD_FAB2_LIB.BASEBOARD_FAB2(SCH_1):VR_PVCCIO_CPU1_XADDR2
   36  VR_PVCCIO_CPU1_XADDR1  XADDR1  @BASEBOARD_FAB2_LIB.BASEBOARD_FAB2(SCH_1):VR_PVCCIO_CPU1_XADDR1
   37  VR_PVCCIO_CPU1_VINSEN  VINSEN  @BASEBOARD_FAB2_LIB.BASEBOARD_FAB2(SCH_1):VR_PVCCIO_CPU1_VINSEN
   39  VR_PVCCIO_CPU1_VDD    VDD  @BASEBOARD_FAB2_LIB.BASEBOARD_FAB2(SCH_1):VR_PVCCIO_CPU1_VDD
   40  VR_PVCCIO_CPU1_VD12   VD12  @BASEBOARD_FAB2_LIB.BASEBOARD_FAB2(SCH_1):VR_PVCCIO_CPU1_VD12
    5  VR_PVCCIO_CPU1_PWM1  APWM1  @BASEBOARD_FAB2_LIB.BASEBOARD_FAB2(SCH_1):VR_PVCCIO_CPU1_PWM1
   10  VR_PVCCIO_CPU1_EN  AVREN  @BASEBOARD_FAB2_LIB.BASEBOARD_FAB2(SCH_1):VR_PVCCIO_CPU1_EN
   19  VR_PVCCIO_CPU1_AVSP  AVSEN  @BASEBOARD_FAB2_LIB.BASEBOARD_FAB2(SCH_1):VR_PVCCIO_CPU1_AVSP
   21  VR_PVCCIO_CPU1_AIREF1  AIREF1  @BASEBOARD_FAB2_LIB.BASEBOARD_FAB2(SCH_1):VR_PVCCIO_CPU1_AIREF1
   31  TP_VR_PVCCIO_CPU1_MP3    MP3  @BASEBOARD_FAB2_LIB.BASEBOARD_FAB2(SCH_1):TP_VR_PVCCIO_CPU1_MP3
   18  TP_VR_PVCCIO_CPU1_MP2    MP2  @BASEBOARD_FAB2_LIB.BASEBOARD_FAB2(SCH_1):TP_VR_PVCCIO_CPU1_MP2
   14  TP_VR_PVCCIO_CPU1_MP1    MP1  @BASEBOARD_FAB2_LIB.BASEBOARD_FAB2(SCH_1):TP_VR_PVCCIO_CPU1_MP1
   13  TP_VR_PVCCIO_CPU1_MP0    MP0  @BASEBOARD_FAB2_LIB.BASEBOARD_FAB2(SCH_1):TP_VR_PVCCIO_CPU1_MP0
   38  TP_VR_PVCCIO_CPU1_AIINSEN  IINSEN  @BASEBOARD_FAB2_LIB.BASEBOARD_FAB2(SCH_1):TP_VR_PVCCIO_CPU1_AIINSEN
    8  TP_PVCCIO_CPU1_RESET_N  RESET_N  @BASEBOARD_FAB2_LIB.BASEBOARD_FAB2(SCH_1):TP_PVCCIO_CPU1_RESET_N
   12  TP_PVCCIO_CPU1_PINALRT_N  PINALRT_N  @BASEBOARD_FAB2_LIB.BASEBOARD_FAB2(SCH_1):TP_PVCCIO_CPU1_PINALRT_N
   29  TP_PVCCIO_CPU1_BVSEN  BVSEN  @BASEBOARD_FAB2_LIB.BASEBOARD_FAB2(SCH_1):TP_PVCCIO_CPU1_BVSEN
   30  TP_PVCCIO_CPU1_BVREF  BVREF  @BASEBOARD_FAB2_LIB.BASEBOARD_FAB2(SCH_1):TP_PVCCIO_CPU1_BVREF
   34  TP_PVCCIO_CPU1_BTSEN  BTSEN  @BASEBOARD_FAB2_LIB.BASEBOARD_FAB2(SCH_1):TP_PVCCIO_CPU1_BTSEN
    3  TP_PVCCIO_CPU1_BPWM1  BPWM1  @BASEBOARD_FAB2_LIB.BASEBOARD_FAB2(SCH_1):TP_PVCCIO_CPU1_BPWM1
   25  TP_PVCCIO_CPU1_BIREF1  BIREF1  @BASEBOARD_FAB2_LIB.BASEBOARD_FAB2(SCH_1):TP_PVCCIO_CPU1_BIREF1
   16  SVID_VDIO_PVCCIO_CPU1   VDIO  @BASEBOARD_FAB2_LIB.BASEBOARD_FAB2(SCH_1):SVID_VDIO_PVCCIO_CPU1
   15  SVID_CLK_PVCCIO_CPU1   VCLK  @BASEBOARD_FAB2_LIB.BASEBOARD_FAB2(SCH_1):SVID_CLK_PVCCIO_CPU1
   17  SVID_ALERT_PVCCIO_CPU1  VALRT_N  @BASEBOARD_FAB2_LIB.BASEBOARD_FAB2(SCH_1):SVID_ALERT_PVCCIO_CPU1
    6  SMB_VR_SDA_PVCCIO_CPU1    SDA  @BASEBOARD_FAB2_LIB.BASEBOARD_FAB2(SCH_1):SMB_VR_SDA_PVCCIO_CPU1
    7  SMB_VR_SCL_PVCCIO_CPU1    SCL  @BASEBOARD_FAB2_LIB.BASEBOARD_FAB2(SCH_1):SMB_VR_SCL_PVCCIO_CPU1
    9  PWRGD_PVCCIO_CPU1_R  AVRRDY  @BASEBOARD_FAB2_LIB.BASEBOARD_FAB2(SCH_1):PWRGD_PVCCIO_CPU1_R
   32  PU_VR_PVCCIO_CPU1_FAULT1    MP4  @BASEBOARD_FAB2_LIB.BASEBOARD_FAB2(SCH_1):PU_VR_PVCCIO_CPU1_FAULT1
   28  NC_PVCCIO_CPU1_DNC4  DNC<4>  @BASEBOARD_FAB2_LIB.BASEBOARD_FAB2(SCH_1):NC_PVCCIO_CPU1_DNC4
   24  NC_PVCCIO_CPU1_DNC3  DNC<3>  @BASEBOARD_FAB2_LIB.BASEBOARD_FAB2(SCH_1):NC_PVCCIO_CPU1_DNC3
    4  NC_PVCCIO_CPU1_DNC2  DNC<2>  @BASEBOARD_FAB2_LIB.BASEBOARD_FAB2(SCH_1):NC_PVCCIO_CPU1_DNC2
    2  NC_PVCCIO_CPU1_DNC1  DNC<1>  @BASEBOARD_FAB2_LIB.BASEBOARD_FAB2(SCH_1):NC_PVCCIO_CPU1_DNC1
    1  NC_PVCCIO_CPU1_DNC0  DNC<0>  @BASEBOARD_FAB2_LIB.BASEBOARD_FAB2(SCH_1):NC_PVCCIO_CPU1_DNC0
   22  ISENSE_PVCCIO_CPU1_PH1_IMON  AISEN1  @BASEBOARD_FAB2_LIB.BASEBOARD_FAB2(SCH_1):ISENSE_PVCCIO_CPU1_PH1_IMON
   11  IRQ_PVCCIO_CPU1_VRHOT_N  VRHOT_N  @BASEBOARD_FAB2_LIB.BASEBOARD_FAB2(SCH_1):IRQ_PVCCIO_CPU1_VRHOT_N
   41  GND            THPAD  @BASEBOARD_FAB2_LIB.BASEBOARD_FAB2(SCH_1):GND
   23  GND            GND<1>  @BASEBOARD_FAB2_LIB.BASEBOARD_FAB2(SCH_1):GND
   27  GND            GND<0>  @BASEBOARD_FAB2_LIB.BASEBOARD_FAB2(SCH_1):GND
   26  GND            BISEN1  @BASEBOARD_FAB2_LIB.BASEBOARD_FAB2(SCH_1):GND
   35  A_TSENSE_PVCCIO_CPU1  ATSEN  @BASEBOARD_FAB2_LIB.BASEBOARD_FAB2(SCH_1):A_TSENSE_PVCCIO_CPU1

IR354XX_SM  I64  EU4D6  [IR354XX_SM-IR35411,IC,H73688-0A]
   34  VR_PVCCIN_CPU0_PWM2    PWM  @BASEBOARD_FAB2_LIB.BASEBOARD_FAB2(SCH_1):VR_PVCCIN_CPU0_PWM2
   10  VR_PVCCIN_CPU0_PHASE2     SW  @BASEBOARD_FAB2_LIB.BASEBOARD_FAB2(SCH_1):VR_PVCCIN_CPU0_PHASE2
    3  VR_PVCCIN_CPU0_PH2_VCIN    VCC  @BASEBOARD_FAB2_LIB.BASEBOARD_FAB2(SCH_1):VR_PVCCIN_CPU0_PH2_VCIN
   32  VR_PVCCIN_CPU0_PH2_PHASE  PHASE  @BASEBOARD_FAB2_LIB.BASEBOARD_FAB2(SCH_1):VR_PVCCIN_CPU0_PH2_PHASE
   37  VR_PVCCIN_CPU0_PH2_OCSET  OCSET  @BASEBOARD_FAB2_LIB.BASEBOARD_FAB2(SCH_1):VR_PVCCIN_CPU0_PH2_OCSET
   33  VR_PVCCIN_CPU0_PH2_BOOT_R  BOOST  @BASEBOARD_FAB2_LIB.BASEBOARD_FAB2(SCH_1):VR_PVCCIN_CPU0_PH2_BOOT_R
   39  VR_PVCCIN_CPU0_AIREF2  REFIN  @BASEBOARD_FAB2_LIB.BASEBOARD_FAB2(SCH_1):VR_PVCCIN_CPU0_AIREF2
   30  VR_FET_SW_P12V_STBY_PVCCIN_CPU0  VIN<1>  @BASEBOARD_FAB2_LIB.BASEBOARD_FAB2(SCH_1):VR_FET_SW_P12V_STBY_PVCCIN_CPU0
   25  VR_FET_SW_P12V_STBY_PVCCIN_CPU0  VIN<0>  @BASEBOARD_FAB2_LIB.BASEBOARD_FAB2(SCH_1):VR_FET_SW_P12V_STBY_PVCCIN_CPU0
   41  TP_PVCCIN_CPU0_PH2_GL_1  GL<1>  @BASEBOARD_FAB2_LIB.BASEBOARD_FAB2(SCH_1):TP_PVCCIN_CPU0_PH2_GL_1
    6  TP_PVCCIN_CPU0_PH2_GL_0  GL<0>  @BASEBOARD_FAB2_LIB.BASEBOARD_FAB2(SCH_1):TP_PVCCIN_CPU0_PH2_GL_0
    1  PVCCIN_CPU0      VOS  @BASEBOARD_FAB2_LIB.BASEBOARD_FAB2(SCH_1):PVCCIN_CPU0
    4  P5V_STBY        VDRV  @BASEBOARD_FAB2_LIB.BASEBOARD_FAB2(SCH_1):P5V_STBY
   35  P5V_STBY          EN  @BASEBOARD_FAB2_LIB.BASEBOARD_FAB2(SCH_1):P5V_STBY
   31  NC_PVCCIN_CPU0_PH2_P31     NC  @BASEBOARD_FAB2_LIB.BASEBOARD_FAB2(SCH_1):NC_PVCCIN_CPU0_PH2_P31
   38  ISENSE_PVCCIN_CPU0_PH2_IMON   IOUT  @BASEBOARD_FAB2_LIB.BASEBOARD_FAB2(SCH_1):ISENSE_PVCCIN_CPU0_PH2_IMON
   40  GND            PGND<2>  @BASEBOARD_FAB2_LIB.BASEBOARD_FAB2(SCH_1):GND
    7  GND            PGND<1>  @BASEBOARD_FAB2_LIB.BASEBOARD_FAB2(SCH_1):GND
    5  GND            PGND<0>  @BASEBOARD_FAB2_LIB.BASEBOARD_FAB2(SCH_1):GND
    2  GND             LGND  @BASEBOARD_FAB2_LIB.BASEBOARD_FAB2(SCH_1):GND
   36  A_TSENSE_PVCCIN_CPU0  TOUT_FLT  @BASEBOARD_FAB2_LIB.BASEBOARD_FAB2(SCH_1):A_TSENSE_PVCCIN_CPU0

IR354XX_SM  I63  EU4E1  [IR354XX_SM-IR35411,IC,H73688-0A]
   34  VR_PVCCIN_CPU0_PWM1    PWM  @BASEBOARD_FAB2_LIB.BASEBOARD_FAB2(SCH_1):VR_PVCCIN_CPU0_PWM1
   10  VR_PVCCIN_CPU0_PHASE1     SW  @BASEBOARD_FAB2_LIB.BASEBOARD_FAB2(SCH_1):VR_PVCCIN_CPU0_PHASE1
    3  VR_PVCCIN_CPU0_PH1_VCIN    VCC  @BASEBOARD_FAB2_LIB.BASEBOARD_FAB2(SCH_1):VR_PVCCIN_CPU0_PH1_VCIN
   32  VR_PVCCIN_CPU0_PH1_PHASE  PHASE  @BASEBOARD_FAB2_LIB.BASEBOARD_FAB2(SCH_1):VR_PVCCIN_CPU0_PH1_PHASE
   37  VR_PVCCIN_CPU0_PH1_OCSET  OCSET  @BASEBOARD_FAB2_LIB.BASEBOARD_FAB2(SCH_1):VR_PVCCIN_CPU0_PH1_OCSET
   33  VR_PVCCIN_CPU0_PH1_BOOT_R  BOOST  @BASEBOARD_FAB2_LIB.BASEBOARD_FAB2(SCH_1):VR_PVCCIN_CPU0_PH1_BOOT_R
   39  VR_PVCCIN_CPU0_AIREF1  REFIN  @BASEBOARD_FAB2_LIB.BASEBOARD_FAB2(SCH_1):VR_PVCCIN_CPU0_AIREF1
   30  VR_FET_SW_P12V_STBY_PVCCIN_CPU0  VIN<1>  @BASEBOARD_FAB2_LIB.BASEBOARD_FAB2(SCH_1):VR_FET_SW_P12V_STBY_PVCCIN_CPU0
   25  VR_FET_SW_P12V_STBY_PVCCIN_CPU0  VIN<0>  @BASEBOARD_FAB2_LIB.BASEBOARD_FAB2(SCH_1):VR_FET_SW_P12V_STBY_PVCCIN_CPU0
   41  TP_PVCCIN_CPU0_PH1_GL_1  GL<1>  @BASEBOARD_FAB2_LIB.BASEBOARD_FAB2(SCH_1):TP_PVCCIN_CPU0_PH1_GL_1
    6  TP_PVCCIN_CPU0_PH1_GL_0  GL<0>  @BASEBOARD_FAB2_LIB.BASEBOARD_FAB2(SCH_1):TP_PVCCIN_CPU0_PH1_GL_0
    1  PVCCIN_CPU0      VOS  @BASEBOARD_FAB2_LIB.BASEBOARD_FAB2(SCH_1):PVCCIN_CPU0
    4  P5V_STBY        VDRV  @BASEBOARD_FAB2_LIB.BASEBOARD_FAB2(SCH_1):P5V_STBY
   35  P5V_STBY          EN  @BASEBOARD_FAB2_LIB.BASEBOARD_FAB2(SCH_1):P5V_STBY
   31  NC_PVCCIN_CPU0_PH1_P31     NC  @BASEBOARD_FAB2_LIB.BASEBOARD_FAB2(SCH_1):NC_PVCCIN_CPU0_PH1_P31
   38  ISENSE_PVCCIN_CPU0_PH1_IMON   IOUT  @BASEBOARD_FAB2_LIB.BASEBOARD_FAB2(SCH_1):ISENSE_PVCCIN_CPU0_PH1_IMON
   40  GND            PGND<2>  @BASEBOARD_FAB2_LIB.BASEBOARD_FAB2(SCH_1):GND
    7  GND            PGND<1>  @BASEBOARD_FAB2_LIB.BASEBOARD_FAB2(SCH_1):GND
    5  GND            PGND<0>  @BASEBOARD_FAB2_LIB.BASEBOARD_FAB2(SCH_1):GND
    2  GND             LGND  @BASEBOARD_FAB2_LIB.BASEBOARD_FAB2(SCH_1):GND
   36  A_TSENSE_PVCCIN_CPU0  TOUT_FLT  @BASEBOARD_FAB2_LIB.BASEBOARD_FAB2(SCH_1):A_TSENSE_PVCCIN_CPU0

IR354XX_SM  I126  EU4E2  [IR354XX_SM-IR35412,IC,H73684-0A]
   34  VR_PVCCIO_CPU1_PWM1    PWM  @BASEBOARD_FAB2_LIB.BASEBOARD_FAB2(SCH_1):VR_PVCCIO_CPU1_PWM1
    3  VR_PVCCIO_CPU1_PH1_VCIN    VCC  @BASEBOARD_FAB2_LIB.BASEBOARD_FAB2(SCH_1):VR_PVCCIO_CPU1_PH1_VCIN
   10  VR_PVCCIO_CPU1_PH1_SW     SW  @BASEBOARD_FAB2_LIB.BASEBOARD_FAB2(SCH_1):VR_PVCCIO_CPU1_PH1_SW
   32  VR_PVCCIO_CPU1_PH1_PHASE  PHASE  @BASEBOARD_FAB2_LIB.BASEBOARD_FAB2(SCH_1):VR_PVCCIO_CPU1_PH1_PHASE
   33  VR_PVCCIO_CPU1_PH1_BOOT_R  BOOST  @BASEBOARD_FAB2_LIB.BASEBOARD_FAB2(SCH_1):VR_PVCCIO_CPU1_PH1_BOOT_R
   37  VR_PVCCIO_CPU1_OCSET  OCSET  @BASEBOARD_FAB2_LIB.BASEBOARD_FAB2(SCH_1):VR_PVCCIO_CPU1_OCSET
   39  VR_PVCCIO_CPU1_AIREF1  REFIN  @BASEBOARD_FAB2_LIB.BASEBOARD_FAB2(SCH_1):VR_PVCCIO_CPU1_AIREF1
   30  VR_FET_SW_P12V_STBY_PVCCIN_CPU0  VIN<1>  @BASEBOARD_FAB2_LIB.BASEBOARD_FAB2(SCH_1):VR_FET_SW_P12V_STBY_PVCCIN_CPU0
   25  VR_FET_SW_P12V_STBY_PVCCIN_CPU0  VIN<0>  @BASEBOARD_FAB2_LIB.BASEBOARD_FAB2(SCH_1):VR_FET_SW_P12V_STBY_PVCCIN_CPU0
   41  TP_PVCCIO_CPU1_GL_1  GL<1>  @BASEBOARD_FAB2_LIB.BASEBOARD_FAB2(SCH_1):TP_PVCCIO_CPU1_GL_1
    6  TP_PVCCIO_CPU1_GL_0  GL<0>  @BASEBOARD_FAB2_LIB.BASEBOARD_FAB2(SCH_1):TP_PVCCIO_CPU1_GL_0
    1  PVCCIO_CPU1      VOS  @BASEBOARD_FAB2_LIB.BASEBOARD_FAB2(SCH_1):PVCCIO_CPU1
    4  P5V_STBY        VDRV  @BASEBOARD_FAB2_LIB.BASEBOARD_FAB2(SCH_1):P5V_STBY
   35  P5V_STBY          EN  @BASEBOARD_FAB2_LIB.BASEBOARD_FAB2(SCH_1):P5V_STBY
   31  NC_PVCCIO_CPU1_PH1_P31     NC  @BASEBOARD_FAB2_LIB.BASEBOARD_FAB2(SCH_1):NC_PVCCIO_CPU1_PH1_P31
   38  ISENSE_PVCCIO_CPU1_PH1_IMON   IOUT  @BASEBOARD_FAB2_LIB.BASEBOARD_FAB2(SCH_1):ISENSE_PVCCIO_CPU1_PH1_IMON
   40  GND            PGND<2>  @BASEBOARD_FAB2_LIB.BASEBOARD_FAB2(SCH_1):GND
    7  GND            PGND<1>  @BASEBOARD_FAB2_LIB.BASEBOARD_FAB2(SCH_1):GND
    5  GND            PGND<0>  @BASEBOARD_FAB2_LIB.BASEBOARD_FAB2(SCH_1):GND
    2  GND             LGND  @BASEBOARD_FAB2_LIB.BASEBOARD_FAB2(SCH_1):GND
   36  A_TSENSE_PVCCIO_CPU1  TOUT_FLT  @BASEBOARD_FAB2_LIB.BASEBOARD_FAB2(SCH_1):A_TSENSE_PVCCIO_CPU1

NCP3232L_SM  I225  EU4G1  [NCP3232L_SM-IC,H86355-001]
   38  VR_VB_PVPP_GHJ     VB  @BASEBOARD_FAB2_LIB.BASEBOARD_FAB2(SCH_1):VR_VB_PVPP_GHJ
    1  VR_PVPP_GHJ_SS     SS  @BASEBOARD_FAB2_LIB.BASEBOARD_FAB2(SCH_1):VR_PVPP_GHJ_SS
   43  VR_PVPP_GHJ_PHASE  VSWH<7>  @BASEBOARD_FAB2_LIB.BASEBOARD_FAB2(SCH_1):VR_PVPP_GHJ_PHASE
   34  VR_PVPP_GHJ_PHASE  VSWH<6>  @BASEBOARD_FAB2_LIB.BASEBOARD_FAB2(SCH_1):VR_PVPP_GHJ_PHASE
   33  VR_PVPP_GHJ_PHASE  VSWH<5>  @BASEBOARD_FAB2_LIB.BASEBOARD_FAB2(SCH_1):VR_PVPP_GHJ_PHASE
   32  VR_PVPP_GHJ_PHASE  VSWH<4>  @BASEBOARD_FAB2_LIB.BASEBOARD_FAB2(SCH_1):VR_PVPP_GHJ_PHASE
   31  VR_PVPP_GHJ_PHASE  VSWH<3>  @BASEBOARD_FAB2_LIB.BASEBOARD_FAB2(SCH_1):VR_PVPP_GHJ_PHASE
   30  VR_PVPP_GHJ_PHASE  VSWH<2>  @BASEBOARD_FAB2_LIB.BASEBOARD_FAB2(SCH_1):VR_PVPP_GHJ_PHASE
   29  VR_PVPP_GHJ_PHASE  VSWH<1>  @BASEBOARD_FAB2_LIB.BASEBOARD_FAB2(SCH_1):VR_PVPP_GHJ_PHASE
   15  VR_PVPP_GHJ_PHASE  VSWH<0>  @BASEBOARD_FAB2_LIB.BASEBOARD_FAB2(SCH_1):VR_PVPP_GHJ_PHASE
   35  VR_PVPP_GHJ_PHASE    VSW  @BASEBOARD_FAB2_LIB.BASEBOARD_FAB2(SCH_1):VR_PVPP_GHJ_PHASE
    4  VR_PVPP_GHJ_ISET   ISET  @BASEBOARD_FAB2_LIB.BASEBOARD_FAB2(SCH_1):VR_PVPP_GHJ_ISET
   36  VR_PVPP_GHJ_BOOT    BST  @BASEBOARD_FAB2_LIB.BASEBOARD_FAB2(SCH_1):VR_PVPP_GHJ_BOOT
   42  VR_FET_SW_P12V_STBY_PVPP_GHJ  VIN<7>  @BASEBOARD_FAB2_LIB.BASEBOARD_FAB2(SCH_1):VR_FET_SW_P12V_STBY_PVPP_GHJ
   14  VR_FET_SW_P12V_STBY_PVPP_GHJ  VIN<6>  @BASEBOARD_FAB2_LIB.BASEBOARD_FAB2(SCH_1):VR_FET_SW_P12V_STBY_PVPP_GHJ
   13  VR_FET_SW_P12V_STBY_PVPP_GHJ  VIN<5>  @BASEBOARD_FAB2_LIB.BASEBOARD_FAB2(SCH_1):VR_FET_SW_P12V_STBY_PVPP_GHJ
   12  VR_FET_SW_P12V_STBY_PVPP_GHJ  VIN<4>  @BASEBOARD_FAB2_LIB.BASEBOARD_FAB2(SCH_1):VR_FET_SW_P12V_STBY_PVPP_GHJ
   11  VR_FET_SW_P12V_STBY_PVPP_GHJ  VIN<3>  @BASEBOARD_FAB2_LIB.BASEBOARD_FAB2(SCH_1):VR_FET_SW_P12V_STBY_PVPP_GHJ
   10  VR_FET_SW_P12V_STBY_PVPP_GHJ  VIN<2>  @BASEBOARD_FAB2_LIB.BASEBOARD_FAB2(SCH_1):VR_FET_SW_P12V_STBY_PVPP_GHJ
    9  VR_FET_SW_P12V_STBY_PVPP_GHJ  VIN<1>  @BASEBOARD_FAB2_LIB.BASEBOARD_FAB2(SCH_1):VR_FET_SW_P12V_STBY_PVPP_GHJ
    8  VR_FET_SW_P12V_STBY_PVPP_GHJ  VIN<0>  @BASEBOARD_FAB2_LIB.BASEBOARD_FAB2(SCH_1):VR_FET_SW_P12V_STBY_PVPP_GHJ
   39  VR_FET_SW_P12V_STBY_PVPP_GHJ    VCC  @BASEBOARD_FAB2_LIB.BASEBOARD_FAB2(SCH_1):VR_FET_SW_P12V_STBY_PVPP_GHJ
    2  VR_FB_PVPP_GHJ     FB  @BASEBOARD_FAB2_LIB.BASEBOARD_FAB2(SCH_1):VR_FB_PVPP_GHJ
    3  VR_COMP_PVPP_GHJ_3   COMP  @BASEBOARD_FAB2_LIB.BASEBOARD_FAB2(SCH_1):VR_COMP_PVPP_GHJ_3
    7  PWRGD_PVPP_GHJ_R     PG  @BASEBOARD_FAB2_LIB.BASEBOARD_FAB2(SCH_1):PWRGD_PVPP_GHJ_R
   37  GND            PGND<13>  @BASEBOARD_FAB2_LIB.BASEBOARD_FAB2(SCH_1):GND
   28  GND            PGND<12>  @BASEBOARD_FAB2_LIB.BASEBOARD_FAB2(SCH_1):GND
   27  GND            PGND<11>  @BASEBOARD_FAB2_LIB.BASEBOARD_FAB2(SCH_1):GND
   26  GND            PGND<10>  @BASEBOARD_FAB2_LIB.BASEBOARD_FAB2(SCH_1):GND
   25  GND            PGND<9>  @BASEBOARD_FAB2_LIB.BASEBOARD_FAB2(SCH_1):GND
   24  GND            PGND<8>  @BASEBOARD_FAB2_LIB.BASEBOARD_FAB2(SCH_1):GND
   23  GND            PGND<7>  @BASEBOARD_FAB2_LIB.BASEBOARD_FAB2(SCH_1):GND
   22  GND            PGND<6>  @BASEBOARD_FAB2_LIB.BASEBOARD_FAB2(SCH_1):GND
   21  GND            PGND<5>  @BASEBOARD_FAB2_LIB.BASEBOARD_FAB2(SCH_1):GND
   20  GND            PGND<4>  @BASEBOARD_FAB2_LIB.BASEBOARD_FAB2(SCH_1):GND
   19  GND            PGND<3>  @BASEBOARD_FAB2_LIB.BASEBOARD_FAB2(SCH_1):GND
   18  GND            PGND<2>  @BASEBOARD_FAB2_LIB.BASEBOARD_FAB2(SCH_1):GND
   17  GND            PGND<1>  @BASEBOARD_FAB2_LIB.BASEBOARD_FAB2(SCH_1):GND
   16  GND            PGND<0>  @BASEBOARD_FAB2_LIB.BASEBOARD_FAB2(SCH_1):GND
   41  GND              GND  @BASEBOARD_FAB2_LIB.BASEBOARD_FAB2(SCH_1):GND
   40  FM_PVPP_PVDDQ_CPU1_EN_GHJ     EN  @BASEBOARD_FAB2_LIB.BASEBOARD_FAB2(SCH_1):FM_PVPP_PVDDQ_CPU1_EN_GHJ
    6  AGND_PVPP_GHJ    OTS  @BASEBOARD_FAB2_LIB.BASEBOARD_FAB2(SCH_1):AGND_PVPP_GHJ
    5  AGND_PVPP_GHJ   AGND  @BASEBOARD_FAB2_LIB.BASEBOARD_FAB2(SCH_1):AGND_PVPP_GHJ

MIC5166_DFN  I24  EU4G2  [MIC5166_DFN-IC,H55101-001]
    4  VSENSE_PVDDQ_GHJ_VTT   VDDQ  @BASEBOARD_FAB2_LIB.BASEBOARD_FAB2(SCH_1):VSENSE_PVDDQ_GHJ_VTT
    1  VR_PVTT_GHJ_VREF   VREF  @BASEBOARD_FAB2_LIB.BASEBOARD_FAB2(SCH_1):VR_PVTT_GHJ_VREF
    6  VR_PVTT_GHJ_SNS    SNS  @BASEBOARD_FAB2_LIB.BASEBOARD_FAB2(SCH_1):VR_PVTT_GHJ_SNS
    2  VR_PVTT_GHJ_BIAS   BIAS  @BASEBOARD_FAB2_LIB.BASEBOARD_FAB2(SCH_1):VR_PVTT_GHJ_BIAS
    5  PWRGD_PVTT_GHJ_CPU1_R     PG  @BASEBOARD_FAB2_LIB.BASEBOARD_FAB2(SCH_1):PWRGD_PVTT_GHJ_CPU1_R
    9  PVTT_GHJ         VTT  @BASEBOARD_FAB2_LIB.BASEBOARD_FAB2(SCH_1):PVTT_GHJ
   10  PVDDQ_GHJ        VIN  @BASEBOARD_FAB2_LIB.BASEBOARD_FAB2(SCH_1):PVDDQ_GHJ
   11  GND            THPAD  @BASEBOARD_FAB2_LIB.BASEBOARD_FAB2(SCH_1):GND
    8  GND             PGND  @BASEBOARD_FAB2_LIB.BASEBOARD_FAB2(SCH_1):GND
    3  GND             AGND  @BASEBOARD_FAB2_LIB.BASEBOARD_FAB2(SCH_1):GND
    7  FM_PVTT_GHJ_EN_R     EN  @BASEBOARD_FAB2_LIB.BASEBOARD_FAB2(SCH_1):FM_PVTT_GHJ_EN_R

MIC5166_DFN  I1   EU4G3  [MIC5166_DFN-IC,H55101-001]
    4  VSENSE_PVDDQ_ABC_VTT   VDDQ  @BASEBOARD_FAB2_LIB.BASEBOARD_FAB2(SCH_1):VSENSE_PVDDQ_ABC_VTT
    1  VR_PVTT_ABC_VREF   VREF  @BASEBOARD_FAB2_LIB.BASEBOARD_FAB2(SCH_1):VR_PVTT_ABC_VREF
    6  VR_PVTT_ABC_SNS    SNS  @BASEBOARD_FAB2_LIB.BASEBOARD_FAB2(SCH_1):VR_PVTT_ABC_SNS
    2  VR_PVTT_ABC_BIAS   BIAS  @BASEBOARD_FAB2_LIB.BASEBOARD_FAB2(SCH_1):VR_PVTT_ABC_BIAS
    5  PWRGD_PVTT_ABC_CPU0_R     PG  @BASEBOARD_FAB2_LIB.BASEBOARD_FAB2(SCH_1):PWRGD_PVTT_ABC_CPU0_R
    9  PVTT_ABC         VTT  @BASEBOARD_FAB2_LIB.BASEBOARD_FAB2(SCH_1):PVTT_ABC
   10  PVDDQ_ABC        VIN  @BASEBOARD_FAB2_LIB.BASEBOARD_FAB2(SCH_1):PVDDQ_ABC
   11  GND            THPAD  @BASEBOARD_FAB2_LIB.BASEBOARD_FAB2(SCH_1):GND
    8  GND             PGND  @BASEBOARD_FAB2_LIB.BASEBOARD_FAB2(SCH_1):GND
    3  GND             AGND  @BASEBOARD_FAB2_LIB.BASEBOARD_FAB2(SCH_1):GND
    7  FM_PVTT_ABC_EN_R     EN  @BASEBOARD_FAB2_LIB.BASEBOARD_FAB2(SCH_1):FM_PVTT_ABC_EN_R

IR354XX_SM  I106  EU7A1  [IR354XX_SM-IR35411,IC,H73688-0A]
   34  VR_PVDDQ_DEF_PWM1    PWM  @BASEBOARD_FAB2_LIB.BASEBOARD_FAB2(SCH_1):VR_PVDDQ_DEF_PWM1
    3  VR_PVDDQ_DEF_PH1_VCIN    VCC  @BASEBOARD_FAB2_LIB.BASEBOARD_FAB2(SCH_1):VR_PVDDQ_DEF_PH1_VCIN
   10  VR_PVDDQ_DEF_PH1_SW     SW  @BASEBOARD_FAB2_LIB.BASEBOARD_FAB2(SCH_1):VR_PVDDQ_DEF_PH1_SW
   32  VR_PVDDQ_DEF_PH1_PHASE  PHASE  @BASEBOARD_FAB2_LIB.BASEBOARD_FAB2(SCH_1):VR_PVDDQ_DEF_PH1_PHASE
   37  VR_PVDDQ_DEF_PH1_OCSET  OCSET  @BASEBOARD_FAB2_LIB.BASEBOARD_FAB2(SCH_1):VR_PVDDQ_DEF_PH1_OCSET
   33  VR_PVDDQ_DEF_PH1_BOOT_R  BOOST  @BASEBOARD_FAB2_LIB.BASEBOARD_FAB2(SCH_1):VR_PVDDQ_DEF_PH1_BOOT_R
   39  VR_PVDDQ_DEF_AIREF1  REFIN  @BASEBOARD_FAB2_LIB.BASEBOARD_FAB2(SCH_1):VR_PVDDQ_DEF_AIREF1
   30  VR_FET_SW_P12V_STBY_PVDDQ_DEF  VIN<1>  @BASEBOARD_FAB2_LIB.BASEBOARD_FAB2(SCH_1):VR_FET_SW_P12V_STBY_PVDDQ_DEF
   25  VR_FET_SW_P12V_STBY_PVDDQ_DEF  VIN<0>  @BASEBOARD_FAB2_LIB.BASEBOARD_FAB2(SCH_1):VR_FET_SW_P12V_STBY_PVDDQ_DEF
   41  TP_PVDDQ_DEF_PH1_GL_1  GL<1>  @BASEBOARD_FAB2_LIB.BASEBOARD_FAB2(SCH_1):TP_PVDDQ_DEF_PH1_GL_1
    6  TP_PVDDQ_DEF_PH1_GL_0  GL<0>  @BASEBOARD_FAB2_LIB.BASEBOARD_FAB2(SCH_1):TP_PVDDQ_DEF_PH1_GL_0
    1  PVDDQ_DEF        VOS  @BASEBOARD_FAB2_LIB.BASEBOARD_FAB2(SCH_1):PVDDQ_DEF
    4  P5V_STBY        VDRV  @BASEBOARD_FAB2_LIB.BASEBOARD_FAB2(SCH_1):P5V_STBY
   35  P5V_STBY          EN  @BASEBOARD_FAB2_LIB.BASEBOARD_FAB2(SCH_1):P5V_STBY
   31  NC_PVDDQ_DEF_PH1_P31     NC  @BASEBOARD_FAB2_LIB.BASEBOARD_FAB2(SCH_1):NC_PVDDQ_DEF_PH1_P31
   38  ISENSE_PVDDQ_DEF_PH1_IMON   IOUT  @BASEBOARD_FAB2_LIB.BASEBOARD_FAB2(SCH_1):ISENSE_PVDDQ_DEF_PH1_IMON
   40  GND            PGND<2>  @BASEBOARD_FAB2_LIB.BASEBOARD_FAB2(SCH_1):GND
    7  GND            PGND<1>  @BASEBOARD_FAB2_LIB.BASEBOARD_FAB2(SCH_1):GND
    5  GND            PGND<0>  @BASEBOARD_FAB2_LIB.BASEBOARD_FAB2(SCH_1):GND
    2  GND             LGND  @BASEBOARD_FAB2_LIB.BASEBOARD_FAB2(SCH_1):GND
   36  A_TSENSE_PVDDQ_DEF  TOUT_FLT  @BASEBOARD_FAB2_LIB.BASEBOARD_FAB2(SCH_1):A_TSENSE_PVDDQ_DEF

IR354XX_SM  I117  EU7A2  [IR354XX_SM-IR35412,IC,H73684-0A]
   34  VR_P1V05_PCH_STBY_PWM1    PWM  @BASEBOARD_FAB2_LIB.BASEBOARD_FAB2(SCH_1):VR_P1V05_PCH_STBY_PWM1
    3  VR_P1V05_PCH_STBY_PH1_VCIN    VCC  @BASEBOARD_FAB2_LIB.BASEBOARD_FAB2(SCH_1):VR_P1V05_PCH_STBY_PH1_VCIN
   10  VR_P1V05_PCH_STBY_PH1_PHASE_SW     SW  @BASEBOARD_FAB2_LIB.BASEBOARD_FAB2(SCH_1):VR_P1V05_PCH_STBY_PH1_PHASE_SW
   32  VR_P1V05_PCH_STBY_PH1_PHASE  PHASE  @BASEBOARD_FAB2_LIB.BASEBOARD_FAB2(SCH_1):VR_P1V05_PCH_STBY_PH1_PHASE
   33  VR_P1V05_PCH_STBY_PH1_BOOT_R  BOOST  @BASEBOARD_FAB2_LIB.BASEBOARD_FAB2(SCH_1):VR_P1V05_PCH_STBY_PH1_BOOT_R
   37  VR_P1V05_PCH_STBY_OCSET  OCSET  @BASEBOARD_FAB2_LIB.BASEBOARD_FAB2(SCH_1):VR_P1V05_PCH_STBY_OCSET
   39  VR_P1V05_PCH_BIREF1  REFIN  @BASEBOARD_FAB2_LIB.BASEBOARD_FAB2(SCH_1):VR_P1V05_PCH_BIREF1
   30  VR_FET_SW_P12V_STBY_PVDDQ_DEF  VIN<1>  @BASEBOARD_FAB2_LIB.BASEBOARD_FAB2(SCH_1):VR_FET_SW_P12V_STBY_PVDDQ_DEF
   25  VR_FET_SW_P12V_STBY_PVDDQ_DEF  VIN<0>  @BASEBOARD_FAB2_LIB.BASEBOARD_FAB2(SCH_1):VR_FET_SW_P12V_STBY_PVDDQ_DEF
   41  TP_P1V05_PCH_GL_1  GL<1>  @BASEBOARD_FAB2_LIB.BASEBOARD_FAB2(SCH_1):TP_P1V05_PCH_GL_1
    6  TP_P1V05_PCH_GL_0  GL<0>  @BASEBOARD_FAB2_LIB.BASEBOARD_FAB2(SCH_1):TP_P1V05_PCH_GL_0
    4  P5V_STBY        VDRV  @BASEBOARD_FAB2_LIB.BASEBOARD_FAB2(SCH_1):P5V_STBY
   35  P5V_STBY          EN  @BASEBOARD_FAB2_LIB.BASEBOARD_FAB2(SCH_1):P5V_STBY
    1  P1V05_PCH_STBY    VOS  @BASEBOARD_FAB2_LIB.BASEBOARD_FAB2(SCH_1):P1V05_PCH_STBY
   31  NC_P1V05_PCH_STBY_PH1_P31     NC  @BASEBOARD_FAB2_LIB.BASEBOARD_FAB2(SCH_1):NC_P1V05_PCH_STBY_PH1_P31
   38  ISENSE_P1V05_PCH_STBY_PH1_IMON   IOUT  @BASEBOARD_FAB2_LIB.BASEBOARD_FAB2(SCH_1):ISENSE_P1V05_PCH_STBY_PH1_IMON
   40  GND            PGND<2>  @BASEBOARD_FAB2_LIB.BASEBOARD_FAB2(SCH_1):GND
    7  GND            PGND<1>  @BASEBOARD_FAB2_LIB.BASEBOARD_FAB2(SCH_1):GND
    5  GND            PGND<0>  @BASEBOARD_FAB2_LIB.BASEBOARD_FAB2(SCH_1):GND
    2  GND             LGND  @BASEBOARD_FAB2_LIB.BASEBOARD_FAB2(SCH_1):GND
   36  A_TSENSE_P1V05_PCH_STBY_TMON  TOUT_FLT  @BASEBOARD_FAB2_LIB.BASEBOARD_FAB2(SCH_1):A_TSENSE_P1V05_PCH_STBY_TMON

IR354XX_SM  I116  EU7A3  [IR354XX_SM-IR35412,IC,H73684-0A]
   37  VR_PVNN_PCH_STBY_OCSET  OCSET  @BASEBOARD_FAB2_LIB.BASEBOARD_FAB2(SCH_1):VR_PVNN_PCH_STBY_OCSET
   34  VR_PVNN_PCH_PWM1    PWM  @BASEBOARD_FAB2_LIB.BASEBOARD_FAB2(SCH_1):VR_PVNN_PCH_PWM1
    3  VR_PVNN_PCH_PH1_VCIN    VCC  @BASEBOARD_FAB2_LIB.BASEBOARD_FAB2(SCH_1):VR_PVNN_PCH_PH1_VCIN
   10  VR_PVNN_PCH_PH1_PHASE_SW     SW  @BASEBOARD_FAB2_LIB.BASEBOARD_FAB2(SCH_1):VR_PVNN_PCH_PH1_PHASE_SW
   32  VR_PVNN_PCH_PH1_PHASE  PHASE  @BASEBOARD_FAB2_LIB.BASEBOARD_FAB2(SCH_1):VR_PVNN_PCH_PH1_PHASE
   33  VR_PVNN_PCH_PH1_BOOT_R  BOOST  @BASEBOARD_FAB2_LIB.BASEBOARD_FAB2(SCH_1):VR_PVNN_PCH_PH1_BOOT_R
   39  VR_PVNN_PCH_AIREF1  REFIN  @BASEBOARD_FAB2_LIB.BASEBOARD_FAB2(SCH_1):VR_PVNN_PCH_AIREF1
   30  VR_FET_SW_P12V_STBY_PVDDQ_DEF  VIN<1>  @BASEBOARD_FAB2_LIB.BASEBOARD_FAB2(SCH_1):VR_FET_SW_P12V_STBY_PVDDQ_DEF
   25  VR_FET_SW_P12V_STBY_PVDDQ_DEF  VIN<0>  @BASEBOARD_FAB2_LIB.BASEBOARD_FAB2(SCH_1):VR_FET_SW_P12V_STBY_PVDDQ_DEF
   41  TP_PVNN_PCH_GL_1  GL<1>  @BASEBOARD_FAB2_LIB.BASEBOARD_FAB2(SCH_1):TP_PVNN_PCH_GL_1
    6  TP_PVNN_PCH_GL_0  GL<0>  @BASEBOARD_FAB2_LIB.BASEBOARD_FAB2(SCH_1):TP_PVNN_PCH_GL_0
    1  PVNN_PCH_STBY    VOS  @BASEBOARD_FAB2_LIB.BASEBOARD_FAB2(SCH_1):PVNN_PCH_STBY
    4  P5V_STBY        VDRV  @BASEBOARD_FAB2_LIB.BASEBOARD_FAB2(SCH_1):P5V_STBY
   35  P5V_STBY          EN  @BASEBOARD_FAB2_LIB.BASEBOARD_FAB2(SCH_1):P5V_STBY
   31  NC_PVNN_PCH_PH1_P31     NC  @BASEBOARD_FAB2_LIB.BASEBOARD_FAB2(SCH_1):NC_PVNN_PCH_PH1_P31
   38  ISENSE_PVNN_PCH_PH1_IMON   IOUT  @BASEBOARD_FAB2_LIB.BASEBOARD_FAB2(SCH_1):ISENSE_PVNN_PCH_PH1_IMON
   40  GND            PGND<2>  @BASEBOARD_FAB2_LIB.BASEBOARD_FAB2(SCH_1):GND
    7  GND            PGND<1>  @BASEBOARD_FAB2_LIB.BASEBOARD_FAB2(SCH_1):GND
    5  GND            PGND<0>  @BASEBOARD_FAB2_LIB.BASEBOARD_FAB2(SCH_1):GND
    2  GND             LGND  @BASEBOARD_FAB2_LIB.BASEBOARD_FAB2(SCH_1):GND
   36  A_TSENSE_PVNN_PCH_TMON  TOUT_FLT  @BASEBOARD_FAB2_LIB.BASEBOARD_FAB2(SCH_1):A_TSENSE_PVNN_PCH_TMON

IR354XX_SM  I107  EU7A4  [IR354XX_SM-IR35411,IC,H73688-0A]
   34  VR_PVDDQ_DEF_PWM2    PWM  @BASEBOARD_FAB2_LIB.BASEBOARD_FAB2(SCH_1):VR_PVDDQ_DEF_PWM2
    3  VR_PVDDQ_DEF_PH2_VCIN    VCC  @BASEBOARD_FAB2_LIB.BASEBOARD_FAB2(SCH_1):VR_PVDDQ_DEF_PH2_VCIN
   10  VR_PVDDQ_DEF_PH2_SW     SW  @BASEBOARD_FAB2_LIB.BASEBOARD_FAB2(SCH_1):VR_PVDDQ_DEF_PH2_SW
   32  VR_PVDDQ_DEF_PH2_PHASE  PHASE  @BASEBOARD_FAB2_LIB.BASEBOARD_FAB2(SCH_1):VR_PVDDQ_DEF_PH2_PHASE
   37  VR_PVDDQ_DEF_PH2_OCSET  OCSET  @BASEBOARD_FAB2_LIB.BASEBOARD_FAB2(SCH_1):VR_PVDDQ_DEF_PH2_OCSET
   33  VR_PVDDQ_DEF_PH2_BOOT_R  BOOST  @BASEBOARD_FAB2_LIB.BASEBOARD_FAB2(SCH_1):VR_PVDDQ_DEF_PH2_BOOT_R
   39  VR_PVDDQ_DEF_AIREF2  REFIN  @BASEBOARD_FAB2_LIB.BASEBOARD_FAB2(SCH_1):VR_PVDDQ_DEF_AIREF2
   30  VR_FET_SW_P12V_STBY_PVDDQ_DEF  VIN<1>  @BASEBOARD_FAB2_LIB.BASEBOARD_FAB2(SCH_1):VR_FET_SW_P12V_STBY_PVDDQ_DEF
   25  VR_FET_SW_P12V_STBY_PVDDQ_DEF  VIN<0>  @BASEBOARD_FAB2_LIB.BASEBOARD_FAB2(SCH_1):VR_FET_SW_P12V_STBY_PVDDQ_DEF
   41  TP_PVDDQ_DEF_PH2_GL_1  GL<1>  @BASEBOARD_FAB2_LIB.BASEBOARD_FAB2(SCH_1):TP_PVDDQ_DEF_PH2_GL_1
    6  TP_PVDDQ_DEF_PH2_GL_0  GL<0>  @BASEBOARD_FAB2_LIB.BASEBOARD_FAB2(SCH_1):TP_PVDDQ_DEF_PH2_GL_0
    1  PVDDQ_DEF        VOS  @BASEBOARD_FAB2_LIB.BASEBOARD_FAB2(SCH_1):PVDDQ_DEF
    4  P5V_STBY        VDRV  @BASEBOARD_FAB2_LIB.BASEBOARD_FAB2(SCH_1):P5V_STBY
   35  P5V_STBY          EN  @BASEBOARD_FAB2_LIB.BASEBOARD_FAB2(SCH_1):P5V_STBY
   31  NC_PVDDQ_DEF_PH2_P31     NC  @BASEBOARD_FAB2_LIB.BASEBOARD_FAB2(SCH_1):NC_PVDDQ_DEF_PH2_P31
   38  ISENSE_PVDDQ_DEF_PH2_IMON   IOUT  @BASEBOARD_FAB2_LIB.BASEBOARD_FAB2(SCH_1):ISENSE_PVDDQ_DEF_PH2_IMON
   40  GND            PGND<2>  @BASEBOARD_FAB2_LIB.BASEBOARD_FAB2(SCH_1):GND
    7  GND            PGND<1>  @BASEBOARD_FAB2_LIB.BASEBOARD_FAB2(SCH_1):GND
    5  GND            PGND<0>  @BASEBOARD_FAB2_LIB.BASEBOARD_FAB2(SCH_1):GND
    2  GND             LGND  @BASEBOARD_FAB2_LIB.BASEBOARD_FAB2(SCH_1):GND
   36  A_TSENSE_PVDDQ_DEF  TOUT_FLT  @BASEBOARD_FAB2_LIB.BASEBOARD_FAB2(SCH_1):A_TSENSE_PVDDQ_DEF

PXM1310B_QFN  I75  EU7A5  [PXM1310B_QFN-IC,H89186-001]
   20  VSENSE_PVDDQ_DEF_N  AVREF  @BASEBOARD_FAB2_LIB.BASEBOARD_FAB2(SCH_1):VSENSE_PVDDQ_DEF_N
   33  VR_PVDDQ_DEF_XADDR2  XADDR2  @BASEBOARD_FAB2_LIB.BASEBOARD_FAB2(SCH_1):VR_PVDDQ_DEF_XADDR2
   36  VR_PVDDQ_DEF_XADDR1  XADDR1  @BASEBOARD_FAB2_LIB.BASEBOARD_FAB2(SCH_1):VR_PVDDQ_DEF_XADDR1
   10  VR_PVDDQ_DEF_VREN  AVREN  @BASEBOARD_FAB2_LIB.BASEBOARD_FAB2(SCH_1):VR_PVDDQ_DEF_VREN
   37  VR_PVDDQ_DEF_VINSEN  VINSEN  @BASEBOARD_FAB2_LIB.BASEBOARD_FAB2(SCH_1):VR_PVDDQ_DEF_VINSEN
   39  VR_PVDDQ_DEF_VDD    VDD  @BASEBOARD_FAB2_LIB.BASEBOARD_FAB2(SCH_1):VR_PVDDQ_DEF_VDD
   40  VR_PVDDQ_DEF_VD12   VD12  @BASEBOARD_FAB2_LIB.BASEBOARD_FAB2(SCH_1):VR_PVDDQ_DEF_VD12
    4  VR_PVDDQ_DEF_PWM2  APWM2  @BASEBOARD_FAB2_LIB.BASEBOARD_FAB2(SCH_1):VR_PVDDQ_DEF_PWM2
    5  VR_PVDDQ_DEF_PWM1  APWM1  @BASEBOARD_FAB2_LIB.BASEBOARD_FAB2(SCH_1):VR_PVDDQ_DEF_PWM1
   19  VR_PVDDQ_DEF_AVSP  AVSEN  @BASEBOARD_FAB2_LIB.BASEBOARD_FAB2(SCH_1):VR_PVDDQ_DEF_AVSP
   23  VR_PVDDQ_DEF_AIREF2  AIREF2  @BASEBOARD_FAB2_LIB.BASEBOARD_FAB2(SCH_1):VR_PVDDQ_DEF_AIREF2
   21  VR_PVDDQ_DEF_AIREF1  AIREF1  @BASEBOARD_FAB2_LIB.BASEBOARD_FAB2(SCH_1):VR_PVDDQ_DEF_AIREF1
   38  VR_PVDDQ_DEF_AIINSEN  IINSEN  @BASEBOARD_FAB2_LIB.BASEBOARD_FAB2(SCH_1):VR_PVDDQ_DEF_AIINSEN
    8  TP_PVDDQ_DEF_RESET_N  RESET_N  @BASEBOARD_FAB2_LIB.BASEBOARD_FAB2(SCH_1):TP_PVDDQ_DEF_RESET_N
    3  TP_PVDDQ_DEF_PWM3  APWM3  @BASEBOARD_FAB2_LIB.BASEBOARD_FAB2(SCH_1):TP_PVDDQ_DEF_PWM3
   12  TP_PVDDQ_DEF_PINALRT_N  PINALRT_N  @BASEBOARD_FAB2_LIB.BASEBOARD_FAB2(SCH_1):TP_PVDDQ_DEF_PINALRT_N
   25  TP_PVDDQ_DEF_PH3_IMON_REF  AIREF3  @BASEBOARD_FAB2_LIB.BASEBOARD_FAB2(SCH_1):TP_PVDDQ_DEF_PH3_IMON_REF
   26  TP_PVDDQ_DEF_PH3_IMON  AISEN3  @BASEBOARD_FAB2_LIB.BASEBOARD_FAB2(SCH_1):TP_PVDDQ_DEF_PH3_IMON
   18  TP_PVDDQ_DEF_MP2    MP2  @BASEBOARD_FAB2_LIB.BASEBOARD_FAB2(SCH_1):TP_PVDDQ_DEF_MP2
   14  TP_PVDDQ_DEF_MP1    MP1  @BASEBOARD_FAB2_LIB.BASEBOARD_FAB2(SCH_1):TP_PVDDQ_DEF_MP1
   29  TP_PVDDQ_DEF_BVSEN  BVSEN  @BASEBOARD_FAB2_LIB.BASEBOARD_FAB2(SCH_1):TP_PVDDQ_DEF_BVSEN
   30  TP_PVDDQ_DEF_BVREF  BVREF  @BASEBOARD_FAB2_LIB.BASEBOARD_FAB2(SCH_1):TP_PVDDQ_DEF_BVREF
   34  TP_PVDDQ_DEF_BTSEN  BTSEN  @BASEBOARD_FAB2_LIB.BASEBOARD_FAB2(SCH_1):TP_PVDDQ_DEF_BTSEN
   31  TP_PVDDQ_DEF_BREF1  BIREF1  @BASEBOARD_FAB2_LIB.BASEBOARD_FAB2(SCH_1):TP_PVDDQ_DEF_BREF1
    1  TP_PVDDQ_DEF_BPWM1  BPWM1  @BASEBOARD_FAB2_LIB.BASEBOARD_FAB2(SCH_1):TP_PVDDQ_DEF_BPWM1
   16  SVID_VDIO_PVDDQ_DEF   VDIO  @BASEBOARD_FAB2_LIB.BASEBOARD_FAB2(SCH_1):SVID_VDIO_PVDDQ_DEF
   15  SVID_CLK_PVDDQ_DEF   VCLK  @BASEBOARD_FAB2_LIB.BASEBOARD_FAB2(SCH_1):SVID_CLK_PVDDQ_DEF
   17  SVID_ALERT_PVDDQ_DEF  VALRT_N  @BASEBOARD_FAB2_LIB.BASEBOARD_FAB2(SCH_1):SVID_ALERT_PVDDQ_DEF
    6  SMB_VR_SDA_VDDQ_DEF    SDA  @BASEBOARD_FAB2_LIB.BASEBOARD_FAB2(SCH_1):SMB_VR_SDA_VDDQ_DEF
    7  SMB_VR_SCL_VDDQ_DEF    SCL  @BASEBOARD_FAB2_LIB.BASEBOARD_FAB2(SCH_1):SMB_VR_SCL_VDDQ_DEF
    9  PWRGD_PVDDQ_DEF_R  AVRRDY  @BASEBOARD_FAB2_LIB.BASEBOARD_FAB2(SCH_1):PWRGD_PVDDQ_DEF_R
   13  PU_VR_PVDDQ_DEF_FAULT1    MP0  @BASEBOARD_FAB2_LIB.BASEBOARD_FAB2(SCH_1):PU_VR_PVDDQ_DEF_FAULT1
   28  NC_PVDDQ_DEF_DNC1  DNC<1>  @BASEBOARD_FAB2_LIB.BASEBOARD_FAB2(SCH_1):NC_PVDDQ_DEF_DNC1
    2  NC_PVDDQ_DEF_DNC0  DNC<0>  @BASEBOARD_FAB2_LIB.BASEBOARD_FAB2(SCH_1):NC_PVDDQ_DEF_DNC0
   24  ISENSE_PVDDQ_DEF_PH2_IMON  AISEN2  @BASEBOARD_FAB2_LIB.BASEBOARD_FAB2(SCH_1):ISENSE_PVDDQ_DEF_PH2_IMON
   22  ISENSE_PVDDQ_DEF_PH1_IMON  AISEN1  @BASEBOARD_FAB2_LIB.BASEBOARD_FAB2(SCH_1):ISENSE_PVDDQ_DEF_PH1_IMON
   11  IRQ_PVDDQ_DEF_VRHOT_LVT3_R_N  VRHOT_N  @BASEBOARD_FAB2_LIB.BASEBOARD_FAB2(SCH_1):IRQ_PVDDQ_DEF_VRHOT_LVT3_R_N
   41  GND            THPAD  @BASEBOARD_FAB2_LIB.BASEBOARD_FAB2(SCH_1):GND
   27  GND              GND  @BASEBOARD_FAB2_LIB.BASEBOARD_FAB2(SCH_1):GND
   32  GND            BISEN1  @BASEBOARD_FAB2_LIB.BASEBOARD_FAB2(SCH_1):GND
   35  A_TSENSE_PVDDQ_DEF  ATSEN  @BASEBOARD_FAB2_LIB.BASEBOARD_FAB2(SCH_1):A_TSENSE_PVDDQ_DEF

NCP3232L_SM  I214  EU7B1  [NCP3232L_SM-IC,H86355-001]
   38  VR_VB_PVPP_DEF     VB  @BASEBOARD_FAB2_LIB.BASEBOARD_FAB2(SCH_1):VR_VB_PVPP_DEF
    1  VR_PVPP_DEF_SS     SS  @BASEBOARD_FAB2_LIB.BASEBOARD_FAB2(SCH_1):VR_PVPP_DEF_SS
   43  VR_PVPP_DEF_PHASE  VSWH<7>  @BASEBOARD_FAB2_LIB.BASEBOARD_FAB2(SCH_1):VR_PVPP_DEF_PHASE
   34  VR_PVPP_DEF_PHASE  VSWH<6>  @BASEBOARD_FAB2_LIB.BASEBOARD_FAB2(SCH_1):VR_PVPP_DEF_PHASE
   33  VR_PVPP_DEF_PHASE  VSWH<5>  @BASEBOARD_FAB2_LIB.BASEBOARD_FAB2(SCH_1):VR_PVPP_DEF_PHASE
   32  VR_PVPP_DEF_PHASE  VSWH<4>  @BASEBOARD_FAB2_LIB.BASEBOARD_FAB2(SCH_1):VR_PVPP_DEF_PHASE
   31  VR_PVPP_DEF_PHASE  VSWH<3>  @BASEBOARD_FAB2_LIB.BASEBOARD_FAB2(SCH_1):VR_PVPP_DEF_PHASE
   30  VR_PVPP_DEF_PHASE  VSWH<2>  @BASEBOARD_FAB2_LIB.BASEBOARD_FAB2(SCH_1):VR_PVPP_DEF_PHASE
   29  VR_PVPP_DEF_PHASE  VSWH<1>  @BASEBOARD_FAB2_LIB.BASEBOARD_FAB2(SCH_1):VR_PVPP_DEF_PHASE
   15  VR_PVPP_DEF_PHASE  VSWH<0>  @BASEBOARD_FAB2_LIB.BASEBOARD_FAB2(SCH_1):VR_PVPP_DEF_PHASE
   35  VR_PVPP_DEF_PHASE    VSW  @BASEBOARD_FAB2_LIB.BASEBOARD_FAB2(SCH_1):VR_PVPP_DEF_PHASE
    4  VR_PVPP_DEF_ISET   ISET  @BASEBOARD_FAB2_LIB.BASEBOARD_FAB2(SCH_1):VR_PVPP_DEF_ISET
   36  VR_PVPP_DEF_BOOT    BST  @BASEBOARD_FAB2_LIB.BASEBOARD_FAB2(SCH_1):VR_PVPP_DEF_BOOT
   42  VR_FET_SW_P12V_STBY_PVPP_DEF  VIN<7>  @BASEBOARD_FAB2_LIB.BASEBOARD_FAB2(SCH_1):VR_FET_SW_P12V_STBY_PVPP_DEF
   14  VR_FET_SW_P12V_STBY_PVPP_DEF  VIN<6>  @BASEBOARD_FAB2_LIB.BASEBOARD_FAB2(SCH_1):VR_FET_SW_P12V_STBY_PVPP_DEF
   13  VR_FET_SW_P12V_STBY_PVPP_DEF  VIN<5>  @BASEBOARD_FAB2_LIB.BASEBOARD_FAB2(SCH_1):VR_FET_SW_P12V_STBY_PVPP_DEF
   12  VR_FET_SW_P12V_STBY_PVPP_DEF  VIN<4>  @BASEBOARD_FAB2_LIB.BASEBOARD_FAB2(SCH_1):VR_FET_SW_P12V_STBY_PVPP_DEF
   11  VR_FET_SW_P12V_STBY_PVPP_DEF  VIN<3>  @BASEBOARD_FAB2_LIB.BASEBOARD_FAB2(SCH_1):VR_FET_SW_P12V_STBY_PVPP_DEF
   10  VR_FET_SW_P12V_STBY_PVPP_DEF  VIN<2>  @BASEBOARD_FAB2_LIB.BASEBOARD_FAB2(SCH_1):VR_FET_SW_P12V_STBY_PVPP_DEF
    9  VR_FET_SW_P12V_STBY_PVPP_DEF  VIN<1>  @BASEBOARD_FAB2_LIB.BASEBOARD_FAB2(SCH_1):VR_FET_SW_P12V_STBY_PVPP_DEF
    8  VR_FET_SW_P12V_STBY_PVPP_DEF  VIN<0>  @BASEBOARD_FAB2_LIB.BASEBOARD_FAB2(SCH_1):VR_FET_SW_P12V_STBY_PVPP_DEF
   39  VR_FET_SW_P12V_STBY_PVPP_DEF    VCC  @BASEBOARD_FAB2_LIB.BASEBOARD_FAB2(SCH_1):VR_FET_SW_P12V_STBY_PVPP_DEF
    2  VR_FB_PVPP_DEF     FB  @BASEBOARD_FAB2_LIB.BASEBOARD_FAB2(SCH_1):VR_FB_PVPP_DEF
    3  VR_COMP_PVPP_DEF_3   COMP  @BASEBOARD_FAB2_LIB.BASEBOARD_FAB2(SCH_1):VR_COMP_PVPP_DEF_3
    7  PWRGD_PVPP_DEF_R     PG  @BASEBOARD_FAB2_LIB.BASEBOARD_FAB2(SCH_1):PWRGD_PVPP_DEF_R
   37  GND            PGND<13>  @BASEBOARD_FAB2_LIB.BASEBOARD_FAB2(SCH_1):GND
   28  GND            PGND<12>  @BASEBOARD_FAB2_LIB.BASEBOARD_FAB2(SCH_1):GND
   27  GND            PGND<11>  @BASEBOARD_FAB2_LIB.BASEBOARD_FAB2(SCH_1):GND
   26  GND            PGND<10>  @BASEBOARD_FAB2_LIB.BASEBOARD_FAB2(SCH_1):GND
   25  GND            PGND<9>  @BASEBOARD_FAB2_LIB.BASEBOARD_FAB2(SCH_1):GND
   24  GND            PGND<8>  @BASEBOARD_FAB2_LIB.BASEBOARD_FAB2(SCH_1):GND
   23  GND            PGND<7>  @BASEBOARD_FAB2_LIB.BASEBOARD_FAB2(SCH_1):GND
   22  GND            PGND<6>  @BASEBOARD_FAB2_LIB.BASEBOARD_FAB2(SCH_1):GND
   21  GND            PGND<5>  @BASEBOARD_FAB2_LIB.BASEBOARD_FAB2(SCH_1):GND
   20  GND            PGND<4>  @BASEBOARD_FAB2_LIB.BASEBOARD_FAB2(SCH_1):GND
   19  GND            PGND<3>  @BASEBOARD_FAB2_LIB.BASEBOARD_FAB2(SCH_1):GND
   18  GND            PGND<2>  @BASEBOARD_FAB2_LIB.BASEBOARD_FAB2(SCH_1):GND
   17  GND            PGND<1>  @BASEBOARD_FAB2_LIB.BASEBOARD_FAB2(SCH_1):GND
   16  GND            PGND<0>  @BASEBOARD_FAB2_LIB.BASEBOARD_FAB2(SCH_1):GND
   41  GND              GND  @BASEBOARD_FAB2_LIB.BASEBOARD_FAB2(SCH_1):GND
   40  FM_PVPP_PVDDQ_CPU0_EN_DEF     EN  @BASEBOARD_FAB2_LIB.BASEBOARD_FAB2(SCH_1):FM_PVPP_PVDDQ_CPU0_EN_DEF
    6  AGND_PVPP_DEF    OTS  @BASEBOARD_FAB2_LIB.BASEBOARD_FAB2(SCH_1):AGND_PVPP_DEF
    5  AGND_PVPP_DEF   AGND  @BASEBOARD_FAB2_LIB.BASEBOARD_FAB2(SCH_1):AGND_PVPP_DEF

IR354XX_SM  I101  EU7C1  [IR354XX_SM-IR35412,IC,H73684-0A]
   34  VR_PVCCIO_CPU0_PWM1    PWM  @BASEBOARD_FAB2_LIB.BASEBOARD_FAB2(SCH_1):VR_PVCCIO_CPU0_PWM1
    3  VR_PVCCIO_CPU0_PH1_VCIN    VCC  @BASEBOARD_FAB2_LIB.BASEBOARD_FAB2(SCH_1):VR_PVCCIO_CPU0_PH1_VCIN
   10  VR_PVCCIO_CPU0_PH1_SW     SW  @BASEBOARD_FAB2_LIB.BASEBOARD_FAB2(SCH_1):VR_PVCCIO_CPU0_PH1_SW
   32  VR_PVCCIO_CPU0_PH1_PHASE  PHASE  @BASEBOARD_FAB2_LIB.BASEBOARD_FAB2(SCH_1):VR_PVCCIO_CPU0_PH1_PHASE
   33  VR_PVCCIO_CPU0_PH1_BOOT_R  BOOST  @BASEBOARD_FAB2_LIB.BASEBOARD_FAB2(SCH_1):VR_PVCCIO_CPU0_PH1_BOOT_R
   37  VR_PVCCIO_CPU0_OCSET  OCSET  @BASEBOARD_FAB2_LIB.BASEBOARD_FAB2(SCH_1):VR_PVCCIO_CPU0_OCSET
   39  VR_PVCCIO_CPU0_AIREF1  REFIN  @BASEBOARD_FAB2_LIB.BASEBOARD_FAB2(SCH_1):VR_PVCCIO_CPU0_AIREF1
   30  VR_FET_SW_P12V_STBY_PVCCIO_CPU0  VIN<1>  @BASEBOARD_FAB2_LIB.BASEBOARD_FAB2(SCH_1):VR_FET_SW_P12V_STBY_PVCCIO_CPU0
   25  VR_FET_SW_P12V_STBY_PVCCIO_CPU0  VIN<0>  @BASEBOARD_FAB2_LIB.BASEBOARD_FAB2(SCH_1):VR_FET_SW_P12V_STBY_PVCCIO_CPU0
   41  TP_PVCCIO_CPU0_GL_1  GL<1>  @BASEBOARD_FAB2_LIB.BASEBOARD_FAB2(SCH_1):TP_PVCCIO_CPU0_GL_1
    6  TP_PVCCIO_CPU0_GL_0  GL<0>  @BASEBOARD_FAB2_LIB.BASEBOARD_FAB2(SCH_1):TP_PVCCIO_CPU0_GL_0
    1  PVCCIO_CPU0      VOS  @BASEBOARD_FAB2_LIB.BASEBOARD_FAB2(SCH_1):PVCCIO_CPU0
    4  P5V_STBY        VDRV  @BASEBOARD_FAB2_LIB.BASEBOARD_FAB2(SCH_1):P5V_STBY
   35  P5V_STBY          EN  @BASEBOARD_FAB2_LIB.BASEBOARD_FAB2(SCH_1):P5V_STBY
   31  NC_PVCCIO_CPU0_PH1_P31     NC  @BASEBOARD_FAB2_LIB.BASEBOARD_FAB2(SCH_1):NC_PVCCIO_CPU0_PH1_P31
   38  ISENSE_PVCCIO_CPU0_PH1_IMON   IOUT  @BASEBOARD_FAB2_LIB.BASEBOARD_FAB2(SCH_1):ISENSE_PVCCIO_CPU0_PH1_IMON
   40  GND            PGND<2>  @BASEBOARD_FAB2_LIB.BASEBOARD_FAB2(SCH_1):GND
    7  GND            PGND<1>  @BASEBOARD_FAB2_LIB.BASEBOARD_FAB2(SCH_1):GND
    5  GND            PGND<0>  @BASEBOARD_FAB2_LIB.BASEBOARD_FAB2(SCH_1):GND
    2  GND             LGND  @BASEBOARD_FAB2_LIB.BASEBOARD_FAB2(SCH_1):GND
   36  A_TSENSE_PVCCIO_CPU0  TOUT_FLT  @BASEBOARD_FAB2_LIB.BASEBOARD_FAB2(SCH_1):A_TSENSE_PVCCIO_CPU0

SLG55021_SM  I19  EU7E1  [SLG55021_SM-IC,G56246-001]
    8  TP_SLG55021_P12V_MAIN_8     PG  @BASEBOARD_FAB2_LIB.BASEBOARD_FAB2(SCH_1):TP_SLG55021_P12V_MAIN_8
    1  P5V_STBY         VCC  @BASEBOARD_FAB2_LIB.BASEBOARD_FAB2(SCH_1):P5V_STBY
    3  P5V_STBY       SHDN_N  @BASEBOARD_FAB2_LIB.BASEBOARD_FAB2(SCH_1):P5V_STBY
    7  P12V_SWITCH_G      G  @BASEBOARD_FAB2_LIB.BASEBOARD_FAB2(SCH_1):P12V_SWITCH_G
    5  P12V_STBY          D  @BASEBOARD_FAB2_LIB.BASEBOARD_FAB2(SCH_1):P12V_STBY
    6  P12V               S  @BASEBOARD_FAB2_LIB.BASEBOARD_FAB2(SCH_1):P12V
    9  GND            THPAD  @BASEBOARD_FAB2_LIB.BASEBOARD_FAB2(SCH_1):GND
    4  GND              GND  @BASEBOARD_FAB2_LIB.BASEBOARD_FAB2(SCH_1):GND
    2  FM_P12V_MAIN_SW_EN     ON  @BASEBOARD_FAB2_LIB.BASEBOARD_FAB2(SCH_1):FM_P12V_MAIN_SW_EN

TPS54821_LCC  I83  EU7E2  [TPS54821_LCC-IC,H63269-001]
    7  VR_P5V_STBY_VSENSE  VSENSE  @BASEBOARD_FAB2_LIB.BASEBOARD_FAB2(SCH_1):VR_P5V_STBY_VSENSE
    6  VR_P5V_STBY_VIN    VIN  @BASEBOARD_FAB2_LIB.BASEBOARD_FAB2(SCH_1):VR_P5V_STBY_VIN
    9  VR_P5V_STBY_SS  SS_TR  @BASEBOARD_FAB2_LIB.BASEBOARD_FAB2(SCH_1):VR_P5V_STBY_SS
    1  VR_P5V_STBY_RT  RT_CLK  @BASEBOARD_FAB2_LIB.BASEBOARD_FAB2(SCH_1):VR_P5V_STBY_RT
   12  VR_P5V_STBY_PHASE  PH<1>  @BASEBOARD_FAB2_LIB.BASEBOARD_FAB2(SCH_1):VR_P5V_STBY_PHASE
   11  VR_P5V_STBY_PHASE  PH<0>  @BASEBOARD_FAB2_LIB.BASEBOARD_FAB2(SCH_1):VR_P5V_STBY_PHASE
   10  VR_P5V_STBY_EN     EN  @BASEBOARD_FAB2_LIB.BASEBOARD_FAB2(SCH_1):VR_P5V_STBY_EN
    8  VR_P5V_STBY_COMP   COMP  @BASEBOARD_FAB2_LIB.BASEBOARD_FAB2(SCH_1):VR_P5V_STBY_COMP
   13  VR_P5V_STBY_BOOT   BOOT  @BASEBOARD_FAB2_LIB.BASEBOARD_FAB2(SCH_1):VR_P5V_STBY_BOOT
    5  VR_FET_SW_P5V_STBY_PVIN  PVIN<1>  @BASEBOARD_FAB2_LIB.BASEBOARD_FAB2(SCH_1):VR_FET_SW_P5V_STBY_PVIN
    4  VR_FET_SW_P5V_STBY_PVIN  PVIN<0>  @BASEBOARD_FAB2_LIB.BASEBOARD_FAB2(SCH_1):VR_FET_SW_P5V_STBY_PVIN
   14  PWRGD_P5V_STBY_R  PWRGD  @BASEBOARD_FAB2_LIB.BASEBOARD_FAB2(SCH_1):PWRGD_P5V_STBY_R
   15  GND            THPAD  @BASEBOARD_FAB2_LIB.BASEBOARD_FAB2(SCH_1):GND
    3  GND            GND<1>  @BASEBOARD_FAB2_LIB.BASEBOARD_FAB2(SCH_1):GND
    2  GND            GND<0>  @BASEBOARD_FAB2_LIB.BASEBOARD_FAB2(SCH_1):GND

NCP3232L_SM  I193  EU7F1  [NCP3232L_SM-IC,H86355-001]
   38  VR_VB_PVPP_ABC     VB  @BASEBOARD_FAB2_LIB.BASEBOARD_FAB2(SCH_1):VR_VB_PVPP_ABC
    1  VR_PVPP_ABC_SS     SS  @BASEBOARD_FAB2_LIB.BASEBOARD_FAB2(SCH_1):VR_PVPP_ABC_SS
   43  VR_PVPP_ABC_PHASE  VSWH<7>  @BASEBOARD_FAB2_LIB.BASEBOARD_FAB2(SCH_1):VR_PVPP_ABC_PHASE
   34  VR_PVPP_ABC_PHASE  VSWH<6>  @BASEBOARD_FAB2_LIB.BASEBOARD_FAB2(SCH_1):VR_PVPP_ABC_PHASE
   33  VR_PVPP_ABC_PHASE  VSWH<5>  @BASEBOARD_FAB2_LIB.BASEBOARD_FAB2(SCH_1):VR_PVPP_ABC_PHASE
   32  VR_PVPP_ABC_PHASE  VSWH<4>  @BASEBOARD_FAB2_LIB.BASEBOARD_FAB2(SCH_1):VR_PVPP_ABC_PHASE
   31  VR_PVPP_ABC_PHASE  VSWH<3>  @BASEBOARD_FAB2_LIB.BASEBOARD_FAB2(SCH_1):VR_PVPP_ABC_PHASE
   30  VR_PVPP_ABC_PHASE  VSWH<2>  @BASEBOARD_FAB2_LIB.BASEBOARD_FAB2(SCH_1):VR_PVPP_ABC_PHASE
   29  VR_PVPP_ABC_PHASE  VSWH<1>  @BASEBOARD_FAB2_LIB.BASEBOARD_FAB2(SCH_1):VR_PVPP_ABC_PHASE
   15  VR_PVPP_ABC_PHASE  VSWH<0>  @BASEBOARD_FAB2_LIB.BASEBOARD_FAB2(SCH_1):VR_PVPP_ABC_PHASE
   35  VR_PVPP_ABC_PHASE    VSW  @BASEBOARD_FAB2_LIB.BASEBOARD_FAB2(SCH_1):VR_PVPP_ABC_PHASE
    4  VR_PVPP_ABC_ISET   ISET  @BASEBOARD_FAB2_LIB.BASEBOARD_FAB2(SCH_1):VR_PVPP_ABC_ISET
   36  VR_PVPP_ABC_BOOT    BST  @BASEBOARD_FAB2_LIB.BASEBOARD_FAB2(SCH_1):VR_PVPP_ABC_BOOT
   42  VR_FET_SW_P12V_STBY_PVPP_ABC  VIN<7>  @BASEBOARD_FAB2_LIB.BASEBOARD_FAB2(SCH_1):VR_FET_SW_P12V_STBY_PVPP_ABC
   14  VR_FET_SW_P12V_STBY_PVPP_ABC  VIN<6>  @BASEBOARD_FAB2_LIB.BASEBOARD_FAB2(SCH_1):VR_FET_SW_P12V_STBY_PVPP_ABC
   13  VR_FET_SW_P12V_STBY_PVPP_ABC  VIN<5>  @BASEBOARD_FAB2_LIB.BASEBOARD_FAB2(SCH_1):VR_FET_SW_P12V_STBY_PVPP_ABC
   12  VR_FET_SW_P12V_STBY_PVPP_ABC  VIN<4>  @BASEBOARD_FAB2_LIB.BASEBOARD_FAB2(SCH_1):VR_FET_SW_P12V_STBY_PVPP_ABC
   11  VR_FET_SW_P12V_STBY_PVPP_ABC  VIN<3>  @BASEBOARD_FAB2_LIB.BASEBOARD_FAB2(SCH_1):VR_FET_SW_P12V_STBY_PVPP_ABC
   10  VR_FET_SW_P12V_STBY_PVPP_ABC  VIN<2>  @BASEBOARD_FAB2_LIB.BASEBOARD_FAB2(SCH_1):VR_FET_SW_P12V_STBY_PVPP_ABC
    9  VR_FET_SW_P12V_STBY_PVPP_ABC  VIN<1>  @BASEBOARD_FAB2_LIB.BASEBOARD_FAB2(SCH_1):VR_FET_SW_P12V_STBY_PVPP_ABC
    8  VR_FET_SW_P12V_STBY_PVPP_ABC  VIN<0>  @BASEBOARD_FAB2_LIB.BASEBOARD_FAB2(SCH_1):VR_FET_SW_P12V_STBY_PVPP_ABC
   39  VR_FET_SW_P12V_STBY_PVPP_ABC    VCC  @BASEBOARD_FAB2_LIB.BASEBOARD_FAB2(SCH_1):VR_FET_SW_P12V_STBY_PVPP_ABC
    2  VR_FB_PVPP_ABC     FB  @BASEBOARD_FAB2_LIB.BASEBOARD_FAB2(SCH_1):VR_FB_PVPP_ABC
    3  VR_COMP_PVPP_ABC_3   COMP  @BASEBOARD_FAB2_LIB.BASEBOARD_FAB2(SCH_1):VR_COMP_PVPP_ABC_3
    7  PWRGD_PVPP_ABC_R     PG  @BASEBOARD_FAB2_LIB.BASEBOARD_FAB2(SCH_1):PWRGD_PVPP_ABC_R
   37  GND            PGND<13>  @BASEBOARD_FAB2_LIB.BASEBOARD_FAB2(SCH_1):GND
   28  GND            PGND<12>  @BASEBOARD_FAB2_LIB.BASEBOARD_FAB2(SCH_1):GND
   27  GND            PGND<11>  @BASEBOARD_FAB2_LIB.BASEBOARD_FAB2(SCH_1):GND
   26  GND            PGND<10>  @BASEBOARD_FAB2_LIB.BASEBOARD_FAB2(SCH_1):GND
   25  GND            PGND<9>  @BASEBOARD_FAB2_LIB.BASEBOARD_FAB2(SCH_1):GND
   24  GND            PGND<8>  @BASEBOARD_FAB2_LIB.BASEBOARD_FAB2(SCH_1):GND
   23  GND            PGND<7>  @BASEBOARD_FAB2_LIB.BASEBOARD_FAB2(SCH_1):GND
   22  GND            PGND<6>  @BASEBOARD_FAB2_LIB.BASEBOARD_FAB2(SCH_1):GND
   21  GND            PGND<5>  @BASEBOARD_FAB2_LIB.BASEBOARD_FAB2(SCH_1):GND
   20  GND            PGND<4>  @BASEBOARD_FAB2_LIB.BASEBOARD_FAB2(SCH_1):GND
   19  GND            PGND<3>  @BASEBOARD_FAB2_LIB.BASEBOARD_FAB2(SCH_1):GND
   18  GND            PGND<2>  @BASEBOARD_FAB2_LIB.BASEBOARD_FAB2(SCH_1):GND
   17  GND            PGND<1>  @BASEBOARD_FAB2_LIB.BASEBOARD_FAB2(SCH_1):GND
   16  GND            PGND<0>  @BASEBOARD_FAB2_LIB.BASEBOARD_FAB2(SCH_1):GND
   41  GND              GND  @BASEBOARD_FAB2_LIB.BASEBOARD_FAB2(SCH_1):GND
   40  FM_PVPP_PVDDQ_CPU0_EN_ABC     EN  @BASEBOARD_FAB2_LIB.BASEBOARD_FAB2(SCH_1):FM_PVPP_PVDDQ_CPU0_EN_ABC
    6  AGND_PVPP_ABC    OTS  @BASEBOARD_FAB2_LIB.BASEBOARD_FAB2(SCH_1):AGND_PVPP_ABC
    5  AGND_PVPP_ABC   AGND  @BASEBOARD_FAB2_LIB.BASEBOARD_FAB2(SCH_1):AGND_PVPP_ABC

PXM1310B_QFN  I358  EU7G1  [PXM1310B_QFN-IC,H89186-001]
   20  VSENSE_PVDDQ_ABC_N  AVREF  @BASEBOARD_FAB2_LIB.BASEBOARD_FAB2(SCH_1):VSENSE_PVDDQ_ABC_N
   33  VR_PVDDQ_ABC_XADDR2  XADDR2  @BASEBOARD_FAB2_LIB.BASEBOARD_FAB2(SCH_1):VR_PVDDQ_ABC_XADDR2
   36  VR_PVDDQ_ABC_XADDR1  XADDR1  @BASEBOARD_FAB2_LIB.BASEBOARD_FAB2(SCH_1):VR_PVDDQ_ABC_XADDR1
   10  VR_PVDDQ_ABC_VREN  AVREN  @BASEBOARD_FAB2_LIB.BASEBOARD_FAB2(SCH_1):VR_PVDDQ_ABC_VREN
   37  VR_PVDDQ_ABC_VINSEN  VINSEN  @BASEBOARD_FAB2_LIB.BASEBOARD_FAB2(SCH_1):VR_PVDDQ_ABC_VINSEN
   39  VR_PVDDQ_ABC_VDD    VDD  @BASEBOARD_FAB2_LIB.BASEBOARD_FAB2(SCH_1):VR_PVDDQ_ABC_VDD
   40  VR_PVDDQ_ABC_VD12   VD12  @BASEBOARD_FAB2_LIB.BASEBOARD_FAB2(SCH_1):VR_PVDDQ_ABC_VD12
    4  VR_PVDDQ_ABC_PWM2  APWM2  @BASEBOARD_FAB2_LIB.BASEBOARD_FAB2(SCH_1):VR_PVDDQ_ABC_PWM2
    5  VR_PVDDQ_ABC_PWM1  APWM1  @BASEBOARD_FAB2_LIB.BASEBOARD_FAB2(SCH_1):VR_PVDDQ_ABC_PWM1
   19  VR_PVDDQ_ABC_AVSP  AVSEN  @BASEBOARD_FAB2_LIB.BASEBOARD_FAB2(SCH_1):VR_PVDDQ_ABC_AVSP
   23  VR_PVDDQ_ABC_AIREF2  AIREF2  @BASEBOARD_FAB2_LIB.BASEBOARD_FAB2(SCH_1):VR_PVDDQ_ABC_AIREF2
   21  VR_PVDDQ_ABC_AIREF1  AIREF1  @BASEBOARD_FAB2_LIB.BASEBOARD_FAB2(SCH_1):VR_PVDDQ_ABC_AIREF1
   38  VR_PVDDQ_ABC_AIINSEN  IINSEN  @BASEBOARD_FAB2_LIB.BASEBOARD_FAB2(SCH_1):VR_PVDDQ_ABC_AIINSEN
    8  TP_PVDDQ_ABC_RESET_N  RESET_N  @BASEBOARD_FAB2_LIB.BASEBOARD_FAB2(SCH_1):TP_PVDDQ_ABC_RESET_N
    3  TP_PVDDQ_ABC_PWM3  APWM3  @BASEBOARD_FAB2_LIB.BASEBOARD_FAB2(SCH_1):TP_PVDDQ_ABC_PWM3
   12  TP_PVDDQ_ABC_PINALRT_N  PINALRT_N  @BASEBOARD_FAB2_LIB.BASEBOARD_FAB2(SCH_1):TP_PVDDQ_ABC_PINALRT_N
   25  TP_PVDDQ_ABC_PH3_IMON_REF  AIREF3  @BASEBOARD_FAB2_LIB.BASEBOARD_FAB2(SCH_1):TP_PVDDQ_ABC_PH3_IMON_REF
   26  TP_PVDDQ_ABC_PH3_IMON  AISEN3  @BASEBOARD_FAB2_LIB.BASEBOARD_FAB2(SCH_1):TP_PVDDQ_ABC_PH3_IMON
   18  TP_PVDDQ_ABC_MP2    MP2  @BASEBOARD_FAB2_LIB.BASEBOARD_FAB2(SCH_1):TP_PVDDQ_ABC_MP2
   14  TP_PVDDQ_ABC_MP1    MP1  @BASEBOARD_FAB2_LIB.BASEBOARD_FAB2(SCH_1):TP_PVDDQ_ABC_MP1
   29  TP_PVDDQ_ABC_BVSEN  BVSEN  @BASEBOARD_FAB2_LIB.BASEBOARD_FAB2(SCH_1):TP_PVDDQ_ABC_BVSEN
   30  TP_PVDDQ_ABC_BVREF  BVREF  @BASEBOARD_FAB2_LIB.BASEBOARD_FAB2(SCH_1):TP_PVDDQ_ABC_BVREF
   34  TP_PVDDQ_ABC_BTSEN  BTSEN  @BASEBOARD_FAB2_LIB.BASEBOARD_FAB2(SCH_1):TP_PVDDQ_ABC_BTSEN
   31  TP_PVDDQ_ABC_BREF1  BIREF1  @BASEBOARD_FAB2_LIB.BASEBOARD_FAB2(SCH_1):TP_PVDDQ_ABC_BREF1
    1  TP_PVDDQ_ABC_BPWM1  BPWM1  @BASEBOARD_FAB2_LIB.BASEBOARD_FAB2(SCH_1):TP_PVDDQ_ABC_BPWM1
   16  SVID_VDIO_PVDDQ_ABC   VDIO  @BASEBOARD_FAB2_LIB.BASEBOARD_FAB2(SCH_1):SVID_VDIO_PVDDQ_ABC
   15  SVID_CLK_PVDDQ_ABC   VCLK  @BASEBOARD_FAB2_LIB.BASEBOARD_FAB2(SCH_1):SVID_CLK_PVDDQ_ABC
   17  SVID_ALERT_PVDDQ_ABC  VALRT_N  @BASEBOARD_FAB2_LIB.BASEBOARD_FAB2(SCH_1):SVID_ALERT_PVDDQ_ABC
    6  SMB_VR_SDA_VDDQ_ABC    SDA  @BASEBOARD_FAB2_LIB.BASEBOARD_FAB2(SCH_1):SMB_VR_SDA_VDDQ_ABC
    7  SMB_VR_SCL_VDDQ_ABC    SCL  @BASEBOARD_FAB2_LIB.BASEBOARD_FAB2(SCH_1):SMB_VR_SCL_VDDQ_ABC
    9  PWRGD_PVDDQ_ABC_R  AVRRDY  @BASEBOARD_FAB2_LIB.BASEBOARD_FAB2(SCH_1):PWRGD_PVDDQ_ABC_R
   13  PU_VR_PVDDQ_ABC_FAULT1    MP0  @BASEBOARD_FAB2_LIB.BASEBOARD_FAB2(SCH_1):PU_VR_PVDDQ_ABC_FAULT1
   28  NC_PVDDQ_ABC_DNC1  DNC<1>  @BASEBOARD_FAB2_LIB.BASEBOARD_FAB2(SCH_1):NC_PVDDQ_ABC_DNC1
    2  NC_PVDDQ_ABC_DNC0  DNC<0>  @BASEBOARD_FAB2_LIB.BASEBOARD_FAB2(SCH_1):NC_PVDDQ_ABC_DNC0
   24  ISENSE_PVDDQ_ABC_PH2_IMON  AISEN2  @BASEBOARD_FAB2_LIB.BASEBOARD_FAB2(SCH_1):ISENSE_PVDDQ_ABC_PH2_IMON
   22  ISENSE_PVDDQ_ABC_PH1_IMON  AISEN1  @BASEBOARD_FAB2_LIB.BASEBOARD_FAB2(SCH_1):ISENSE_PVDDQ_ABC_PH1_IMON
   11  IRQ_PVDDQ_ABC_VRHOT_LVT3_R_N  VRHOT_N  @BASEBOARD_FAB2_LIB.BASEBOARD_FAB2(SCH_1):IRQ_PVDDQ_ABC_VRHOT_LVT3_R_N
   41  GND            THPAD  @BASEBOARD_FAB2_LIB.BASEBOARD_FAB2(SCH_1):GND
   27  GND              GND  @BASEBOARD_FAB2_LIB.BASEBOARD_FAB2(SCH_1):GND
   32  GND            BISEN1  @BASEBOARD_FAB2_LIB.BASEBOARD_FAB2(SCH_1):GND
   35  A_TSENSE_PVDDQ_ABC  ATSEN  @BASEBOARD_FAB2_LIB.BASEBOARD_FAB2(SCH_1):A_TSENSE_PVDDQ_ABC

IR354XX_SM  I102  EU7G2  [IR354XX_SM-IR35411,IC,H73688-0A]
   34  VR_PVDDQ_ABC_PWM1    PWM  @BASEBOARD_FAB2_LIB.BASEBOARD_FAB2(SCH_1):VR_PVDDQ_ABC_PWM1
    3  VR_PVDDQ_ABC_PH1_VCIN    VCC  @BASEBOARD_FAB2_LIB.BASEBOARD_FAB2(SCH_1):VR_PVDDQ_ABC_PH1_VCIN
   10  VR_PVDDQ_ABC_PH1_SW     SW  @BASEBOARD_FAB2_LIB.BASEBOARD_FAB2(SCH_1):VR_PVDDQ_ABC_PH1_SW
   32  VR_PVDDQ_ABC_PH1_PHASE  PHASE  @BASEBOARD_FAB2_LIB.BASEBOARD_FAB2(SCH_1):VR_PVDDQ_ABC_PH1_PHASE
   37  VR_PVDDQ_ABC_PH1_OCSET  OCSET  @BASEBOARD_FAB2_LIB.BASEBOARD_FAB2(SCH_1):VR_PVDDQ_ABC_PH1_OCSET
   33  VR_PVDDQ_ABC_PH1_BOOT_R  BOOST  @BASEBOARD_FAB2_LIB.BASEBOARD_FAB2(SCH_1):VR_PVDDQ_ABC_PH1_BOOT_R
   39  VR_PVDDQ_ABC_AIREF1  REFIN  @BASEBOARD_FAB2_LIB.BASEBOARD_FAB2(SCH_1):VR_PVDDQ_ABC_AIREF1
   30  VR_FET_SW_P12V_STBY_PVDDQ_ABC  VIN<1>  @BASEBOARD_FAB2_LIB.BASEBOARD_FAB2(SCH_1):VR_FET_SW_P12V_STBY_PVDDQ_ABC
   25  VR_FET_SW_P12V_STBY_PVDDQ_ABC  VIN<0>  @BASEBOARD_FAB2_LIB.BASEBOARD_FAB2(SCH_1):VR_FET_SW_P12V_STBY_PVDDQ_ABC
   41  TP_PVDDQ_ABC_PH1_GL_1  GL<1>  @BASEBOARD_FAB2_LIB.BASEBOARD_FAB2(SCH_1):TP_PVDDQ_ABC_PH1_GL_1
    6  TP_PVDDQ_ABC_PH1_GL_0  GL<0>  @BASEBOARD_FAB2_LIB.BASEBOARD_FAB2(SCH_1):TP_PVDDQ_ABC_PH1_GL_0
    1  PVDDQ_ABC        VOS  @BASEBOARD_FAB2_LIB.BASEBOARD_FAB2(SCH_1):PVDDQ_ABC
    4  P5V_STBY        VDRV  @BASEBOARD_FAB2_LIB.BASEBOARD_FAB2(SCH_1):P5V_STBY
   35  P5V_STBY          EN  @BASEBOARD_FAB2_LIB.BASEBOARD_FAB2(SCH_1):P5V_STBY
   31  NC_PVDDQ_ABC_PH1_P31     NC  @BASEBOARD_FAB2_LIB.BASEBOARD_FAB2(SCH_1):NC_PVDDQ_ABC_PH1_P31
   38  ISENSE_PVDDQ_ABC_PH1_IMON   IOUT  @BASEBOARD_FAB2_LIB.BASEBOARD_FAB2(SCH_1):ISENSE_PVDDQ_ABC_PH1_IMON
   40  GND            PGND<2>  @BASEBOARD_FAB2_LIB.BASEBOARD_FAB2(SCH_1):GND
    7  GND            PGND<1>  @BASEBOARD_FAB2_LIB.BASEBOARD_FAB2(SCH_1):GND
    5  GND            PGND<0>  @BASEBOARD_FAB2_LIB.BASEBOARD_FAB2(SCH_1):GND
    2  GND             LGND  @BASEBOARD_FAB2_LIB.BASEBOARD_FAB2(SCH_1):GND
   36  A_TSENSE_PVDDQ_ABC  TOUT_FLT  @BASEBOARD_FAB2_LIB.BASEBOARD_FAB2(SCH_1):A_TSENSE_PVDDQ_ABC

IR354XX_SM  I103  EU7G3  [IR354XX_SM-IR35411,IC,H73688-0A]
   34  VR_PVDDQ_ABC_PWM2    PWM  @BASEBOARD_FAB2_LIB.BASEBOARD_FAB2(SCH_1):VR_PVDDQ_ABC_PWM2
    3  VR_PVDDQ_ABC_PH2_VCIN    VCC  @BASEBOARD_FAB2_LIB.BASEBOARD_FAB2(SCH_1):VR_PVDDQ_ABC_PH2_VCIN
   10  VR_PVDDQ_ABC_PH2_SW     SW  @BASEBOARD_FAB2_LIB.BASEBOARD_FAB2(SCH_1):VR_PVDDQ_ABC_PH2_SW
   32  VR_PVDDQ_ABC_PH2_PHASE  PHASE  @BASEBOARD_FAB2_LIB.BASEBOARD_FAB2(SCH_1):VR_PVDDQ_ABC_PH2_PHASE
   37  VR_PVDDQ_ABC_PH2_OCSET  OCSET  @BASEBOARD_FAB2_LIB.BASEBOARD_FAB2(SCH_1):VR_PVDDQ_ABC_PH2_OCSET
   33  VR_PVDDQ_ABC_PH2_BOOT_R  BOOST  @BASEBOARD_FAB2_LIB.BASEBOARD_FAB2(SCH_1):VR_PVDDQ_ABC_PH2_BOOT_R
   39  VR_PVDDQ_ABC_AIREF2  REFIN  @BASEBOARD_FAB2_LIB.BASEBOARD_FAB2(SCH_1):VR_PVDDQ_ABC_AIREF2
   30  VR_FET_SW_P12V_STBY_PVDDQ_ABC  VIN<1>  @BASEBOARD_FAB2_LIB.BASEBOARD_FAB2(SCH_1):VR_FET_SW_P12V_STBY_PVDDQ_ABC
   25  VR_FET_SW_P12V_STBY_PVDDQ_ABC  VIN<0>  @BASEBOARD_FAB2_LIB.BASEBOARD_FAB2(SCH_1):VR_FET_SW_P12V_STBY_PVDDQ_ABC
   41  TP_PVDDQ_ABC_PH2_GL_1  GL<1>  @BASEBOARD_FAB2_LIB.BASEBOARD_FAB2(SCH_1):TP_PVDDQ_ABC_PH2_GL_1
    6  TP_PVDDQ_ABC_PH2_GL_0  GL<0>  @BASEBOARD_FAB2_LIB.BASEBOARD_FAB2(SCH_1):TP_PVDDQ_ABC_PH2_GL_0
    1  PVDDQ_ABC        VOS  @BASEBOARD_FAB2_LIB.BASEBOARD_FAB2(SCH_1):PVDDQ_ABC
    4  P5V_STBY        VDRV  @BASEBOARD_FAB2_LIB.BASEBOARD_FAB2(SCH_1):P5V_STBY
   35  P5V_STBY          EN  @BASEBOARD_FAB2_LIB.BASEBOARD_FAB2(SCH_1):P5V_STBY
   31  NC_PVDDQ_ABC_PH2_P31     NC  @BASEBOARD_FAB2_LIB.BASEBOARD_FAB2(SCH_1):NC_PVDDQ_ABC_PH2_P31
   38  ISENSE_PVDDQ_ABC_PH2_IMON   IOUT  @BASEBOARD_FAB2_LIB.BASEBOARD_FAB2(SCH_1):ISENSE_PVDDQ_ABC_PH2_IMON
   40  GND            PGND<2>  @BASEBOARD_FAB2_LIB.BASEBOARD_FAB2(SCH_1):GND
    7  GND            PGND<1>  @BASEBOARD_FAB2_LIB.BASEBOARD_FAB2(SCH_1):GND
    5  GND            PGND<0>  @BASEBOARD_FAB2_LIB.BASEBOARD_FAB2(SCH_1):GND
    2  GND             LGND  @BASEBOARD_FAB2_LIB.BASEBOARD_FAB2(SCH_1):GND
   36  A_TSENSE_PVDDQ_ABC  TOUT_FLT  @BASEBOARD_FAB2_LIB.BASEBOARD_FAB2(SCH_1):A_TSENSE_PVDDQ_ABC

PXE1110B_QFN  I229  EU8A1  [PXE1110B_QFN-IC,H89187-001]
   20  VSENSE_PVNN_PCH_STBY_AVSN  AVREF  @BASEBOARD_FAB2_LIB.BASEBOARD_FAB2(SCH_1):VSENSE_PVNN_PCH_STBY_AVSN
   30  VSENSE_P1V05_PCH_STBY_AVSN  BVREF  @BASEBOARD_FAB2_LIB.BASEBOARD_FAB2(SCH_1):VSENSE_P1V05_PCH_STBY_AVSN
   33  VR_PVNN_PCH_XADDR2  XADDR2  @BASEBOARD_FAB2_LIB.BASEBOARD_FAB2(SCH_1):VR_PVNN_PCH_XADDR2
   36  VR_PVNN_PCH_XADDR1  XADDR1  @BASEBOARD_FAB2_LIB.BASEBOARD_FAB2(SCH_1):VR_PVNN_PCH_XADDR1
   10  VR_PVNN_PCH_VREN  AVREN  @BASEBOARD_FAB2_LIB.BASEBOARD_FAB2(SCH_1):VR_PVNN_PCH_VREN
   37  VR_PVNN_PCH_VINSEN  VINSEN  @BASEBOARD_FAB2_LIB.BASEBOARD_FAB2(SCH_1):VR_PVNN_PCH_VINSEN
   39  VR_PVNN_PCH_VDD    VDD  @BASEBOARD_FAB2_LIB.BASEBOARD_FAB2(SCH_1):VR_PVNN_PCH_VDD
    5  VR_PVNN_PCH_PWM1  APWM1  @BASEBOARD_FAB2_LIB.BASEBOARD_FAB2(SCH_1):VR_PVNN_PCH_PWM1
   19  VR_PVNN_PCH_AVSP  AVSEN  @BASEBOARD_FAB2_LIB.BASEBOARD_FAB2(SCH_1):VR_PVNN_PCH_AVSP
   21  VR_PVNN_PCH_AIREF1  AIREF1  @BASEBOARD_FAB2_LIB.BASEBOARD_FAB2(SCH_1):VR_PVNN_PCH_AIREF1
   40  VR_PVNN_P1V05_PCH_VD12   VD12  @BASEBOARD_FAB2_LIB.BASEBOARD_FAB2(SCH_1):VR_PVNN_P1V05_PCH_VD12
    3  VR_P1V05_PCH_STBY_PWM1  BPWM1  @BASEBOARD_FAB2_LIB.BASEBOARD_FAB2(SCH_1):VR_P1V05_PCH_STBY_PWM1
   29  VR_P1V05_PCH_STBY_AVSP  BVSEN  @BASEBOARD_FAB2_LIB.BASEBOARD_FAB2(SCH_1):VR_P1V05_PCH_STBY_AVSP
   25  VR_P1V05_PCH_BIREF1  BIREF1  @BASEBOARD_FAB2_LIB.BASEBOARD_FAB2(SCH_1):VR_P1V05_PCH_BIREF1
   14  VID_PCH_CORE_PVNN_AUX_VID_1    MP1  @BASEBOARD_FAB2_LIB.BASEBOARD_FAB2(SCH_1):VID_PCH_CORE_PVNN_AUX_VID_1
   13  VID_PCH_CORE_PVNN_AUX_VID_0    MP0  @BASEBOARD_FAB2_LIB.BASEBOARD_FAB2(SCH_1):VID_PCH_CORE_PVNN_AUX_VID_0
   38  TP_VR_PVNN_PCH_AIINSEN  IINSEN  @BASEBOARD_FAB2_LIB.BASEBOARD_FAB2(SCH_1):TP_VR_PVNN_PCH_AIINSEN
   16  TP_PVNN_PCH_VDIO   VDIO  @BASEBOARD_FAB2_LIB.BASEBOARD_FAB2(SCH_1):TP_PVNN_PCH_VDIO
   15  TP_PVNN_PCH_VCLK   VCLK  @BASEBOARD_FAB2_LIB.BASEBOARD_FAB2(SCH_1):TP_PVNN_PCH_VCLK
   17  TP_PVNN_PCH_SVID_ALERT  VALRT_N  @BASEBOARD_FAB2_LIB.BASEBOARD_FAB2(SCH_1):TP_PVNN_PCH_SVID_ALERT
    8  TP_PVNN_PCH_RESET_N  RESET_N  @BASEBOARD_FAB2_LIB.BASEBOARD_FAB2(SCH_1):TP_PVNN_PCH_RESET_N
   12  TP_PVNN_PCH_PINALRT_N  PINALRT_N  @BASEBOARD_FAB2_LIB.BASEBOARD_FAB2(SCH_1):TP_PVNN_PCH_PINALRT_N
   31  TP_PVNN_PCH_MP3    MP3  @BASEBOARD_FAB2_LIB.BASEBOARD_FAB2(SCH_1):TP_PVNN_PCH_MP3
   18  TP_PVNN_PCH_MP2    MP2  @BASEBOARD_FAB2_LIB.BASEBOARD_FAB2(SCH_1):TP_PVNN_PCH_MP2
    6  SMB_VR_SDA_PVNN_PCH    SDA  @BASEBOARD_FAB2_LIB.BASEBOARD_FAB2(SCH_1):SMB_VR_SDA_PVNN_PCH
    7  SMB_VR_SCL_PVNN_PCH    SCL  @BASEBOARD_FAB2_LIB.BASEBOARD_FAB2(SCH_1):SMB_VR_SCL_PVNN_PCH
    9  PWRGD_PVNN_PCH_R  AVRRDY  @BASEBOARD_FAB2_LIB.BASEBOARD_FAB2(SCH_1):PWRGD_PVNN_PCH_R
   32  PU_VR_PVNN_PCH_FAULT1    MP4  @BASEBOARD_FAB2_LIB.BASEBOARD_FAB2(SCH_1):PU_VR_PVNN_PCH_FAULT1
   28  NC_PVNN_PCH_DNC4  DNC<4>  @BASEBOARD_FAB2_LIB.BASEBOARD_FAB2(SCH_1):NC_PVNN_PCH_DNC4
   24  NC_PVNN_PCH_DNC3  DNC<3>  @BASEBOARD_FAB2_LIB.BASEBOARD_FAB2(SCH_1):NC_PVNN_PCH_DNC3
    4  NC_PVNN_PCH_DNC2  DNC<2>  @BASEBOARD_FAB2_LIB.BASEBOARD_FAB2(SCH_1):NC_PVNN_PCH_DNC2
    2  NC_PVNN_PCH_DNC1  DNC<1>  @BASEBOARD_FAB2_LIB.BASEBOARD_FAB2(SCH_1):NC_PVNN_PCH_DNC1
    1  NC_PVNN_PCH_DNC0  DNC<0>  @BASEBOARD_FAB2_LIB.BASEBOARD_FAB2(SCH_1):NC_PVNN_PCH_DNC0
   22  ISENSE_PVNN_PCH_PH1_IMON  AISEN1  @BASEBOARD_FAB2_LIB.BASEBOARD_FAB2(SCH_1):ISENSE_PVNN_PCH_PH1_IMON
   26  ISENSE_P1V05_PCH_STBY_PH1_IMON  BISEN1  @BASEBOARD_FAB2_LIB.BASEBOARD_FAB2(SCH_1):ISENSE_P1V05_PCH_STBY_PH1_IMON
   11  IRQ_PVNN_PCH_VRHOT_N  VRHOT_N  @BASEBOARD_FAB2_LIB.BASEBOARD_FAB2(SCH_1):IRQ_PVNN_PCH_VRHOT_N
   41  GND            THPAD  @BASEBOARD_FAB2_LIB.BASEBOARD_FAB2(SCH_1):GND
   23  GND            GND<1>  @BASEBOARD_FAB2_LIB.BASEBOARD_FAB2(SCH_1):GND
   27  GND            GND<0>  @BASEBOARD_FAB2_LIB.BASEBOARD_FAB2(SCH_1):GND
   35  A_TSENSE_PVNN_PCH_TMON  ATSEN  @BASEBOARD_FAB2_LIB.BASEBOARD_FAB2(SCH_1):A_TSENSE_PVNN_PCH_TMON
   34  A_TSENSE_P1V05_PCH_STBY_TMON  BTSEN  @BASEBOARD_FAB2_LIB.BASEBOARD_FAB2(SCH_1):A_TSENSE_P1V05_PCH_STBY_TMON

RT9059_DFN  I86  EU8A2  [RT9059_DFN-IC,H65765-001]
    4  VR_P1V8_PCH_STBY_FB  ADJ_NC  @BASEBOARD_FAB2_LIB.BASEBOARD_FAB2(SCH_1):VR_P1V8_PCH_STBY_FB
    6  PWRGD_P3V3_STBY     EN  @BASEBOARD_FAB2_LIB.BASEBOARD_FAB2(SCH_1):PWRGD_P3V3_STBY
    5  PWRGD_P1V8_PCH_STBY_R  PGOOD  @BASEBOARD_FAB2_LIB.BASEBOARD_FAB2(SCH_1):PWRGD_P1V8_PCH_STBY_R
    9  P3V3_STBY      VIN<2>  @BASEBOARD_FAB2_LIB.BASEBOARD_FAB2(SCH_1):P3V3_STBY
    8  P3V3_STBY      VIN<1>  @BASEBOARD_FAB2_LIB.BASEBOARD_FAB2(SCH_1):P3V3_STBY
    7  P3V3_STBY      VIN<0>  @BASEBOARD_FAB2_LIB.BASEBOARD_FAB2(SCH_1):P3V3_STBY
   10  P3V3_STBY        VDD  @BASEBOARD_FAB2_LIB.BASEBOARD_FAB2(SCH_1):P3V3_STBY
    3  P1V8_PCH_STBY  VOUT<2>  @BASEBOARD_FAB2_LIB.BASEBOARD_FAB2(SCH_1):P1V8_PCH_STBY
    2  P1V8_PCH_STBY  VOUT<1>  @BASEBOARD_FAB2_LIB.BASEBOARD_FAB2(SCH_1):P1V8_PCH_STBY
    1  P1V8_PCH_STBY  VOUT<0>  @BASEBOARD_FAB2_LIB.BASEBOARD_FAB2(SCH_1):P1V8_PCH_STBY
   11  GND              GND  @BASEBOARD_FAB2_LIB.BASEBOARD_FAB2(SCH_1):GND

SLG55021_SM  I13  EU8B1  [SLG55021_SM-IC,G56246-001]
    8  TP_SLG55021_P5V_8     PG  @BASEBOARD_FAB2_LIB.BASEBOARD_FAB2(SCH_1):TP_SLG55021_P5V_8
    7  P5V_SWITCH_G       G  @BASEBOARD_FAB2_LIB.BASEBOARD_FAB2(SCH_1):P5V_SWITCH_G
    1  P5V_STBY         VCC  @BASEBOARD_FAB2_LIB.BASEBOARD_FAB2(SCH_1):P5V_STBY
    3  P5V_STBY       SHDN_N  @BASEBOARD_FAB2_LIB.BASEBOARD_FAB2(SCH_1):P5V_STBY
    5  P5V_STBY           D  @BASEBOARD_FAB2_LIB.BASEBOARD_FAB2(SCH_1):P5V_STBY
    6  P5V                S  @BASEBOARD_FAB2_LIB.BASEBOARD_FAB2(SCH_1):P5V
    9  GND            THPAD  @BASEBOARD_FAB2_LIB.BASEBOARD_FAB2(SCH_1):GND
    4  GND              GND  @BASEBOARD_FAB2_LIB.BASEBOARD_FAB2(SCH_1):GND
    2  FM_CTNR_PS_ON     ON  @BASEBOARD_FAB2_LIB.BASEBOARD_FAB2(SCH_1):FM_CTNR_PS_ON

CSD87384M_SM  I170  EU8E1  [CSD87384M_SM-IC,H66258-001]
    1  VR_P3V3_STBY_UGATE     TG  @BASEBOARD_FAB2_LIB.BASEBOARD_FAB2(SCH_1):VR_P3V3_STBY_UGATE
    5  VR_P3V3_STBY_PHASE    VSW  @BASEBOARD_FAB2_LIB.BASEBOARD_FAB2(SCH_1):VR_P3V3_STBY_PHASE
    4  VR_P3V3_STBY_LGATE     BG  @BASEBOARD_FAB2_LIB.BASEBOARD_FAB2(SCH_1):VR_P3V3_STBY_LGATE
    2  VR_FET_SW_P12V_STBY_P3V3_STBY    VIN  @BASEBOARD_FAB2_LIB.BASEBOARD_FAB2(SCH_1):VR_FET_SW_P12V_STBY_P3V3_STBY
    3  GND             PGND  @BASEBOARD_FAB2_LIB.BASEBOARD_FAB2(SCH_1):GND

RT8240_QFN  I125  EU8F1  [RT8240_QFN-IC,H66262-001]
    6  VSENSE_VOUT_P3V3_STBY   VOUT  @BASEBOARD_FAB2_LIB.BASEBOARD_FAB2(SCH_1):VSENSE_VOUT_P3V3_STBY
    7  VSENSE_RGND_P3V3_STBY   RGND  @BASEBOARD_FAB2_LIB.BASEBOARD_FAB2(SCH_1):VSENSE_RGND_P3V3_STBY
    3  VR_P3V3_STBY_UGATE  UGATE  @BASEBOARD_FAB2_LIB.BASEBOARD_FAB2(SCH_1):VR_P3V3_STBY_UGATE
    2  VR_P3V3_STBY_PHASE  PHASE  @BASEBOARD_FAB2_LIB.BASEBOARD_FAB2(SCH_1):VR_P3V3_STBY_PHASE
   10  VR_P3V3_STBY_OCSELECT     CS  @BASEBOARD_FAB2_LIB.BASEBOARD_FAB2(SCH_1):VR_P3V3_STBY_OCSELECT
    1  VR_P3V3_STBY_LGATE  LGATE  @BASEBOARD_FAB2_LIB.BASEBOARD_FAB2(SCH_1):VR_P3V3_STBY_LGATE
    8  VR_P3V3_STBY_EN     EN  @BASEBOARD_FAB2_LIB.BASEBOARD_FAB2(SCH_1):VR_P3V3_STBY_EN
    4  VR_P3V3_STBY_BOOT   BOOT  @BASEBOARD_FAB2_LIB.BASEBOARD_FAB2(SCH_1):VR_P3V3_STBY_BOOT
    9  PWRGD_P3V3_STBY_R  PGOOD  @BASEBOARD_FAB2_LIB.BASEBOARD_FAB2(SCH_1):PWRGD_P3V3_STBY_R
    5  P5V_STBY         VCC  @BASEBOARD_FAB2_LIB.BASEBOARD_FAB2(SCH_1):P5V_STBY
   13  AGND_P3V3_STBY  GND<1>  @BASEBOARD_FAB2_LIB.BASEBOARD_FAB2(SCH_1):AGND_P3V3_STBY
   12  AGND_P3V3_STBY  GND<0>  @BASEBOARD_FAB2_LIB.BASEBOARD_FAB2(SCH_1):AGND_P3V3_STBY
   11  AGND_P3V3_STBY     G0  @BASEBOARD_FAB2_LIB.BASEBOARD_FAB2(SCH_1):AGND_P3V3_STBY

ICS9FGP204_MLFP  I34  EU8F2  [ICS9FGP204_MLFP-IC,E95226-001]
   20  XTAL_CK_MNG_OUT  X2_25  @BASEBOARD_FAB2_LIB.BASEBOARD_FAB2(SCH_1):XTAL_CK_MNG_OUT
   19  XTAL_CK_MNG_IN  X1_25  @BASEBOARD_FAB2_LIB.BASEBOARD_FAB2(SCH_1):XTAL_CK_MNG_IN
    3  TP_CLK_96M_CKMNG_P  DOT96SST  @BASEBOARD_FAB2_LIB.BASEBOARD_FAB2(SCH_1):TP_CLK_96M_CKMNG_P
    4  TP_CLK_96M_CKMNG_N  DOT96SSC  @BASEBOARD_FAB2_LIB.BASEBOARD_FAB2(SCH_1):TP_CLK_96M_CKMNG_N
   37  TP_CLK_125M_BMCA  RGMII<0>  @BASEBOARD_FAB2_LIB.BASEBOARD_FAB2(SCH_1):TP_CLK_125M_BMCA
   36  TP_CLK_125M    RGMII<1>  @BASEBOARD_FAB2_LIB.BASEBOARD_FAB2(SCH_1):TP_CLK_125M
    7  TP_CLK_100M_R_DP  CPUCLKT0  @BASEBOARD_FAB2_LIB.BASEBOARD_FAB2(SCH_1):TP_CLK_100M_R_DP
    8  TP_CLK_100M_R_DN  CPUCLKC0  @BASEBOARD_FAB2_LIB.BASEBOARD_FAB2(SCH_1):TP_CLK_100M_R_DN
   24  TP_CLK5_50M_CKMNG  RMII<5>  @BASEBOARD_FAB2_LIB.BASEBOARD_FAB2(SCH_1):TP_CLK5_50M_CKMNG
   22  TP_33P_33M_SMBADR  33MHZ_SMBADR  @BASEBOARD_FAB2_LIB.BASEBOARD_FAB2(SCH_1):TP_33P_33M_SMBADR
   39  SMB_HOST_STBY_LVC3_SDA  SMBDAT  @BASEBOARD_FAB2_LIB.BASEBOARD_FAB2(SCH_1):SMB_HOST_STBY_LVC3_SDA
   38  SMB_HOST_STBY_LVC3_SCL  SMBCLK  @BASEBOARD_FAB2_LIB.BASEBOARD_FAB2(SCH_1):SMB_HOST_STBY_LVC3_SCL
   40  PWRGD_P3V3_STBY  VTTPWR_GD_PD_N  @BASEBOARD_FAB2_LIB.BASEBOARD_FAB2(SCH_1):PWRGD_P3V3_STBY
    6  PD_CKMNG_OE    OE_CPU  @BASEBOARD_FAB2_LIB.BASEBOARD_FAB2(SCH_1):PD_CKMNG_OE
    5  PD_CKMNG_OE    OE_96  @BASEBOARD_FAB2_LIB.BASEBOARD_FAB2(SCH_1):PD_CKMNG_OE
   31  P3V3_STBY_MNG_RMII  VDDRMII<1>  @BASEBOARD_FAB2_LIB.BASEBOARD_FAB2(SCH_1):P3V3_STBY_MNG_RMII
   26  P3V3_STBY_MNG_RMII  VDDRMII<0>  @BASEBOARD_FAB2_LIB.BASEBOARD_FAB2(SCH_1):P3V3_STBY_MNG_RMII
   34  P3V3_STBY_MNG_RGMII  VDD_RGMII  @BASEBOARD_FAB2_LIB.BASEBOARD_FAB2(SCH_1):P3V3_STBY_MNG_RGMII
    9  P3V3_STBY_MNG_CPU  VDDCPU  @BASEBOARD_FAB2_LIB.BASEBOARD_FAB2(SCH_1):P3V3_STBY_MNG_CPU
   15  P3V3_STBY_MNG  VDDREF  @BASEBOARD_FAB2_LIB.BASEBOARD_FAB2(SCH_1):P3V3_STBY_MNG
    2  P3V3_STBY_MNG  VDD96  @BASEBOARD_FAB2_LIB.BASEBOARD_FAB2(SCH_1):P3V3_STBY_MNG
   23  P3V3_STBY_MNG  VDD33  @BASEBOARD_FAB2_LIB.BASEBOARD_FAB2(SCH_1):P3V3_STBY_MNG
   12  P3V3_STBY_MNG  VDD32K  @BASEBOARD_FAB2_LIB.BASEBOARD_FAB2(SCH_1):P3V3_STBY_MNG
   30  GND            GNDRMII<1>  @BASEBOARD_FAB2_LIB.BASEBOARD_FAB2(SCH_1):GND
   27  GND            GNDRMII<0>  @BASEBOARD_FAB2_LIB.BASEBOARD_FAB2(SCH_1):GND
   18  GND            GNDREF  @BASEBOARD_FAB2_LIB.BASEBOARD_FAB2(SCH_1):GND
   10  GND            GNDCPU  @BASEBOARD_FAB2_LIB.BASEBOARD_FAB2(SCH_1):GND
   35  GND            GND_RGMII  @BASEBOARD_FAB2_LIB.BASEBOARD_FAB2(SCH_1):GND
   21  GND            GND33  @BASEBOARD_FAB2_LIB.BASEBOARD_FAB2(SCH_1):GND
   14  GND            GND32K  @BASEBOARD_FAB2_LIB.BASEBOARD_FAB2(SCH_1):GND
   41  GND            GND<1>  @BASEBOARD_FAB2_LIB.BASEBOARD_FAB2(SCH_1):GND
    1  GND            GND<0>  @BASEBOARD_FAB2_LIB.BASEBOARD_FAB2(SCH_1):GND
   28  CLK_50M_CKMNG_SPRVLLE_R  RMII<3>  @BASEBOARD_FAB2_LIB.BASEBOARD_FAB2(SCH_1):CLK_50M_CKMNG_SPRVLLE_R
   25  CLK_50M_CKMNG_PCH_10GBE_R  RMII<4>  @BASEBOARD_FAB2_LIB.BASEBOARD_FAB2(SCH_1):CLK_50M_CKMNG_PCH_10GBE_R
   33  CLK_50M_CKMNG_OCP_R  RMII<0>  @BASEBOARD_FAB2_LIB.BASEBOARD_FAB2(SCH_1):CLK_50M_CKMNG_OCP_R
   29  CLK_50M_CKMNG_BMC_2_R  RMII<2>  @BASEBOARD_FAB2_LIB.BASEBOARD_FAB2(SCH_1):CLK_50M_CKMNG_BMC_2_R
   32  CLK_50M_CKMNG_BMC_1_R  RMII<1>  @BASEBOARD_FAB2_LIB.BASEBOARD_FAB2(SCH_1):CLK_50M_CKMNG_BMC_1_R
   13  CLK_32K_SUSCLK_PLD_R  32KHZ  @BASEBOARD_FAB2_LIB.BASEBOARD_FAB2(SCH_1):CLK_32K_SUSCLK_PLD_R
   17  CLK_25M_CPLD_R  25MHZ_1  @BASEBOARD_FAB2_LIB.BASEBOARD_FAB2(SCH_1):CLK_25M_CPLD_R
   16  CLK_25M_BMC_R  25MHZ_0  @BASEBOARD_FAB2_LIB.BASEBOARD_FAB2(SCH_1):CLK_25M_BMC_R
   11  A_COMP_CKMNG    IREF  @BASEBOARD_FAB2_LIB.BASEBOARD_FAB2(SCH_1):A_COMP_CKMNG

SPRINGVILLE_SM1  I72  EU9E1  [SPRINGVILLE_SM1-IC,G47144-004]
   45  XTAL_25MHZ_OUT  XTAL2  @BASEBOARD_FAB2_LIB.BASEBOARD_FAB2(SCH_1):XTAL_25MHZ_OUT
   46  XTAL_25MHZ_IN_R  XTAL1  @BASEBOARD_FAB2_LIB.BASEBOARD_FAB2(SCH_1):XTAL_25MHZ_IN_R
   60  TP_SPRV_SDP3    SDP3  @BASEBOARD_FAB2_LIB.BASEBOARD_FAB2(SCH_1):TP_SPRV_SDP3
   62  TP_SPRV_SDP2    SDP2  @BASEBOARD_FAB2_LIB.BASEBOARD_FAB2(SCH_1):TP_SPRV_SDP2
   61  TP_SPRV_SDP1   SDP1_PCIE_DIS_SDP1  @BASEBOARD_FAB2_LIB.BASEBOARD_FAB2(SCH_1):TP_SPRV_SDP1
   63  TP_SPRV_SDP0    SDP0  @BASEBOARD_FAB2_LIB.BASEBOARD_FAB2(SCH_1):TP_SPRV_SDP0
   13  SPI_NIC_SCLK_R  NVM_SK  @BASEBOARD_FAB2_LIB.BASEBOARD_FAB2(SCH_1):SPI_NIC_SCLK_R
   12  SPI_NIC_MOSI_R  NVM_SI  @BASEBOARD_FAB2_LIB.BASEBOARD_FAB2(SCH_1):SPI_NIC_MOSI_R
   14  SPI_NIC_MISO   NVM_SO  @BASEBOARD_FAB2_LIB.BASEBOARD_FAB2(SCH_1):SPI_NIC_MISO
   15  SPI_NIC_CS_R_N  NVM_CS_N  @BASEBOARD_FAB2_LIB.BASEBOARD_FAB2(SCH_1):SPI_NIC_CS_R_N
   36  SMB_SPRINGVILLE_STBY_LVC3_SDA  SMB_DATA  @BASEBOARD_FAB2_LIB.BASEBOARD_FAB2(SCH_1):SMB_SPRINGVILLE_STBY_LVC3_SDA
   34  SMB_SPRINGVILLE_STBY_LVC3_SCL  SMB_CLK  @BASEBOARD_FAB2_LIB.BASEBOARD_FAB2(SCH_1):SMB_SPRINGVILLE_STBY_LVC3_SCL
   17  RST_PLTRST_SPRV_R_N  PE_RST_N  @BASEBOARD_FAB2_LIB.BASEBOARD_FAB2(SCH_1):RST_PLTRST_SPRV_R_N
    5  RMII_SPRNGVLLE_BMC_PCH_RXD1_R  NC_SI_RXD1  @BASEBOARD_FAB2_LIB.BASEBOARD_FAB2(SCH_1):RMII_SPRNGVLLE_BMC_PCH_RXD1_R
    6  RMII_SPRNGVLLE_BMC_PCH_RXD0_R  NC_SI_RXD0  @BASEBOARD_FAB2_LIB.BASEBOARD_FAB2(SCH_1):RMII_SPRNGVLLE_BMC_PCH_RXD0_R
   43  RMII_PCH_SPRNGVLLE_ARB_OUT  NC_SI_ARB_IN  @BASEBOARD_FAB2_LIB.BASEBOARD_FAB2(SCH_1):RMII_PCH_SPRNGVLLE_ARB_OUT
   44  RMII_PCH_SPRNGVLLE_ARB_IN_R  NC_SI_ARB_OUT  @BASEBOARD_FAB2_LIB.BASEBOARD_FAB2(SCH_1):RMII_PCH_SPRNGVLLE_ARB_IN_R
    7  RMII_BMC_PCH_SPRNGVLLE_TXEN  NC_SI_TX_EN  @BASEBOARD_FAB2_LIB.BASEBOARD_FAB2(SCH_1):RMII_BMC_PCH_SPRNGVLLE_TXEN
    8  RMII_BMC_PCH_SPRNGVLLE_TXD1  NC_SI_TXD1  @BASEBOARD_FAB2_LIB.BASEBOARD_FAB2(SCH_1):RMII_BMC_PCH_SPRNGVLLE_TXD1
    9  RMII_BMC_PCH_SPRNGVLLE_TXD0  NC_SI_TXD0  @BASEBOARD_FAB2_LIB.BASEBOARD_FAB2(SCH_1):RMII_BMC_PCH_SPRNGVLLE_TXD0
    3  RMII_BMC_PCH_SPRNGVLLE_CRSDV_R  NC_SI_CRS_DV  @BASEBOARD_FAB2_LIB.BASEBOARD_FAB2(SCH_1):RMII_BMC_PCH_SPRNGVLLE_CRSDV_R
    1  PU_SPRV_LAN_PWR_GOOD  LAN_PWR_GOOD  @BASEBOARD_FAB2_LIB.BASEBOARD_FAB2(SCH_1):PU_SPRV_LAN_PWR_GOOD
   18  PU_JTAG_SPRV_TMS  JTAG_TMS  @BASEBOARD_FAB2_LIB.BASEBOARD_FAB2(SCH_1):PU_JTAG_SPRV_TMS
    4  PU_JTAG_SPRV_TDO  JTAG_TDO  @BASEBOARD_FAB2_LIB.BASEBOARD_FAB2(SCH_1):PU_JTAG_SPRV_TDO
   29  PU_JTAG_SPRV_TDI  JTAG_TDI  @BASEBOARD_FAB2_LIB.BASEBOARD_FAB2(SCH_1):PU_JTAG_SPRV_TDI
   19  PU_JTAG_SPRV_TCK  JTAG_CLK  @BASEBOARD_FAB2_LIB.BASEBOARD_FAB2(SCH_1):PU_JTAG_SPRV_TCK
   24  PE_PCH_SPRV_TX_C_DP  PE_RP  @BASEBOARD_FAB2_LIB.BASEBOARD_FAB2(SCH_1):PE_PCH_SPRV_TX_C_DP
   23  PE_PCH_SPRV_TX_C_DN  PE_RN  @BASEBOARD_FAB2_LIB.BASEBOARD_FAB2(SCH_1):PE_PCH_SPRV_TX_C_DN
   21  PE_PCH_SPRV_RX_DP  PE_TP  @BASEBOARD_FAB2_LIB.BASEBOARD_FAB2(SCH_1):PE_PCH_SPRV_RX_DP
   20  PE_PCH_SPRV_RX_DN  PE_TN  @BASEBOARD_FAB2_LIB.BASEBOARD_FAB2(SCH_1):PE_PCH_SPRV_RX_DN
   48  PD_SPRV_RSET    RSET  @BASEBOARD_FAB2_LIB.BASEBOARD_FAB2(SCH_1):PD_SPRV_RSET
   51  P3V3_STBY_P1V5_LAN_I210  VDD3P3<1>  @BASEBOARD_FAB2_LIB.BASEBOARD_FAB2(SCH_1):P3V3_STBY_P1V5_LAN_I210
   10  P3V3_STBY      VDD3P3<4>  @BASEBOARD_FAB2_LIB.BASEBOARD_FAB2(SCH_1):P3V3_STBY
   27  P3V3_STBY      VDD3P3<3>  @BASEBOARD_FAB2_LIB.BASEBOARD_FAB2(SCH_1):P3V3_STBY
   41  P3V3_STBY      VDD3P3<2>  @BASEBOARD_FAB2_LIB.BASEBOARD_FAB2(SCH_1):P3V3_STBY
   64  P3V3_STBY      VDD3P3<0>  @BASEBOARD_FAB2_LIB.BASEBOARD_FAB2(SCH_1):P3V3_STBY
   56  P1V5_LAN_I210  VDD1P5<0>  @BASEBOARD_FAB2_LIB.BASEBOARD_FAB2(SCH_1):P1V5_LAN_I210
   39  P1V5_LAN       VDD1P5_OUT  @BASEBOARD_FAB2_LIB.BASEBOARD_FAB2(SCH_1):P1V5_LAN
   47  P1V5_LAN       VDD1P5<1>  @BASEBOARD_FAB2_LIB.BASEBOARD_FAB2(SCH_1):P1V5_LAN
   38  P0V9_LAN_I210  VDD0P9_OUT  @BASEBOARD_FAB2_LIB.BASEBOARD_FAB2(SCH_1):P0V9_LAN_I210
   42  P0V9_LAN       VDD0P9<3>  @BASEBOARD_FAB2_LIB.BASEBOARD_FAB2(SCH_1):P0V9_LAN
   11  P0V9_LAN       VDD0P9<2>  @BASEBOARD_FAB2_LIB.BASEBOARD_FAB2(SCH_1):P0V9_LAN
   32  P0V9_LAN       VDD0P9<1>  @BASEBOARD_FAB2_LIB.BASEBOARD_FAB2(SCH_1):P0V9_LAN
   59  P0V9_LAN       VDD0P9<0>  @BASEBOARD_FAB2_LIB.BASEBOARD_FAB2(SCH_1):P0V9_LAN
   53  NIC_SET_P_MDI_2_DP  MDI_PLUS2_SETP  @BASEBOARD_FAB2_LIB.BASEBOARD_FAB2(SCH_1):NIC_SET_P_MDI_2_DP
   52  NIC_SET_N_MDI_2_DN  MDI_MINUS2_SETN  @BASEBOARD_FAB2_LIB.BASEBOARD_FAB2(SCH_1):NIC_SET_N_MDI_2_DN
   50  NIC_SER_P_MDI_3_DP  MDI_PLUS3_SERP  @BASEBOARD_FAB2_LIB.BASEBOARD_FAB2(SCH_1):NIC_SER_P_MDI_3_DP
   49  NIC_SER_N_MDI_3_DN  MDI_MINUS3_SERN  @BASEBOARD_FAB2_LIB.BASEBOARD_FAB2(SCH_1):NIC_SER_N_MDI_3_DN
   55  NIC_MDI_SPRV_RJ45_1_DP  MDI_PLUS1_SFP_I2C_CLK  @BASEBOARD_FAB2_LIB.BASEBOARD_FAB2(SCH_1):NIC_MDI_SPRV_RJ45_1_DP
   54  NIC_MDI_SPRV_RJ45_1_DN  MDI_MINUS1_SRDS_SIG_DET  @BASEBOARD_FAB2_LIB.BASEBOARD_FAB2(SCH_1):NIC_MDI_SPRV_RJ45_1_DN
   58  NIC_MDI_SPRV_RJ45_0_DP  MDI_PLUS0_NC  @BASEBOARD_FAB2_LIB.BASEBOARD_FAB2(SCH_1):NIC_MDI_SPRV_RJ45_0_DP
   57  NIC_MDI_SPRV_RJ45_0_DN  MDI_MINUS0_SFP_I2C_DATA  @BASEBOARD_FAB2_LIB.BASEBOARD_FAB2(SCH_1):NIC_MDI_SPRV_RJ45_0_DN
   22  NC_SPRNGVLLE_22     NC  @BASEBOARD_FAB2_LIB.BASEBOARD_FAB2(SCH_1):NC_SPRNGVLLE_22
   33  LED_LAN_2_N     LED2  @BASEBOARD_FAB2_LIB.BASEBOARD_FAB2(SCH_1):LED_LAN_2_N
   30  LED_LAN_1_N     LED1  @BASEBOARD_FAB2_LIB.BASEBOARD_FAB2(SCH_1):LED_LAN_1_N
   31  LED_LAN_0_N     LED0  @BASEBOARD_FAB2_LIB.BASEBOARD_FAB2(SCH_1):LED_LAN_0_N
   35  IRQ_LOM_ALERT_N  SMB_ALRT_N  @BASEBOARD_FAB2_LIB.BASEBOARD_FAB2(SCH_1):IRQ_LOM_ALERT_N
   65  GND              GND  @BASEBOARD_FAB2_LIB.BASEBOARD_FAB2(SCH_1):GND
   16  FM_PE_SPRV_WAKE_N  PE_WAKE_N  @BASEBOARD_FAB2_LIB.BASEBOARD_FAB2(SCH_1):FM_PE_SPRV_WAKE_N
   28  FM_1GB_LOM_DISABLE_N  DEV_OFF_N  @BASEBOARD_FAB2_LIB.BASEBOARD_FAB2(SCH_1):FM_1GB_LOM_DISABLE_N
    2  CLK_50M_CKMNG_SPRVLLE  NC_SI_CLK_IN  @BASEBOARD_FAB2_LIB.BASEBOARD_FAB2(SCH_1):CLK_50M_CKMNG_SPRVLLE
   26  CLK_100M_SPRV_DP  PECLKP  @BASEBOARD_FAB2_LIB.BASEBOARD_FAB2(SCH_1):CLK_100M_SPRV_DP
   25  CLK_100M_SPRV_DN  PECLKN  @BASEBOARD_FAB2_LIB.BASEBOARD_FAB2(SCH_1):CLK_100M_SPRV_DN
   40  A_CTOP          CTOP  @BASEBOARD_FAB2_LIB.BASEBOARD_FAB2(SCH_1):A_CTOP
   37  A_CBOT          CBOT  @BASEBOARD_FAB2_LIB.BASEBOARD_FAB2(SCH_1):A_CBOT

RT9059_DFN  I40  EU9F1  [RT9059_DFN-IC,H65765-001]
    4  VR_P1V26_BMC_STBY_FB  ADJ_NC  @BASEBOARD_FAB2_LIB.BASEBOARD_FAB2(SCH_1):VR_P1V26_BMC_STBY_FB
    6  PWRGD_P1V538_BMC_STBY     EN  @BASEBOARD_FAB2_LIB.BASEBOARD_FAB2(SCH_1):PWRGD_P1V538_BMC_STBY
    5  PWRGD_P1V26_BMC_STBY_R  PGOOD  @BASEBOARD_FAB2_LIB.BASEBOARD_FAB2(SCH_1):PWRGD_P1V26_BMC_STBY_R
   10  P3V3_STBY        VDD  @BASEBOARD_FAB2_LIB.BASEBOARD_FAB2(SCH_1):P3V3_STBY
    9  P1V538_BMC_STBY  VIN<2>  @BASEBOARD_FAB2_LIB.BASEBOARD_FAB2(SCH_1):P1V538_BMC_STBY
    8  P1V538_BMC_STBY  VIN<1>  @BASEBOARD_FAB2_LIB.BASEBOARD_FAB2(SCH_1):P1V538_BMC_STBY
    7  P1V538_BMC_STBY  VIN<0>  @BASEBOARD_FAB2_LIB.BASEBOARD_FAB2(SCH_1):P1V538_BMC_STBY
    3  P1V26_BMC_STBY  VOUT<2>  @BASEBOARD_FAB2_LIB.BASEBOARD_FAB2(SCH_1):P1V26_BMC_STBY
    2  P1V26_BMC_STBY  VOUT<1>  @BASEBOARD_FAB2_LIB.BASEBOARD_FAB2(SCH_1):P1V26_BMC_STBY
    1  P1V26_BMC_STBY  VOUT<0>  @BASEBOARD_FAB2_LIB.BASEBOARD_FAB2(SCH_1):P1V26_BMC_STBY
   11  GND              GND  @BASEBOARD_FAB2_LIB.BASEBOARD_FAB2(SCH_1):GND

RT9059_DFN  I70  EU9F2  [RT9059_DFN-IC,H65765-001]
    4  VR_P1V538_BMC_STBY_FB  ADJ_NC  @BASEBOARD_FAB2_LIB.BASEBOARD_FAB2(SCH_1):VR_P1V538_BMC_STBY_FB
    6  PWRGD_P3V3_STBY     EN  @BASEBOARD_FAB2_LIB.BASEBOARD_FAB2(SCH_1):PWRGD_P3V3_STBY
    5  PWRGD_P1V538_BMC_STBY_R  PGOOD  @BASEBOARD_FAB2_LIB.BASEBOARD_FAB2(SCH_1):PWRGD_P1V538_BMC_STBY_R
    9  P3V3_STBY      VIN<2>  @BASEBOARD_FAB2_LIB.BASEBOARD_FAB2(SCH_1):P3V3_STBY
    8  P3V3_STBY      VIN<1>  @BASEBOARD_FAB2_LIB.BASEBOARD_FAB2(SCH_1):P3V3_STBY
    7  P3V3_STBY      VIN<0>  @BASEBOARD_FAB2_LIB.BASEBOARD_FAB2(SCH_1):P3V3_STBY
   10  P3V3_STBY        VDD  @BASEBOARD_FAB2_LIB.BASEBOARD_FAB2(SCH_1):P3V3_STBY
    3  P1V538_BMC_STBY  VOUT<2>  @BASEBOARD_FAB2_LIB.BASEBOARD_FAB2(SCH_1):P1V538_BMC_STBY
    2  P1V538_BMC_STBY  VOUT<1>  @BASEBOARD_FAB2_LIB.BASEBOARD_FAB2(SCH_1):P1V538_BMC_STBY
    1  P1V538_BMC_STBY  VOUT<0>  @BASEBOARD_FAB2_LIB.BASEBOARD_FAB2(SCH_1):P1V538_BMC_STBY
   11  GND              GND  @BASEBOARD_FAB2_LIB.BASEBOARD_FAB2(SCH_1):GND

PI7C9X1172_QFN  I1   EU9F3  [PI7C9X1172_QFN-IC,H66899-001]
   10  XTAL_24MHZ_OUT_R  XTAL2  @BASEBOARD_FAB2_LIB.BASEBOARD_FAB2(SCH_1):XTAL_24MHZ_OUT_R
    9  XTAL_24MHZ_IN_R  XTAL1  @BASEBOARD_FAB2_LIB.BASEBOARD_FAB2(SCH_1):XTAL_24MHZ_IN_R
    7  UART_BRIDGE_TXD5    TXB  @BASEBOARD_FAB2_LIB.BASEBOARD_FAB2(SCH_1):UART_BRIDGE_TXD5
    4  UART_BRIDGE_RXD5    RXB  @BASEBOARD_FAB2_LIB.BASEBOARD_FAB2(SCH_1):UART_BRIDGE_RXD5
    2  TP_PI7C9X1172_SO     SO  @BASEBOARD_FAB2_LIB.BASEBOARD_FAB2(SCH_1):TP_PI7C9X1172_SO
   15  TP_PI7C9X1172_RTSB_N  RTSB_N  @BASEBOARD_FAB2_LIB.BASEBOARD_FAB2(SCH_1):TP_PI7C9X1172_RTSB_N
   21  TP_PI7C9X1172_RTSA_N  RTSA_N  @BASEBOARD_FAB2_LIB.BASEBOARD_FAB2(SCH_1):TP_PI7C9X1172_RTSA_N
   18  TP_PI7C9X1172_ENIR_N  ENIR_N  @BASEBOARD_FAB2_LIB.BASEBOARD_FAB2(SCH_1):TP_PI7C9X1172_ENIR_N
   19  TP_PI7C9X1172_EN485_N  EN485_N  @BASEBOARD_FAB2_LIB.BASEBOARD_FAB2(SCH_1):TP_PI7C9X1172_EN485_N
   28  TP_GPIO7_RIA_N  GPIO7_RIA_N  @BASEBOARD_FAB2_LIB.BASEBOARD_FAB2(SCH_1):TP_GPIO7_RIA_N
   27  TP_GPIO6_CDA_N  GPIO6_CDA_N  @BASEBOARD_FAB2_LIB.BASEBOARD_FAB2(SCH_1):TP_GPIO6_CDA_N
   22  TP_GPIO5_DTRA_N  GPIO5_DTRA_N  @BASEBOARD_FAB2_LIB.BASEBOARD_FAB2(SCH_1):TP_GPIO5_DTRA_N
   26  TP_GPIO4_DSRA_N  GPIO4_DSRA_N  @BASEBOARD_FAB2_LIB.BASEBOARD_FAB2(SCH_1):TP_GPIO4_DSRA_N
   14  TP_GPIO3_RIB_N  GPIO3_RIB_N  @BASEBOARD_FAB2_LIB.BASEBOARD_FAB2(SCH_1):TP_GPIO3_RIB_N
   11  TP_GPIO2_CDB_N  GPIO2_CDB_N  @BASEBOARD_FAB2_LIB.BASEBOARD_FAB2(SCH_1):TP_GPIO2_CDB_N
   23  TP_GPIO1_DTRB_N  GPIO1_DTRB_N  @BASEBOARD_FAB2_LIB.BASEBOARD_FAB2(SCH_1):TP_GPIO1_DTRB_N
   13  TP_GPIO0_DSRB_N  GPIO0_DSRB_N  @BASEBOARD_FAB2_LIB.BASEBOARD_FAB2(SCH_1):TP_GPIO0_DSRB_N
    6  SP1_HOST_BRIDGE_UART_TX    TXA  @BASEBOARD_FAB2_LIB.BASEBOARD_FAB2(SCH_1):SP1_HOST_BRIDGE_UART_TX
    5  SP1_HOST_BRIDGE_UART_RX    RXA  @BASEBOARD_FAB2_LIB.BASEBOARD_FAB2(SCH_1):SP1_HOST_BRIDGE_UART_RX
    3  SMB_SLOTX24_PCH_STBY_LVC3_SDA    SDA  @BASEBOARD_FAB2_LIB.BASEBOARD_FAB2(SCH_1):SMB_SLOTX24_PCH_STBY_LVC3_SDA
   17  SMB_SLOTX24_PCH_STBY_LVC3_SCL    SCL  @BASEBOARD_FAB2_LIB.BASEBOARD_FAB2(SCH_1):SMB_SLOTX24_PCH_STBY_LVC3_SCL
   24  PWRGD_DSW_PWROK  RESET_N  @BASEBOARD_FAB2_LIB.BASEBOARD_FAB2(SCH_1):PWRGD_DSW_PWROK
   32  PU_PI7C9X1172_I2C_SPI_N  I2C_SPI_N  @BASEBOARD_FAB2_LIB.BASEBOARD_FAB2(SCH_1):PU_PI7C9X1172_I2C_SPI_N
   29  P3V3_STBY        VDD  @BASEBOARD_FAB2_LIB.BASEBOARD_FAB2(SCH_1):P3V3_STBY
    8  NC_PI7C9X1172_8  NC<1>  @BASEBOARD_FAB2_LIB.BASEBOARD_FAB2(SCH_1):NC_PI7C9X1172_8
    1  NC_PI7C9X1172_1  NC<0>  @BASEBOARD_FAB2_LIB.BASEBOARD_FAB2(SCH_1):NC_PI7C9X1172_1
   33  GND            THPAD  @BASEBOARD_FAB2_LIB.BASEBOARD_FAB2(SCH_1):GND
   12  GND              GND  @BASEBOARD_FAB2_LIB.BASEBOARD_FAB2(SCH_1):GND
   16  GND            CTSB_N  @BASEBOARD_FAB2_LIB.BASEBOARD_FAB2(SCH_1):GND
   25  GND            CTSA_N  @BASEBOARD_FAB2_LIB.BASEBOARD_FAB2(SCH_1):GND
   20  FM_UART_ALERT_N  IRQ_N  @BASEBOARD_FAB2_LIB.BASEBOARD_FAB2(SCH_1):FM_UART_ALERT_N
   31  FM_PI7C9X1172_A1  A1_S1  @BASEBOARD_FAB2_LIB.BASEBOARD_FAB2(SCH_1):FM_PI7C9X1172_A1
   30  FM_PI7C9X1172_A0  A0_CS_N  @BASEBOARD_FAB2_LIB.BASEBOARD_FAB2(SCH_1):FM_PI7C9X1172_A0

ADC128D818_SM  I52  EU9G1  [ADC128D818_SM-IC,H63642-001]
    1  TP_ADC128_VREF   VREF  @BASEBOARD_FAB2_LIB.BASEBOARD_FAB2(SCH_1):TP_ADC128_VREF
    2  SMB_SENSOR_PCH_STBY_LVC3_SDA    SDA  @BASEBOARD_FAB2_LIB.BASEBOARD_FAB2(SCH_1):SMB_SENSOR_PCH_STBY_LVC3_SDA
    3  SMB_SENSOR_PCH_STBY_LVC3_SCL    SCL  @BASEBOARD_FAB2_LIB.BASEBOARD_FAB2(SCH_1):SMB_SENSOR_PCH_STBY_LVC3_SCL
    5  P3V3_FB_ADC128_VCC     VP  @BASEBOARD_FAB2_LIB.BASEBOARD_FAB2(SCH_1):P3V3_FB_ADC128_VCC
    6  IRQ_VM_INT_R_N  INT_N  @BASEBOARD_FAB2_LIB.BASEBOARD_FAB2(SCH_1):IRQ_VM_INT_R_N
    4  GND              GND  @BASEBOARD_FAB2_LIB.BASEBOARD_FAB2(SCH_1):GND
    8  FM_ADC128_A1      A1  @BASEBOARD_FAB2_LIB.BASEBOARD_FAB2(SCH_1):FM_ADC128_A1
    7  FM_ADC128_A0      A0  @BASEBOARD_FAB2_LIB.BASEBOARD_FAB2(SCH_1):FM_ADC128_A0
   12  A_PVNN_STBY_PCH_SENSOR    IN4  @BASEBOARD_FAB2_LIB.BASEBOARD_FAB2(SCH_1):A_PVNN_STBY_PCH_SENSOR
   10  A_P5V_STBY_SCALED    IN6  @BASEBOARD_FAB2_LIB.BASEBOARD_FAB2(SCH_1):A_P5V_STBY_SCALED
   15  A_P5V_SCALED     IN1  @BASEBOARD_FAB2_LIB.BASEBOARD_FAB2(SCH_1):A_P5V_SCALED
    9  A_P3V_BAT_SCALED    IN7  @BASEBOARD_FAB2_LIB.BASEBOARD_FAB2(SCH_1):A_P3V_BAT_SCALED
   11  A_P3V3_STBY_SCALED    IN5  @BASEBOARD_FAB2_LIB.BASEBOARD_FAB2(SCH_1):A_P3V3_STBY_SCALED
   16  A_P3V3_SCALED    IN0  @BASEBOARD_FAB2_LIB.BASEBOARD_FAB2(SCH_1):A_P3V3_SCALED
   13  A_P1V05_STBY_PCH_SENSOR    IN3  @BASEBOARD_FAB2_LIB.BASEBOARD_FAB2(SCH_1):A_P1V05_STBY_PCH_SENSOR
   14  A_P12V_STBY_SCALED    IN2  @BASEBOARD_FAB2_LIB.BASEBOARD_FAB2(SCH_1):A_P12V_STBY_SCALED

SLG55021_SM  I69  EU9M1  [SLG55021_SM-IC,G56246-001]
    8  TP_SLG55021_P12V_FAN_8     PG  @BASEBOARD_FAB2_LIB.BASEBOARD_FAB2(SCH_1):TP_SLG55021_P12V_FAN_8
    1  P5V_STBY         VCC  @BASEBOARD_FAB2_LIB.BASEBOARD_FAB2(SCH_1):P5V_STBY
    3  P5V_STBY       SHDN_N  @BASEBOARD_FAB2_LIB.BASEBOARD_FAB2(SCH_1):P5V_STBY
    5  P12V_STBY          D  @BASEBOARD_FAB2_LIB.BASEBOARD_FAB2(SCH_1):P12V_STBY
    7  P12V_FAN_SWITCH_G      G  @BASEBOARD_FAB2_LIB.BASEBOARD_FAB2(SCH_1):P12V_FAN_SWITCH_G
    6  P12V_FAN           S  @BASEBOARD_FAB2_LIB.BASEBOARD_FAB2(SCH_1):P12V_FAN
    9  GND            THPAD  @BASEBOARD_FAB2_LIB.BASEBOARD_FAB2(SCH_1):GND
    4  GND              GND  @BASEBOARD_FAB2_LIB.BASEBOARD_FAB2(SCH_1):GND
    2  FM_ENABLE_FAN_POWER     ON  @BASEBOARD_FAB2_LIB.BASEBOARD_FAB2(SCH_1):FM_ENABLE_FAN_POWER

MOSFETN_1D3S_SOT5  I57  EU9R1  [MOSFETN_1D3S_SOT5-IC,G68777-001]
    3  P12V_STBY         S3  @BASEBOARD_FAB2_LIB.BASEBOARD_FAB2(SCH_1):P12V_STBY
    2  P12V_STBY         S2  @BASEBOARD_FAB2_LIB.BASEBOARD_FAB2(SCH_1):P12V_STBY
    1  P12V_STBY         S1  @BASEBOARD_FAB2_LIB.BASEBOARD_FAB2(SCH_1):P12V_STBY
    5  P12V_MB0_SW        D  @BASEBOARD_FAB2_LIB.BASEBOARD_FAB2(SCH_1):P12V_MB0_SW
    4  A_HSC_GATE2_R      G  @BASEBOARD_FAB2_LIB.BASEBOARD_FAB2(SCH_1):A_HSC_GATE2_R

FUSE_SMT  I129  F1L1   [FUSE_SMT-IC,H45581-001]
    2  P5V_STBY_DGB_FS   B<0>  @BASEBOARD_FAB2_LIB.BASEBOARD_FAB2(SCH_1):P5V_STBY_DGB_FS
    1  P5V_STBY_DBG    A<0>  @BASEBOARD_FAB2_LIB.BASEBOARD_FAB2(SCH_1):P5V_STBY_DBG

FUSE  I41  F8B1   [FUSE_SMLF-IC,C94311-006]
    2  P5V_HDD_SATA    B<0>  @BASEBOARD_FAB2_LIB.BASEBOARD_FAB2(SCH_1):P5V_HDD_SATA
    1  P5V             A<0>  @BASEBOARD_FAB2_LIB.BASEBOARD_FAB2(SCH_1):P5V

FUSE_SM  I38  F9B1   [FUSE_SM-IC,C94311-016]
    2  P12V_HDD_SATA   B<0>  @BASEBOARD_FAB2_LIB.BASEBOARD_FAB2(SCH_1):P12V_HDD_SATA
    1  P12V            A<0>  @BASEBOARD_FAB2_LIB.BASEBOARD_FAB2(SCH_1):P12V

FERRITE  I153  FB1T1  [FERRITE_SMLF-300,EMPTY,693286-A]
    1  P1V8_PCH_STBY      A  @BASEBOARD_FAB2_LIB.BASEBOARD_FAB2(SCH_1):P1V8_PCH_STBY
    2  P1V8_BMC_STBY_PCIE      B  @BASEBOARD_FAB2_LIB.BASEBOARD_FAB2(SCH_1):P1V8_BMC_STBY_PCIE

FERRITE  I122  FB1T2  [FERRITE_SMLF-300,FB,693286-046]
    2  P3V3_STBY_BMC_HPLLAV33      B  @BASEBOARD_FAB2_LIB.BASEBOARD_FAB2(SCH_1):P3V3_STBY_BMC_HPLLAV33
    1  P3V3_STBY          A  @BASEBOARD_FAB2_LIB.BASEBOARD_FAB2(SCH_1):P3V3_STBY

FERRITE  I140  FB1U1  [FERRITE_SMLF-300,FB,693286-046]
    2  P3V3_STBY_BMC_ADCAV33      B  @BASEBOARD_FAB2_LIB.BASEBOARD_FAB2(SCH_1):P3V3_STBY_BMC_ADCAV33
    1  P3V3_STBY          A  @BASEBOARD_FAB2_LIB.BASEBOARD_FAB2(SCH_1):P3V3_STBY

FERRITE  I79  FB1U2  [FERRITE_SMLF-60,FB,693286-001]
    1  P3V3_STBY          A  @BASEBOARD_FAB2_LIB.BASEBOARD_FAB2(SCH_1):P3V3_STBY
    2  P3V3_FB_ADC128_VCC      B  @BASEBOARD_FAB2_LIB.BASEBOARD_FAB2(SCH_1):P3V3_FB_ADC128_VCC

FERRITE  I57  FB1U3  [FERRITE_SMLF-30,FB,693286-021]
    2  P1V05_PCH_STBY      B  @BASEBOARD_FAB2_LIB.BASEBOARD_FAB2(SCH_1):P1V05_PCH_STBY
    1  A_P1V05_STBY_PCH_SENSOR      A  @BASEBOARD_FAB2_LIB.BASEBOARD_FAB2(SCH_1):A_P1V05_STBY_PCH_SENSOR

FERRITE  I155  FB1U4  [FERRITE_SMLF-30,FB,693286-021]
    2  PVNN_PCH_STBY      B  @BASEBOARD_FAB2_LIB.BASEBOARD_FAB2(SCH_1):PVNN_PCH_STBY
    1  A_PVNN_STBY_PCH_SENSOR      A  @BASEBOARD_FAB2_LIB.BASEBOARD_FAB2(SCH_1):A_PVNN_STBY_PCH_SENSOR

FERRITE_SM  I46  FB2M1  [FERRITE_SM-120,FB,693286-027]
    2  P1V05_PCH_STBY_WM20_PLL      B  @BASEBOARD_FAB2_LIB.BASEBOARD_FAB2(SCH_1):P1V05_PCH_STBY_WM20_PLL
    1  P1V05_PCH_STBY      A  @BASEBOARD_FAB2_LIB.BASEBOARD_FAB2(SCH_1):P1V05_PCH_STBY

FERRITE_SM  I69  FB2M2  [FERRITE_SM-120,FB,693286-027]
    2  P1V05_PCH_STBY_WM26_PLL      B  @BASEBOARD_FAB2_LIB.BASEBOARD_FAB2(SCH_1):P1V05_PCH_STBY_WM26_PLL
    1  P1V05_PCH_STBY      A  @BASEBOARD_FAB2_LIB.BASEBOARD_FAB2(SCH_1):P1V05_PCH_STBY

FERRITE  I163  FB2T1  [FERRITE_SMLF-300,EMPTY,693286-A]
    1  P1V8_PCH_STBY      A  @BASEBOARD_FAB2_LIB.BASEBOARD_FAB2(SCH_1):P1V8_PCH_STBY
    2  P1V8_BMC_STBY_PCIEA      B  @BASEBOARD_FAB2_LIB.BASEBOARD_FAB2(SCH_1):P1V8_BMC_STBY_PCIEA

FERRITE  I114  FB2T2  [FERRITE_SMLF-600,FB,656554-043]
    2  P3V3_STBY_MNG      B  @BASEBOARD_FAB2_LIB.BASEBOARD_FAB2(SCH_1):P3V3_STBY_MNG
    1  P3V3_STBY          A  @BASEBOARD_FAB2_LIB.BASEBOARD_FAB2(SCH_1):P3V3_STBY

FERRITE_SM  I8   FB3M1  [FERRITE_SM-120,FB,693286-027]
    2  P1V05_PCH_STBY_VCCA_PLL1      B  @BASEBOARD_FAB2_LIB.BASEBOARD_FAB2(SCH_1):P1V05_PCH_STBY_VCCA_PLL1
    1  P1V05_PCH_STBY      A  @BASEBOARD_FAB2_LIB.BASEBOARD_FAB2(SCH_1):P1V05_PCH_STBY

FERRITE_SM  I17  FB3M2  [FERRITE_SM-120,FB,693286-027]
    2  P1V05_PCH_STBY_VCCA_PLL0      B  @BASEBOARD_FAB2_LIB.BASEBOARD_FAB2(SCH_1):P1V05_PCH_STBY_VCCA_PLL0
    1  P1V05_PCH_STBY      A  @BASEBOARD_FAB2_LIB.BASEBOARD_FAB2(SCH_1):P1V05_PCH_STBY

FERRITE_SM  I26  FB3M3  [FERRITE_SM-120,FB,693286-027]
    2  P1V05_PCH_STBY_VCCA_XTAL      B  @BASEBOARD_FAB2_LIB.BASEBOARD_FAB2(SCH_1):P1V05_PCH_STBY_VCCA_XTAL
    1  P1V05_PCH_STBY      A  @BASEBOARD_FAB2_LIB.BASEBOARD_FAB2(SCH_1):P1V05_PCH_STBY

FERRITE_SM  I56  FB3M4  [FERRITE_SM-120,FB,693286-027]
    2  P1V05_PCH_STBY_ISCLK_PLL      B  @BASEBOARD_FAB2_LIB.BASEBOARD_FAB2(SCH_1):P1V05_PCH_STBY_ISCLK_PLL
    1  P1V05_PCH_STBY      A  @BASEBOARD_FAB2_LIB.BASEBOARD_FAB2(SCH_1):P1V05_PCH_STBY

FERRITE_SM  I154  FB4A1  [FERRITE_SM-22,FB,656554-051]
    2  VR_FET_SW_P12V_STBY_PVPP_KLM      B  @BASEBOARD_FAB2_LIB.BASEBOARD_FAB2(SCH_1):VR_FET_SW_P12V_STBY_PVPP_KLM
    1  P12V_STBY          A  @BASEBOARD_FAB2_LIB.BASEBOARD_FAB2(SCH_1):P12V_STBY

FERRITE_SM  I198  FB4G1  [FERRITE_SM-22,FB,656554-051]
    2  VR_FET_SW_P12V_STBY_PVPP_GHJ      B  @BASEBOARD_FAB2_LIB.BASEBOARD_FAB2(SCH_1):VR_FET_SW_P12V_STBY_PVPP_GHJ
    1  P12V_STBY          A  @BASEBOARD_FAB2_LIB.BASEBOARD_FAB2(SCH_1):P12V_STBY

FERRITE  I8   FB6P1  [FERRITE_SMLF-600,FB,656554-043]
    2  P3V3_DB1200        B  @BASEBOARD_FAB2_LIB.BASEBOARD_FAB2(SCH_1):P3V3_DB1200
    1  P3V3               A  @BASEBOARD_FAB2_LIB.BASEBOARD_FAB2(SCH_1):P3V3

FERRITE_SM  I200  FB7B1  [FERRITE_SM-22,FB,656554-051]
    2  VR_FET_SW_P12V_STBY_PVPP_DEF      B  @BASEBOARD_FAB2_LIB.BASEBOARD_FAB2(SCH_1):VR_FET_SW_P12V_STBY_PVPP_DEF
    1  P12V_STBY          A  @BASEBOARD_FAB2_LIB.BASEBOARD_FAB2(SCH_1):P12V_STBY

FERRITE_SM  I82  FB7E1  [FERRITE_SM-22,FB,656554-051]
    2  VR_FET_SW_P5V_STBY_PVIN      B  @BASEBOARD_FAB2_LIB.BASEBOARD_FAB2(SCH_1):VR_FET_SW_P5V_STBY_PVIN
    1  P12V_STBY          A  @BASEBOARD_FAB2_LIB.BASEBOARD_FAB2(SCH_1):P12V_STBY

FERRITE_SM  I162  FB7F1  [FERRITE_SM-22,FB,656554-051]
    2  VR_FET_SW_P12V_STBY_PVPP_ABC      B  @BASEBOARD_FAB2_LIB.BASEBOARD_FAB2(SCH_1):VR_FET_SW_P12V_STBY_PVPP_ABC
    1  P12V_STBY          A  @BASEBOARD_FAB2_LIB.BASEBOARD_FAB2(SCH_1):P12V_STBY

FERRITE_SM  I132  FB9E1  [FERRITE_SM-22,FB,656554-051]
    2  VR_FET_SW_P12V_STBY_P3V3_STBY      B  @BASEBOARD_FAB2_LIB.BASEBOARD_FAB2(SCH_1):VR_FET_SW_P12V_STBY_P3V3_STBY
    1  P12V_STBY          A  @BASEBOARD_FAB2_LIB.BASEBOARD_FAB2(SCH_1):P12V_STBY

FERRITE  I107  FB9F1  [FERRITE_SMLF-300,FB,693286-046]
    2  P1V26_BMC_STBY_V1PLLAV12      B  @BASEBOARD_FAB2_LIB.BASEBOARD_FAB2(SCH_1):P1V26_BMC_STBY_V1PLLAV12
    1  P1V26_BMC_STBY      A  @BASEBOARD_FAB2_LIB.BASEBOARD_FAB2(SCH_1):P1V26_BMC_STBY

SCONN288_H44441004_PIP  I169  J1A1   [SCONN288_H44441004_PIP-SCONN,HA]
   77  PVTT_KLM       VTT<1>  @BASEBOARD_FAB2_LIB.BASEBOARD_FAB2(SCH_1):PVTT_KLM
  221  PVTT_KLM       VTT<0>  @BASEBOARD_FAB2_LIB.BASEBOARD_FAB2(SCH_1):PVTT_KLM
  142  PVPP_KLM       VPP<4>  @BASEBOARD_FAB2_LIB.BASEBOARD_FAB2(SCH_1):PVPP_KLM
  143  PVPP_KLM       VPP<3>  @BASEBOARD_FAB2_LIB.BASEBOARD_FAB2(SCH_1):PVPP_KLM
  288  PVPP_KLM       VPP<2>  @BASEBOARD_FAB2_LIB.BASEBOARD_FAB2(SCH_1):PVPP_KLM
  286  PVPP_KLM       VPP<1>  @BASEBOARD_FAB2_LIB.BASEBOARD_FAB2(SCH_1):PVPP_KLM
  287  PVPP_KLM       VPP<0>  @BASEBOARD_FAB2_LIB.BASEBOARD_FAB2(SCH_1):PVPP_KLM
   59  PVDDQ_KLM      VDD<25>  @BASEBOARD_FAB2_LIB.BASEBOARD_FAB2(SCH_1):PVDDQ_KLM
   61  PVDDQ_KLM      VDD<24>  @BASEBOARD_FAB2_LIB.BASEBOARD_FAB2(SCH_1):PVDDQ_KLM
   64  PVDDQ_KLM      VDD<23>  @BASEBOARD_FAB2_LIB.BASEBOARD_FAB2(SCH_1):PVDDQ_KLM
   67  PVDDQ_KLM      VDD<22>  @BASEBOARD_FAB2_LIB.BASEBOARD_FAB2(SCH_1):PVDDQ_KLM
   70  PVDDQ_KLM      VDD<21>  @BASEBOARD_FAB2_LIB.BASEBOARD_FAB2(SCH_1):PVDDQ_KLM
   73  PVDDQ_KLM      VDD<20>  @BASEBOARD_FAB2_LIB.BASEBOARD_FAB2(SCH_1):PVDDQ_KLM
   76  PVDDQ_KLM      VDD<19>  @BASEBOARD_FAB2_LIB.BASEBOARD_FAB2(SCH_1):PVDDQ_KLM
   80  PVDDQ_KLM      VDD<18>  @BASEBOARD_FAB2_LIB.BASEBOARD_FAB2(SCH_1):PVDDQ_KLM
   83  PVDDQ_KLM      VDD<17>  @BASEBOARD_FAB2_LIB.BASEBOARD_FAB2(SCH_1):PVDDQ_KLM
   85  PVDDQ_KLM      VDD<16>  @BASEBOARD_FAB2_LIB.BASEBOARD_FAB2(SCH_1):PVDDQ_KLM
   88  PVDDQ_KLM      VDD<15>  @BASEBOARD_FAB2_LIB.BASEBOARD_FAB2(SCH_1):PVDDQ_KLM
   90  PVDDQ_KLM      VDD<14>  @BASEBOARD_FAB2_LIB.BASEBOARD_FAB2(SCH_1):PVDDQ_KLM
   92  PVDDQ_KLM      VDD<13>  @BASEBOARD_FAB2_LIB.BASEBOARD_FAB2(SCH_1):PVDDQ_KLM
  204  PVDDQ_KLM      VDD<12>  @BASEBOARD_FAB2_LIB.BASEBOARD_FAB2(SCH_1):PVDDQ_KLM
  206  PVDDQ_KLM      VDD<11>  @BASEBOARD_FAB2_LIB.BASEBOARD_FAB2(SCH_1):PVDDQ_KLM
  209  PVDDQ_KLM      VDD<10>  @BASEBOARD_FAB2_LIB.BASEBOARD_FAB2(SCH_1):PVDDQ_KLM
  212  PVDDQ_KLM      VDD<9>  @BASEBOARD_FAB2_LIB.BASEBOARD_FAB2(SCH_1):PVDDQ_KLM
  215  PVDDQ_KLM      VDD<8>  @BASEBOARD_FAB2_LIB.BASEBOARD_FAB2(SCH_1):PVDDQ_KLM
  217  PVDDQ_KLM      VDD<7>  @BASEBOARD_FAB2_LIB.BASEBOARD_FAB2(SCH_1):PVDDQ_KLM
  220  PVDDQ_KLM      VDD<6>  @BASEBOARD_FAB2_LIB.BASEBOARD_FAB2(SCH_1):PVDDQ_KLM
  223  PVDDQ_KLM      VDD<5>  @BASEBOARD_FAB2_LIB.BASEBOARD_FAB2(SCH_1):PVDDQ_KLM
  226  PVDDQ_KLM      VDD<4>  @BASEBOARD_FAB2_LIB.BASEBOARD_FAB2(SCH_1):PVDDQ_KLM
  229  PVDDQ_KLM      VDD<3>  @BASEBOARD_FAB2_LIB.BASEBOARD_FAB2(SCH_1):PVDDQ_KLM
  231  PVDDQ_KLM      VDD<2>  @BASEBOARD_FAB2_LIB.BASEBOARD_FAB2(SCH_1):PVDDQ_KLM
  233  PVDDQ_KLM      VDD<1>  @BASEBOARD_FAB2_LIB.BASEBOARD_FAB2(SCH_1):PVDDQ_KLM
  236  PVDDQ_KLM      VDD<0>  @BASEBOARD_FAB2_LIB.BASEBOARD_FAB2(SCH_1):PVDDQ_KLM
    1  P12V_NVDIMM_KLM  12V<1>  @BASEBOARD_FAB2_LIB.BASEBOARD_FAB2(SCH_1):P12V_NVDIMM_KLM
  145  P12V_NVDIMM_KLM  12V<0>  @BASEBOARD_FAB2_LIB.BASEBOARD_FAB2(SCH_1):P12V_NVDIMM_KLM

SCONN288_H44441004_PIP  I185  J1A1   [SCONN288_H44441004_PIP-SCONN,HA]
    2  GND            VSS<93>  @BASEBOARD_FAB2_LIB.BASEBOARD_FAB2(SCH_1):GND
    4  GND            VSS<92>  @BASEBOARD_FAB2_LIB.BASEBOARD_FAB2(SCH_1):GND
    6  GND            VSS<91>  @BASEBOARD_FAB2_LIB.BASEBOARD_FAB2(SCH_1):GND
    9  GND            VSS<90>  @BASEBOARD_FAB2_LIB.BASEBOARD_FAB2(SCH_1):GND
   11  GND            VSS<89>  @BASEBOARD_FAB2_LIB.BASEBOARD_FAB2(SCH_1):GND
   13  GND            VSS<88>  @BASEBOARD_FAB2_LIB.BASEBOARD_FAB2(SCH_1):GND
   15  GND            VSS<87>  @BASEBOARD_FAB2_LIB.BASEBOARD_FAB2(SCH_1):GND
   17  GND            VSS<86>  @BASEBOARD_FAB2_LIB.BASEBOARD_FAB2(SCH_1):GND
   20  GND            VSS<85>  @BASEBOARD_FAB2_LIB.BASEBOARD_FAB2(SCH_1):GND
   22  GND            VSS<84>  @BASEBOARD_FAB2_LIB.BASEBOARD_FAB2(SCH_1):GND
   24  GND            VSS<83>  @BASEBOARD_FAB2_LIB.BASEBOARD_FAB2(SCH_1):GND
   26  GND            VSS<82>  @BASEBOARD_FAB2_LIB.BASEBOARD_FAB2(SCH_1):GND
   28  GND            VSS<81>  @BASEBOARD_FAB2_LIB.BASEBOARD_FAB2(SCH_1):GND
   31  GND            VSS<80>  @BASEBOARD_FAB2_LIB.BASEBOARD_FAB2(SCH_1):GND
   33  GND            VSS<79>  @BASEBOARD_FAB2_LIB.BASEBOARD_FAB2(SCH_1):GND
   35  GND            VSS<78>  @BASEBOARD_FAB2_LIB.BASEBOARD_FAB2(SCH_1):GND
   37  GND            VSS<77>  @BASEBOARD_FAB2_LIB.BASEBOARD_FAB2(SCH_1):GND
   39  GND            VSS<76>  @BASEBOARD_FAB2_LIB.BASEBOARD_FAB2(SCH_1):GND
   42  GND            VSS<75>  @BASEBOARD_FAB2_LIB.BASEBOARD_FAB2(SCH_1):GND
   44  GND            VSS<74>  @BASEBOARD_FAB2_LIB.BASEBOARD_FAB2(SCH_1):GND
   46  GND            VSS<73>  @BASEBOARD_FAB2_LIB.BASEBOARD_FAB2(SCH_1):GND
   48  GND            VSS<72>  @BASEBOARD_FAB2_LIB.BASEBOARD_FAB2(SCH_1):GND
   50  GND            VSS<71>  @BASEBOARD_FAB2_LIB.BASEBOARD_FAB2(SCH_1):GND
   53  GND            VSS<70>  @BASEBOARD_FAB2_LIB.BASEBOARD_FAB2(SCH_1):GND
   55  GND            VSS<69>  @BASEBOARD_FAB2_LIB.BASEBOARD_FAB2(SCH_1):GND
   57  GND            VSS<68>  @BASEBOARD_FAB2_LIB.BASEBOARD_FAB2(SCH_1):GND
   94  GND            VSS<67>  @BASEBOARD_FAB2_LIB.BASEBOARD_FAB2(SCH_1):GND
   96  GND            VSS<66>  @BASEBOARD_FAB2_LIB.BASEBOARD_FAB2(SCH_1):GND
   98  GND            VSS<65>  @BASEBOARD_FAB2_LIB.BASEBOARD_FAB2(SCH_1):GND
  101  GND            VSS<64>  @BASEBOARD_FAB2_LIB.BASEBOARD_FAB2(SCH_1):GND
  103  GND            VSS<63>  @BASEBOARD_FAB2_LIB.BASEBOARD_FAB2(SCH_1):GND
  105  GND            VSS<62>  @BASEBOARD_FAB2_LIB.BASEBOARD_FAB2(SCH_1):GND
  107  GND            VSS<61>  @BASEBOARD_FAB2_LIB.BASEBOARD_FAB2(SCH_1):GND
  109  GND            VSS<60>  @BASEBOARD_FAB2_LIB.BASEBOARD_FAB2(SCH_1):GND
  112  GND            VSS<59>  @BASEBOARD_FAB2_LIB.BASEBOARD_FAB2(SCH_1):GND
  114  GND            VSS<58>  @BASEBOARD_FAB2_LIB.BASEBOARD_FAB2(SCH_1):GND
  116  GND            VSS<57>  @BASEBOARD_FAB2_LIB.BASEBOARD_FAB2(SCH_1):GND
  118  GND            VSS<56>  @BASEBOARD_FAB2_LIB.BASEBOARD_FAB2(SCH_1):GND
  120  GND            VSS<55>  @BASEBOARD_FAB2_LIB.BASEBOARD_FAB2(SCH_1):GND
  123  GND            VSS<54>  @BASEBOARD_FAB2_LIB.BASEBOARD_FAB2(SCH_1):GND
  125  GND            VSS<53>  @BASEBOARD_FAB2_LIB.BASEBOARD_FAB2(SCH_1):GND
  127  GND            VSS<52>  @BASEBOARD_FAB2_LIB.BASEBOARD_FAB2(SCH_1):GND
  129  GND            VSS<51>  @BASEBOARD_FAB2_LIB.BASEBOARD_FAB2(SCH_1):GND
  131  GND            VSS<50>  @BASEBOARD_FAB2_LIB.BASEBOARD_FAB2(SCH_1):GND
  134  GND            VSS<49>  @BASEBOARD_FAB2_LIB.BASEBOARD_FAB2(SCH_1):GND
  136  GND            VSS<48>  @BASEBOARD_FAB2_LIB.BASEBOARD_FAB2(SCH_1):GND
  138  GND            VSS<47>  @BASEBOARD_FAB2_LIB.BASEBOARD_FAB2(SCH_1):GND
  147  GND            VSS<46>  @BASEBOARD_FAB2_LIB.BASEBOARD_FAB2(SCH_1):GND
  149  GND            VSS<45>  @BASEBOARD_FAB2_LIB.BASEBOARD_FAB2(SCH_1):GND
  151  GND            VSS<44>  @BASEBOARD_FAB2_LIB.BASEBOARD_FAB2(SCH_1):GND
  154  GND            VSS<43>  @BASEBOARD_FAB2_LIB.BASEBOARD_FAB2(SCH_1):GND
  156  GND            VSS<42>  @BASEBOARD_FAB2_LIB.BASEBOARD_FAB2(SCH_1):GND
  158  GND            VSS<41>  @BASEBOARD_FAB2_LIB.BASEBOARD_FAB2(SCH_1):GND
  160  GND            VSS<40>  @BASEBOARD_FAB2_LIB.BASEBOARD_FAB2(SCH_1):GND
  162  GND            VSS<39>  @BASEBOARD_FAB2_LIB.BASEBOARD_FAB2(SCH_1):GND
  165  GND            VSS<38>  @BASEBOARD_FAB2_LIB.BASEBOARD_FAB2(SCH_1):GND
  167  GND            VSS<37>  @BASEBOARD_FAB2_LIB.BASEBOARD_FAB2(SCH_1):GND
  169  GND            VSS<36>  @BASEBOARD_FAB2_LIB.BASEBOARD_FAB2(SCH_1):GND
  171  GND            VSS<35>  @BASEBOARD_FAB2_LIB.BASEBOARD_FAB2(SCH_1):GND
  173  GND            VSS<34>  @BASEBOARD_FAB2_LIB.BASEBOARD_FAB2(SCH_1):GND
  176  GND            VSS<33>  @BASEBOARD_FAB2_LIB.BASEBOARD_FAB2(SCH_1):GND
  178  GND            VSS<32>  @BASEBOARD_FAB2_LIB.BASEBOARD_FAB2(SCH_1):GND
  180  GND            VSS<31>  @BASEBOARD_FAB2_LIB.BASEBOARD_FAB2(SCH_1):GND
  182  GND            VSS<30>  @BASEBOARD_FAB2_LIB.BASEBOARD_FAB2(SCH_1):GND
  184  GND            VSS<29>  @BASEBOARD_FAB2_LIB.BASEBOARD_FAB2(SCH_1):GND
  187  GND            VSS<28>  @BASEBOARD_FAB2_LIB.BASEBOARD_FAB2(SCH_1):GND
  189  GND            VSS<27>  @BASEBOARD_FAB2_LIB.BASEBOARD_FAB2(SCH_1):GND
  191  GND            VSS<26>  @BASEBOARD_FAB2_LIB.BASEBOARD_FAB2(SCH_1):GND
  193  GND            VSS<25>  @BASEBOARD_FAB2_LIB.BASEBOARD_FAB2(SCH_1):GND
  195  GND            VSS<24>  @BASEBOARD_FAB2_LIB.BASEBOARD_FAB2(SCH_1):GND
  198  GND            VSS<23>  @BASEBOARD_FAB2_LIB.BASEBOARD_FAB2(SCH_1):GND
  200  GND            VSS<22>  @BASEBOARD_FAB2_LIB.BASEBOARD_FAB2(SCH_1):GND
  202  GND            VSS<21>  @BASEBOARD_FAB2_LIB.BASEBOARD_FAB2(SCH_1):GND
  239  GND            VSS<20>  @BASEBOARD_FAB2_LIB.BASEBOARD_FAB2(SCH_1):GND
  241  GND            VSS<19>  @BASEBOARD_FAB2_LIB.BASEBOARD_FAB2(SCH_1):GND
  243  GND            VSS<18>  @BASEBOARD_FAB2_LIB.BASEBOARD_FAB2(SCH_1):GND
  246  GND            VSS<17>  @BASEBOARD_FAB2_LIB.BASEBOARD_FAB2(SCH_1):GND
  248  GND            VSS<16>  @BASEBOARD_FAB2_LIB.BASEBOARD_FAB2(SCH_1):GND
  250  GND            VSS<15>  @BASEBOARD_FAB2_LIB.BASEBOARD_FAB2(SCH_1):GND
  252  GND            VSS<14>  @BASEBOARD_FAB2_LIB.BASEBOARD_FAB2(SCH_1):GND
  254  GND            VSS<13>  @BASEBOARD_FAB2_LIB.BASEBOARD_FAB2(SCH_1):GND
  257  GND            VSS<12>  @BASEBOARD_FAB2_LIB.BASEBOARD_FAB2(SCH_1):GND
  259  GND            VSS<11>  @BASEBOARD_FAB2_LIB.BASEBOARD_FAB2(SCH_1):GND
  261  GND            VSS<10>  @BASEBOARD_FAB2_LIB.BASEBOARD_FAB2(SCH_1):GND
  263  GND            VSS<9>  @BASEBOARD_FAB2_LIB.BASEBOARD_FAB2(SCH_1):GND
  265  GND            VSS<8>  @BASEBOARD_FAB2_LIB.BASEBOARD_FAB2(SCH_1):GND
  268  GND            VSS<7>  @BASEBOARD_FAB2_LIB.BASEBOARD_FAB2(SCH_1):GND
  270  GND            VSS<6>  @BASEBOARD_FAB2_LIB.BASEBOARD_FAB2(SCH_1):GND
  272  GND            VSS<5>  @BASEBOARD_FAB2_LIB.BASEBOARD_FAB2(SCH_1):GND
  274  GND            VSS<4>  @BASEBOARD_FAB2_LIB.BASEBOARD_FAB2(SCH_1):GND
  276  GND            VSS<3>  @BASEBOARD_FAB2_LIB.BASEBOARD_FAB2(SCH_1):GND
  279  GND            VSS<2>  @BASEBOARD_FAB2_LIB.BASEBOARD_FAB2(SCH_1):GND
  281  GND            VSS<1>  @BASEBOARD_FAB2_LIB.BASEBOARD_FAB2(SCH_1):GND
  283  GND            VSS<0>  @BASEBOARD_FAB2_LIB.BASEBOARD_FAB2(SCH_1):GND

SCONN288_H44441004_PIP  I187  J1A1   [SCONN288_H44441004_PIP-SCONN,HA]
    7  M_M_DQS_DP<9>  DQS9P  @BASEBOARD_FAB2_LIB.BASEBOARD_FAB2(SCH_1):M_M_DQS_DP<9>
  197  M_M_DQS_DP<8>  DQS8P  @BASEBOARD_FAB2_LIB.BASEBOARD_FAB2(SCH_1):M_M_DQS_DP<8>
  278  M_M_DQS_DP<7>  DQS7P  @BASEBOARD_FAB2_LIB.BASEBOARD_FAB2(SCH_1):M_M_DQS_DP<7>
  267  M_M_DQS_DP<6>  DQS6P  @BASEBOARD_FAB2_LIB.BASEBOARD_FAB2(SCH_1):M_M_DQS_DP<6>
  256  M_M_DQS_DP<5>  DQS5P  @BASEBOARD_FAB2_LIB.BASEBOARD_FAB2(SCH_1):M_M_DQS_DP<5>
  245  M_M_DQS_DP<4>  DQS4P  @BASEBOARD_FAB2_LIB.BASEBOARD_FAB2(SCH_1):M_M_DQS_DP<4>
  186  M_M_DQS_DP<3>  DQS3P  @BASEBOARD_FAB2_LIB.BASEBOARD_FAB2(SCH_1):M_M_DQS_DP<3>
  175  M_M_DQS_DP<2>  DQS2P  @BASEBOARD_FAB2_LIB.BASEBOARD_FAB2(SCH_1):M_M_DQS_DP<2>
  164  M_M_DQS_DP<1>  DQS1P  @BASEBOARD_FAB2_LIB.BASEBOARD_FAB2(SCH_1):M_M_DQS_DP<1>
   51  M_M_DQS_DP<17>  DQS17P  @BASEBOARD_FAB2_LIB.BASEBOARD_FAB2(SCH_1):M_M_DQS_DP<17>
  132  M_M_DQS_DP<16>  DQS16P  @BASEBOARD_FAB2_LIB.BASEBOARD_FAB2(SCH_1):M_M_DQS_DP<16>
  121  M_M_DQS_DP<15>  DQS15P  @BASEBOARD_FAB2_LIB.BASEBOARD_FAB2(SCH_1):M_M_DQS_DP<15>
  110  M_M_DQS_DP<14>  DQS14P  @BASEBOARD_FAB2_LIB.BASEBOARD_FAB2(SCH_1):M_M_DQS_DP<14>
   99  M_M_DQS_DP<13>  DQS13P  @BASEBOARD_FAB2_LIB.BASEBOARD_FAB2(SCH_1):M_M_DQS_DP<13>
   40  M_M_DQS_DP<12>  DQS12P  @BASEBOARD_FAB2_LIB.BASEBOARD_FAB2(SCH_1):M_M_DQS_DP<12>
   29  M_M_DQS_DP<11>  DQS11P  @BASEBOARD_FAB2_LIB.BASEBOARD_FAB2(SCH_1):M_M_DQS_DP<11>
   18  M_M_DQS_DP<10>  DQS10P  @BASEBOARD_FAB2_LIB.BASEBOARD_FAB2(SCH_1):M_M_DQS_DP<10>
  153  M_M_DQS_DP<0>  DQS0P  @BASEBOARD_FAB2_LIB.BASEBOARD_FAB2(SCH_1):M_M_DQS_DP<0>
    8  M_M_DQS_DN<9>  DQS9N  @BASEBOARD_FAB2_LIB.BASEBOARD_FAB2(SCH_1):M_M_DQS_DN<9>
  196  M_M_DQS_DN<8>  DQS8N  @BASEBOARD_FAB2_LIB.BASEBOARD_FAB2(SCH_1):M_M_DQS_DN<8>
  277  M_M_DQS_DN<7>  DQS7N  @BASEBOARD_FAB2_LIB.BASEBOARD_FAB2(SCH_1):M_M_DQS_DN<7>
  266  M_M_DQS_DN<6>  DQS6N  @BASEBOARD_FAB2_LIB.BASEBOARD_FAB2(SCH_1):M_M_DQS_DN<6>
  255  M_M_DQS_DN<5>  DQS5N  @BASEBOARD_FAB2_LIB.BASEBOARD_FAB2(SCH_1):M_M_DQS_DN<5>
  244  M_M_DQS_DN<4>  DQS4N  @BASEBOARD_FAB2_LIB.BASEBOARD_FAB2(SCH_1):M_M_DQS_DN<4>
  185  M_M_DQS_DN<3>  DQS3N  @BASEBOARD_FAB2_LIB.BASEBOARD_FAB2(SCH_1):M_M_DQS_DN<3>
  174  M_M_DQS_DN<2>  DQS2N  @BASEBOARD_FAB2_LIB.BASEBOARD_FAB2(SCH_1):M_M_DQS_DN<2>
  163  M_M_DQS_DN<1>  DQS1N  @BASEBOARD_FAB2_LIB.BASEBOARD_FAB2(SCH_1):M_M_DQS_DN<1>
   52  M_M_DQS_DN<17>  DQS17N  @BASEBOARD_FAB2_LIB.BASEBOARD_FAB2(SCH_1):M_M_DQS_DN<17>
  133  M_M_DQS_DN<16>  DQS16N  @BASEBOARD_FAB2_LIB.BASEBOARD_FAB2(SCH_1):M_M_DQS_DN<16>
  122  M_M_DQS_DN<15>  DQS15N  @BASEBOARD_FAB2_LIB.BASEBOARD_FAB2(SCH_1):M_M_DQS_DN<15>
  111  M_M_DQS_DN<14>  DQS14N  @BASEBOARD_FAB2_LIB.BASEBOARD_FAB2(SCH_1):M_M_DQS_DN<14>
  100  M_M_DQS_DN<13>  DQS13N  @BASEBOARD_FAB2_LIB.BASEBOARD_FAB2(SCH_1):M_M_DQS_DN<13>
   41  M_M_DQS_DN<12>  DQS12N  @BASEBOARD_FAB2_LIB.BASEBOARD_FAB2(SCH_1):M_M_DQS_DN<12>
   30  M_M_DQS_DN<11>  DQS11N  @BASEBOARD_FAB2_LIB.BASEBOARD_FAB2(SCH_1):M_M_DQS_DN<11>
   19  M_M_DQS_DN<10>  DQS10N  @BASEBOARD_FAB2_LIB.BASEBOARD_FAB2(SCH_1):M_M_DQS_DN<10>
  152  M_M_DQS_DN<0>  DQS0N  @BASEBOARD_FAB2_LIB.BASEBOARD_FAB2(SCH_1):M_M_DQS_DN<0>

SCONN288_H44441004_PIP  I186  J1A1   [SCONN288_H44441004_PIP-SCONN,HA]
  144  TP_CH_M_DIMM_M0_RFU_2  RFU<2>  @BASEBOARD_FAB2_LIB.BASEBOARD_FAB2(SCH_1):TP_CH_M_DIMM_M0_RFU_2
  227  TP_CH_M_DIMM_M0_RFU_1  RFU<1>  @BASEBOARD_FAB2_LIB.BASEBOARD_FAB2(SCH_1):TP_CH_M_DIMM_M0_RFU_1
  205  TP_CH_M_DIMM_M0_RFU_0  RFU<0>  @BASEBOARD_FAB2_LIB.BASEBOARD_FAB2(SCH_1):TP_CH_M_DIMM_M0_RFU_0
  285  SMB_DDR_KLM_VPP_SDA    SDA  @BASEBOARD_FAB2_LIB.BASEBOARD_FAB2(SCH_1):SMB_DDR_KLM_VPP_SDA
  141  SMB_DDR_KLM_VPP_SCL    SCL  @BASEBOARD_FAB2_LIB.BASEBOARD_FAB2(SCH_1):SMB_DDR_KLM_VPP_SCL
  284  PVPP_KLM       VDDSPD  @BASEBOARD_FAB2_LIB.BASEBOARD_FAB2(SCH_1):PVPP_KLM
  238  PVPP_KLM       SA<2>  @BASEBOARD_FAB2_LIB.BASEBOARD_FAB2(SCH_1):PVPP_KLM
  146  M_M_VREF       VREFCA  @BASEBOARD_FAB2_LIB.BASEBOARD_FAB2(SCH_1):M_M_VREF
  222  M_M_PAR          PAR  @BASEBOARD_FAB2_LIB.BASEBOARD_FAB2(SCH_1):M_M_PAR
   91  M_M_ODT<1>     ODT<1>  @BASEBOARD_FAB2_LIB.BASEBOARD_FAB2(SCH_1):M_M_ODT<1>
   87  M_M_ODT<0>     ODT<0>  @BASEBOARD_FAB2_LIB.BASEBOARD_FAB2(SCH_1):M_M_ODT<0>
   66  M_M_MA<9>         A9  @BASEBOARD_FAB2_LIB.BASEBOARD_FAB2(SCH_1):M_M_MA<9>
   68  M_M_MA<8>         A8  @BASEBOARD_FAB2_LIB.BASEBOARD_FAB2(SCH_1):M_M_MA<8>
  211  M_M_MA<7>         A7  @BASEBOARD_FAB2_LIB.BASEBOARD_FAB2(SCH_1):M_M_MA<7>
   69  M_M_MA<6>         A6  @BASEBOARD_FAB2_LIB.BASEBOARD_FAB2(SCH_1):M_M_MA<6>
  213  M_M_MA<5>         A5  @BASEBOARD_FAB2_LIB.BASEBOARD_FAB2(SCH_1):M_M_MA<5>
  214  M_M_MA<4>         A4  @BASEBOARD_FAB2_LIB.BASEBOARD_FAB2(SCH_1):M_M_MA<4>
   71  M_M_MA<3>         A3  @BASEBOARD_FAB2_LIB.BASEBOARD_FAB2(SCH_1):M_M_MA<3>
  216  M_M_MA<2>         A2  @BASEBOARD_FAB2_LIB.BASEBOARD_FAB2(SCH_1):M_M_MA<2>
   72  M_M_MA<1>         A1  @BASEBOARD_FAB2_LIB.BASEBOARD_FAB2(SCH_1):M_M_MA<1>
  234  M_M_MA<17>       A17  @BASEBOARD_FAB2_LIB.BASEBOARD_FAB2(SCH_1):M_M_MA<17>
   82  M_M_MA<16>     A16_RAS_N  @BASEBOARD_FAB2_LIB.BASEBOARD_FAB2(SCH_1):M_M_MA<16>
   86  M_M_MA<15>     A15_CAS_N  @BASEBOARD_FAB2_LIB.BASEBOARD_FAB2(SCH_1):M_M_MA<15>
  228  M_M_MA<14>     A14_WE_N  @BASEBOARD_FAB2_LIB.BASEBOARD_FAB2(SCH_1):M_M_MA<14>
  232  M_M_MA<13>       A13  @BASEBOARD_FAB2_LIB.BASEBOARD_FAB2(SCH_1):M_M_MA<13>
   65  M_M_MA<12>       A12  @BASEBOARD_FAB2_LIB.BASEBOARD_FAB2(SCH_1):M_M_MA<12>
  210  M_M_MA<11>       A11  @BASEBOARD_FAB2_LIB.BASEBOARD_FAB2(SCH_1):M_M_MA<11>
  225  M_M_MA<10>       A10  @BASEBOARD_FAB2_LIB.BASEBOARD_FAB2(SCH_1):M_M_MA<10>
   79  M_M_MA<0>         A0  @BASEBOARD_FAB2_LIB.BASEBOARD_FAB2(SCH_1):M_M_MA<0>
   54  M_M_ECC<7>     CB<6>  @BASEBOARD_FAB2_LIB.BASEBOARD_FAB2(SCH_1):M_M_ECC<7>
  199  M_M_ECC<6>     CB<7>  @BASEBOARD_FAB2_LIB.BASEBOARD_FAB2(SCH_1):M_M_ECC<6>
   47  M_M_ECC<5>     CB<4>  @BASEBOARD_FAB2_LIB.BASEBOARD_FAB2(SCH_1):M_M_ECC<5>
  192  M_M_ECC<4>     CB<5>  @BASEBOARD_FAB2_LIB.BASEBOARD_FAB2(SCH_1):M_M_ECC<4>
   56  M_M_ECC<3>     CB<2>  @BASEBOARD_FAB2_LIB.BASEBOARD_FAB2(SCH_1):M_M_ECC<3>
  201  M_M_ECC<2>     CB<3>  @BASEBOARD_FAB2_LIB.BASEBOARD_FAB2(SCH_1):M_M_ECC<2>
   49  M_M_ECC<1>     CB<0>  @BASEBOARD_FAB2_LIB.BASEBOARD_FAB2(SCH_1):M_M_ECC<1>
  194  M_M_ECC<0>     CB<1>  @BASEBOARD_FAB2_LIB.BASEBOARD_FAB2(SCH_1):M_M_ECC<0>
   16  M_M_DQ<9>      DQ<8>  @BASEBOARD_FAB2_LIB.BASEBOARD_FAB2(SCH_1):M_M_DQ<9>
  161  M_M_DQ<8>      DQ<9>  @BASEBOARD_FAB2_LIB.BASEBOARD_FAB2(SCH_1):M_M_DQ<8>
   10  M_M_DQ<7>      DQ<6>  @BASEBOARD_FAB2_LIB.BASEBOARD_FAB2(SCH_1):M_M_DQ<7>
  155  M_M_DQ<6>      DQ<7>  @BASEBOARD_FAB2_LIB.BASEBOARD_FAB2(SCH_1):M_M_DQ<6>
  135  M_M_DQ<63>     DQ<62>  @BASEBOARD_FAB2_LIB.BASEBOARD_FAB2(SCH_1):M_M_DQ<63>
  280  M_M_DQ<62>     DQ<63>  @BASEBOARD_FAB2_LIB.BASEBOARD_FAB2(SCH_1):M_M_DQ<62>
  128  M_M_DQ<61>     DQ<60>  @BASEBOARD_FAB2_LIB.BASEBOARD_FAB2(SCH_1):M_M_DQ<61>
  273  M_M_DQ<60>     DQ<61>  @BASEBOARD_FAB2_LIB.BASEBOARD_FAB2(SCH_1):M_M_DQ<60>
    3  M_M_DQ<5>      DQ<4>  @BASEBOARD_FAB2_LIB.BASEBOARD_FAB2(SCH_1):M_M_DQ<5>
  137  M_M_DQ<59>     DQ<58>  @BASEBOARD_FAB2_LIB.BASEBOARD_FAB2(SCH_1):M_M_DQ<59>
  282  M_M_DQ<58>     DQ<59>  @BASEBOARD_FAB2_LIB.BASEBOARD_FAB2(SCH_1):M_M_DQ<58>
  130  M_M_DQ<57>     DQ<56>  @BASEBOARD_FAB2_LIB.BASEBOARD_FAB2(SCH_1):M_M_DQ<57>
  275  M_M_DQ<56>     DQ<57>  @BASEBOARD_FAB2_LIB.BASEBOARD_FAB2(SCH_1):M_M_DQ<56>
  124  M_M_DQ<55>     DQ<54>  @BASEBOARD_FAB2_LIB.BASEBOARD_FAB2(SCH_1):M_M_DQ<55>
  269  M_M_DQ<54>     DQ<55>  @BASEBOARD_FAB2_LIB.BASEBOARD_FAB2(SCH_1):M_M_DQ<54>
  117  M_M_DQ<53>     DQ<52>  @BASEBOARD_FAB2_LIB.BASEBOARD_FAB2(SCH_1):M_M_DQ<53>
  262  M_M_DQ<52>     DQ<53>  @BASEBOARD_FAB2_LIB.BASEBOARD_FAB2(SCH_1):M_M_DQ<52>
  126  M_M_DQ<51>     DQ<50>  @BASEBOARD_FAB2_LIB.BASEBOARD_FAB2(SCH_1):M_M_DQ<51>
  271  M_M_DQ<50>     DQ<51>  @BASEBOARD_FAB2_LIB.BASEBOARD_FAB2(SCH_1):M_M_DQ<50>
  148  M_M_DQ<4>      DQ<5>  @BASEBOARD_FAB2_LIB.BASEBOARD_FAB2(SCH_1):M_M_DQ<4>
  119  M_M_DQ<49>     DQ<48>  @BASEBOARD_FAB2_LIB.BASEBOARD_FAB2(SCH_1):M_M_DQ<49>
  264  M_M_DQ<48>     DQ<49>  @BASEBOARD_FAB2_LIB.BASEBOARD_FAB2(SCH_1):M_M_DQ<48>
  113  M_M_DQ<47>     DQ<46>  @BASEBOARD_FAB2_LIB.BASEBOARD_FAB2(SCH_1):M_M_DQ<47>
  258  M_M_DQ<46>     DQ<47>  @BASEBOARD_FAB2_LIB.BASEBOARD_FAB2(SCH_1):M_M_DQ<46>
  106  M_M_DQ<45>     DQ<44>  @BASEBOARD_FAB2_LIB.BASEBOARD_FAB2(SCH_1):M_M_DQ<45>
  251  M_M_DQ<44>     DQ<45>  @BASEBOARD_FAB2_LIB.BASEBOARD_FAB2(SCH_1):M_M_DQ<44>
  115  M_M_DQ<43>     DQ<42>  @BASEBOARD_FAB2_LIB.BASEBOARD_FAB2(SCH_1):M_M_DQ<43>
  260  M_M_DQ<42>     DQ<43>  @BASEBOARD_FAB2_LIB.BASEBOARD_FAB2(SCH_1):M_M_DQ<42>
  108  M_M_DQ<41>     DQ<40>  @BASEBOARD_FAB2_LIB.BASEBOARD_FAB2(SCH_1):M_M_DQ<41>
  253  M_M_DQ<40>     DQ<41>  @BASEBOARD_FAB2_LIB.BASEBOARD_FAB2(SCH_1):M_M_DQ<40>
   12  M_M_DQ<3>      DQ<2>  @BASEBOARD_FAB2_LIB.BASEBOARD_FAB2(SCH_1):M_M_DQ<3>
  102  M_M_DQ<39>     DQ<38>  @BASEBOARD_FAB2_LIB.BASEBOARD_FAB2(SCH_1):M_M_DQ<39>
  247  M_M_DQ<38>     DQ<39>  @BASEBOARD_FAB2_LIB.BASEBOARD_FAB2(SCH_1):M_M_DQ<38>
   95  M_M_DQ<37>     DQ<36>  @BASEBOARD_FAB2_LIB.BASEBOARD_FAB2(SCH_1):M_M_DQ<37>
  240  M_M_DQ<36>     DQ<37>  @BASEBOARD_FAB2_LIB.BASEBOARD_FAB2(SCH_1):M_M_DQ<36>
  104  M_M_DQ<35>     DQ<34>  @BASEBOARD_FAB2_LIB.BASEBOARD_FAB2(SCH_1):M_M_DQ<35>
  249  M_M_DQ<34>     DQ<35>  @BASEBOARD_FAB2_LIB.BASEBOARD_FAB2(SCH_1):M_M_DQ<34>
   97  M_M_DQ<33>     DQ<32>  @BASEBOARD_FAB2_LIB.BASEBOARD_FAB2(SCH_1):M_M_DQ<33>
  242  M_M_DQ<32>     DQ<33>  @BASEBOARD_FAB2_LIB.BASEBOARD_FAB2(SCH_1):M_M_DQ<32>
   43  M_M_DQ<31>     DQ<30>  @BASEBOARD_FAB2_LIB.BASEBOARD_FAB2(SCH_1):M_M_DQ<31>
  188  M_M_DQ<30>     DQ<31>  @BASEBOARD_FAB2_LIB.BASEBOARD_FAB2(SCH_1):M_M_DQ<30>
  157  M_M_DQ<2>      DQ<3>  @BASEBOARD_FAB2_LIB.BASEBOARD_FAB2(SCH_1):M_M_DQ<2>
   36  M_M_DQ<29>     DQ<28>  @BASEBOARD_FAB2_LIB.BASEBOARD_FAB2(SCH_1):M_M_DQ<29>
  181  M_M_DQ<28>     DQ<29>  @BASEBOARD_FAB2_LIB.BASEBOARD_FAB2(SCH_1):M_M_DQ<28>
   45  M_M_DQ<27>     DQ<26>  @BASEBOARD_FAB2_LIB.BASEBOARD_FAB2(SCH_1):M_M_DQ<27>
  190  M_M_DQ<26>     DQ<27>  @BASEBOARD_FAB2_LIB.BASEBOARD_FAB2(SCH_1):M_M_DQ<26>
   38  M_M_DQ<25>     DQ<24>  @BASEBOARD_FAB2_LIB.BASEBOARD_FAB2(SCH_1):M_M_DQ<25>
  183  M_M_DQ<24>     DQ<25>  @BASEBOARD_FAB2_LIB.BASEBOARD_FAB2(SCH_1):M_M_DQ<24>
   32  M_M_DQ<23>     DQ<22>  @BASEBOARD_FAB2_LIB.BASEBOARD_FAB2(SCH_1):M_M_DQ<23>
  177  M_M_DQ<22>     DQ<23>  @BASEBOARD_FAB2_LIB.BASEBOARD_FAB2(SCH_1):M_M_DQ<22>
   25  M_M_DQ<21>     DQ<20>  @BASEBOARD_FAB2_LIB.BASEBOARD_FAB2(SCH_1):M_M_DQ<21>
  170  M_M_DQ<20>     DQ<21>  @BASEBOARD_FAB2_LIB.BASEBOARD_FAB2(SCH_1):M_M_DQ<20>
    5  M_M_DQ<1>      DQ<0>  @BASEBOARD_FAB2_LIB.BASEBOARD_FAB2(SCH_1):M_M_DQ<1>
   34  M_M_DQ<19>     DQ<18>  @BASEBOARD_FAB2_LIB.BASEBOARD_FAB2(SCH_1):M_M_DQ<19>
  179  M_M_DQ<18>     DQ<19>  @BASEBOARD_FAB2_LIB.BASEBOARD_FAB2(SCH_1):M_M_DQ<18>
   27  M_M_DQ<17>     DQ<16>  @BASEBOARD_FAB2_LIB.BASEBOARD_FAB2(SCH_1):M_M_DQ<17>
  172  M_M_DQ<16>     DQ<17>  @BASEBOARD_FAB2_LIB.BASEBOARD_FAB2(SCH_1):M_M_DQ<16>
   21  M_M_DQ<15>     DQ<14>  @BASEBOARD_FAB2_LIB.BASEBOARD_FAB2(SCH_1):M_M_DQ<15>
  166  M_M_DQ<14>     DQ<15>  @BASEBOARD_FAB2_LIB.BASEBOARD_FAB2(SCH_1):M_M_DQ<14>
   14  M_M_DQ<13>     DQ<12>  @BASEBOARD_FAB2_LIB.BASEBOARD_FAB2(SCH_1):M_M_DQ<13>
  159  M_M_DQ<12>     DQ<13>  @BASEBOARD_FAB2_LIB.BASEBOARD_FAB2(SCH_1):M_M_DQ<12>
   23  M_M_DQ<11>     DQ<10>  @BASEBOARD_FAB2_LIB.BASEBOARD_FAB2(SCH_1):M_M_DQ<11>
  168  M_M_DQ<10>     DQ<11>  @BASEBOARD_FAB2_LIB.BASEBOARD_FAB2(SCH_1):M_M_DQ<10>
  150  M_M_DQ<0>      DQ<1>  @BASEBOARD_FAB2_LIB.BASEBOARD_FAB2(SCH_1):M_M_DQ<0>
  237  M_M_CS_N<3>    S3_N_C<1>  @BASEBOARD_FAB2_LIB.BASEBOARD_FAB2(SCH_1):M_M_CS_N<3>
   93  M_M_CS_N<2>    S2_N_C<0>  @BASEBOARD_FAB2_LIB.BASEBOARD_FAB2(SCH_1):M_M_CS_N<2>
   89  M_M_CS_N<1>     S1_N  @BASEBOARD_FAB2_LIB.BASEBOARD_FAB2(SCH_1):M_M_CS_N<1>
   84  M_M_CS_N<0>     S0_N  @BASEBOARD_FAB2_LIB.BASEBOARD_FAB2(SCH_1):M_M_CS_N<0>
  218  M_M_CLK_DP<1>   CK1P  @BASEBOARD_FAB2_LIB.BASEBOARD_FAB2(SCH_1):M_M_CLK_DP<1>
   74  M_M_CLK_DP<0>   CK0P  @BASEBOARD_FAB2_LIB.BASEBOARD_FAB2(SCH_1):M_M_CLK_DP<0>
  219  M_M_CLK_DN<1>   CK1N  @BASEBOARD_FAB2_LIB.BASEBOARD_FAB2(SCH_1):M_M_CLK_DN<1>
   75  M_M_CLK_DN<0>   CK0N  @BASEBOARD_FAB2_LIB.BASEBOARD_FAB2(SCH_1):M_M_CLK_DN<0>
  203  M_M_CKE<1>     CKE<1>  @BASEBOARD_FAB2_LIB.BASEBOARD_FAB2(SCH_1):M_M_CKE<1>
   60  M_M_CKE<0>     CKE<0>  @BASEBOARD_FAB2_LIB.BASEBOARD_FAB2(SCH_1):M_M_CKE<0>
  235  M_M_C<2>        C<2>  @BASEBOARD_FAB2_LIB.BASEBOARD_FAB2(SCH_1):M_M_C<2>
  207  M_M_BG<1>      BG<1>  @BASEBOARD_FAB2_LIB.BASEBOARD_FAB2(SCH_1):M_M_BG<1>
   63  M_M_BG<0>      BG<0>  @BASEBOARD_FAB2_LIB.BASEBOARD_FAB2(SCH_1):M_M_BG<0>
  224  M_M_BA<1>      BA<1>  @BASEBOARD_FAB2_LIB.BASEBOARD_FAB2(SCH_1):M_M_BA<1>
   81  M_M_BA<0>      BA<0>  @BASEBOARD_FAB2_LIB.BASEBOARD_FAB2(SCH_1):M_M_BA<0>
  208  M_M_ALERT_N    ALERT_N  @BASEBOARD_FAB2_LIB.BASEBOARD_FAB2(SCH_1):M_M_ALERT_N
   62  M_M_ACT_N      ACT_N  @BASEBOARD_FAB2_LIB.BASEBOARD_FAB2(SCH_1):M_M_ACT_N
   58  M_KLM_RST_N    RESET_N  @BASEBOARD_FAB2_LIB.BASEBOARD_FAB2(SCH_1):M_KLM_RST_N
  140  GND            SA<1>  @BASEBOARD_FAB2_LIB.BASEBOARD_FAB2(SCH_1):GND
  139  GND            SA<0>  @BASEBOARD_FAB2_LIB.BASEBOARD_FAB2(SCH_1):GND
   78  FM_DIMM_EVENT_COD_N  EVENT_N  @BASEBOARD_FAB2_LIB.BASEBOARD_FAB2(SCH_1):FM_DIMM_EVENT_COD_N
  230  FM_ADR_COMPLETE_KLM_N  SAVE_N_NC  @BASEBOARD_FAB2_LIB.BASEBOARD_FAB2(SCH_1):FM_ADR_COMPLETE_KLM_N

SCONN288_H44441004_PIP  I172  J1A2   [SCONN288_H44441004_PIP-SCONN,HA]
   77  PVTT_KLM       VTT<1>  @BASEBOARD_FAB2_LIB.BASEBOARD_FAB2(SCH_1):PVTT_KLM
  221  PVTT_KLM       VTT<0>  @BASEBOARD_FAB2_LIB.BASEBOARD_FAB2(SCH_1):PVTT_KLM
  142  PVPP_KLM       VPP<4>  @BASEBOARD_FAB2_LIB.BASEBOARD_FAB2(SCH_1):PVPP_KLM
  143  PVPP_KLM       VPP<3>  @BASEBOARD_FAB2_LIB.BASEBOARD_FAB2(SCH_1):PVPP_KLM
  288  PVPP_KLM       VPP<2>  @BASEBOARD_FAB2_LIB.BASEBOARD_FAB2(SCH_1):PVPP_KLM
  286  PVPP_KLM       VPP<1>  @BASEBOARD_FAB2_LIB.BASEBOARD_FAB2(SCH_1):PVPP_KLM
  287  PVPP_KLM       VPP<0>  @BASEBOARD_FAB2_LIB.BASEBOARD_FAB2(SCH_1):PVPP_KLM
   59  PVDDQ_KLM      VDD<25>  @BASEBOARD_FAB2_LIB.BASEBOARD_FAB2(SCH_1):PVDDQ_KLM
   61  PVDDQ_KLM      VDD<24>  @BASEBOARD_FAB2_LIB.BASEBOARD_FAB2(SCH_1):PVDDQ_KLM
   64  PVDDQ_KLM      VDD<23>  @BASEBOARD_FAB2_LIB.BASEBOARD_FAB2(SCH_1):PVDDQ_KLM
   67  PVDDQ_KLM      VDD<22>  @BASEBOARD_FAB2_LIB.BASEBOARD_FAB2(SCH_1):PVDDQ_KLM
   70  PVDDQ_KLM      VDD<21>  @BASEBOARD_FAB2_LIB.BASEBOARD_FAB2(SCH_1):PVDDQ_KLM
   73  PVDDQ_KLM      VDD<20>  @BASEBOARD_FAB2_LIB.BASEBOARD_FAB2(SCH_1):PVDDQ_KLM
   76  PVDDQ_KLM      VDD<19>  @BASEBOARD_FAB2_LIB.BASEBOARD_FAB2(SCH_1):PVDDQ_KLM
   80  PVDDQ_KLM      VDD<18>  @BASEBOARD_FAB2_LIB.BASEBOARD_FAB2(SCH_1):PVDDQ_KLM
   83  PVDDQ_KLM      VDD<17>  @BASEBOARD_FAB2_LIB.BASEBOARD_FAB2(SCH_1):PVDDQ_KLM
   85  PVDDQ_KLM      VDD<16>  @BASEBOARD_FAB2_LIB.BASEBOARD_FAB2(SCH_1):PVDDQ_KLM
   88  PVDDQ_KLM      VDD<15>  @BASEBOARD_FAB2_LIB.BASEBOARD_FAB2(SCH_1):PVDDQ_KLM
   90  PVDDQ_KLM      VDD<14>  @BASEBOARD_FAB2_LIB.BASEBOARD_FAB2(SCH_1):PVDDQ_KLM
   92  PVDDQ_KLM      VDD<13>  @BASEBOARD_FAB2_LIB.BASEBOARD_FAB2(SCH_1):PVDDQ_KLM
  204  PVDDQ_KLM      VDD<12>  @BASEBOARD_FAB2_LIB.BASEBOARD_FAB2(SCH_1):PVDDQ_KLM
  206  PVDDQ_KLM      VDD<11>  @BASEBOARD_FAB2_LIB.BASEBOARD_FAB2(SCH_1):PVDDQ_KLM
  209  PVDDQ_KLM      VDD<10>  @BASEBOARD_FAB2_LIB.BASEBOARD_FAB2(SCH_1):PVDDQ_KLM
  212  PVDDQ_KLM      VDD<9>  @BASEBOARD_FAB2_LIB.BASEBOARD_FAB2(SCH_1):PVDDQ_KLM
  215  PVDDQ_KLM      VDD<8>  @BASEBOARD_FAB2_LIB.BASEBOARD_FAB2(SCH_1):PVDDQ_KLM
  217  PVDDQ_KLM      VDD<7>  @BASEBOARD_FAB2_LIB.BASEBOARD_FAB2(SCH_1):PVDDQ_KLM
  220  PVDDQ_KLM      VDD<6>  @BASEBOARD_FAB2_LIB.BASEBOARD_FAB2(SCH_1):PVDDQ_KLM
  223  PVDDQ_KLM      VDD<5>  @BASEBOARD_FAB2_LIB.BASEBOARD_FAB2(SCH_1):PVDDQ_KLM
  226  PVDDQ_KLM      VDD<4>  @BASEBOARD_FAB2_LIB.BASEBOARD_FAB2(SCH_1):PVDDQ_KLM
  229  PVDDQ_KLM      VDD<3>  @BASEBOARD_FAB2_LIB.BASEBOARD_FAB2(SCH_1):PVDDQ_KLM
  231  PVDDQ_KLM      VDD<2>  @BASEBOARD_FAB2_LIB.BASEBOARD_FAB2(SCH_1):PVDDQ_KLM
  233  PVDDQ_KLM      VDD<1>  @BASEBOARD_FAB2_LIB.BASEBOARD_FAB2(SCH_1):PVDDQ_KLM
  236  PVDDQ_KLM      VDD<0>  @BASEBOARD_FAB2_LIB.BASEBOARD_FAB2(SCH_1):PVDDQ_KLM
    1  P12V_NVDIMM_KLM  12V<1>  @BASEBOARD_FAB2_LIB.BASEBOARD_FAB2(SCH_1):P12V_NVDIMM_KLM
  145  P12V_NVDIMM_KLM  12V<0>  @BASEBOARD_FAB2_LIB.BASEBOARD_FAB2(SCH_1):P12V_NVDIMM_KLM

SCONN288_H44441004_PIP  I43  J1A2   [SCONN288_H44441004_PIP-SCONN,HA]
    2  GND            VSS<93>  @BASEBOARD_FAB2_LIB.BASEBOARD_FAB2(SCH_1):GND
    4  GND            VSS<92>  @BASEBOARD_FAB2_LIB.BASEBOARD_FAB2(SCH_1):GND
    6  GND            VSS<91>  @BASEBOARD_FAB2_LIB.BASEBOARD_FAB2(SCH_1):GND
    9  GND            VSS<90>  @BASEBOARD_FAB2_LIB.BASEBOARD_FAB2(SCH_1):GND
   11  GND            VSS<89>  @BASEBOARD_FAB2_LIB.BASEBOARD_FAB2(SCH_1):GND
   13  GND            VSS<88>  @BASEBOARD_FAB2_LIB.BASEBOARD_FAB2(SCH_1):GND
   15  GND            VSS<87>  @BASEBOARD_FAB2_LIB.BASEBOARD_FAB2(SCH_1):GND
   17  GND            VSS<86>  @BASEBOARD_FAB2_LIB.BASEBOARD_FAB2(SCH_1):GND
   20  GND            VSS<85>  @BASEBOARD_FAB2_LIB.BASEBOARD_FAB2(SCH_1):GND
   22  GND            VSS<84>  @BASEBOARD_FAB2_LIB.BASEBOARD_FAB2(SCH_1):GND
   24  GND            VSS<83>  @BASEBOARD_FAB2_LIB.BASEBOARD_FAB2(SCH_1):GND
   26  GND            VSS<82>  @BASEBOARD_FAB2_LIB.BASEBOARD_FAB2(SCH_1):GND
   28  GND            VSS<81>  @BASEBOARD_FAB2_LIB.BASEBOARD_FAB2(SCH_1):GND
   31  GND            VSS<80>  @BASEBOARD_FAB2_LIB.BASEBOARD_FAB2(SCH_1):GND
   33  GND            VSS<79>  @BASEBOARD_FAB2_LIB.BASEBOARD_FAB2(SCH_1):GND
   35  GND            VSS<78>  @BASEBOARD_FAB2_LIB.BASEBOARD_FAB2(SCH_1):GND
   37  GND            VSS<77>  @BASEBOARD_FAB2_LIB.BASEBOARD_FAB2(SCH_1):GND
   39  GND            VSS<76>  @BASEBOARD_FAB2_LIB.BASEBOARD_FAB2(SCH_1):GND
   42  GND            VSS<75>  @BASEBOARD_FAB2_LIB.BASEBOARD_FAB2(SCH_1):GND
   44  GND            VSS<74>  @BASEBOARD_FAB2_LIB.BASEBOARD_FAB2(SCH_1):GND
   46  GND            VSS<73>  @BASEBOARD_FAB2_LIB.BASEBOARD_FAB2(SCH_1):GND
   48  GND            VSS<72>  @BASEBOARD_FAB2_LIB.BASEBOARD_FAB2(SCH_1):GND
   50  GND            VSS<71>  @BASEBOARD_FAB2_LIB.BASEBOARD_FAB2(SCH_1):GND
   53  GND            VSS<70>  @BASEBOARD_FAB2_LIB.BASEBOARD_FAB2(SCH_1):GND
   55  GND            VSS<69>  @BASEBOARD_FAB2_LIB.BASEBOARD_FAB2(SCH_1):GND
   57  GND            VSS<68>  @BASEBOARD_FAB2_LIB.BASEBOARD_FAB2(SCH_1):GND
   94  GND            VSS<67>  @BASEBOARD_FAB2_LIB.BASEBOARD_FAB2(SCH_1):GND
   96  GND            VSS<66>  @BASEBOARD_FAB2_LIB.BASEBOARD_FAB2(SCH_1):GND
   98  GND            VSS<65>  @BASEBOARD_FAB2_LIB.BASEBOARD_FAB2(SCH_1):GND
  101  GND            VSS<64>  @BASEBOARD_FAB2_LIB.BASEBOARD_FAB2(SCH_1):GND
  103  GND            VSS<63>  @BASEBOARD_FAB2_LIB.BASEBOARD_FAB2(SCH_1):GND
  105  GND            VSS<62>  @BASEBOARD_FAB2_LIB.BASEBOARD_FAB2(SCH_1):GND
  107  GND            VSS<61>  @BASEBOARD_FAB2_LIB.BASEBOARD_FAB2(SCH_1):GND
  109  GND            VSS<60>  @BASEBOARD_FAB2_LIB.BASEBOARD_FAB2(SCH_1):GND
  112  GND            VSS<59>  @BASEBOARD_FAB2_LIB.BASEBOARD_FAB2(SCH_1):GND
  114  GND            VSS<58>  @BASEBOARD_FAB2_LIB.BASEBOARD_FAB2(SCH_1):GND
  116  GND            VSS<57>  @BASEBOARD_FAB2_LIB.BASEBOARD_FAB2(SCH_1):GND
  118  GND            VSS<56>  @BASEBOARD_FAB2_LIB.BASEBOARD_FAB2(SCH_1):GND
  120  GND            VSS<55>  @BASEBOARD_FAB2_LIB.BASEBOARD_FAB2(SCH_1):GND
  123  GND            VSS<54>  @BASEBOARD_FAB2_LIB.BASEBOARD_FAB2(SCH_1):GND
  125  GND            VSS<53>  @BASEBOARD_FAB2_LIB.BASEBOARD_FAB2(SCH_1):GND
  127  GND            VSS<52>  @BASEBOARD_FAB2_LIB.BASEBOARD_FAB2(SCH_1):GND
  129  GND            VSS<51>  @BASEBOARD_FAB2_LIB.BASEBOARD_FAB2(SCH_1):GND
  131  GND            VSS<50>  @BASEBOARD_FAB2_LIB.BASEBOARD_FAB2(SCH_1):GND
  134  GND            VSS<49>  @BASEBOARD_FAB2_LIB.BASEBOARD_FAB2(SCH_1):GND
  136  GND            VSS<48>  @BASEBOARD_FAB2_LIB.BASEBOARD_FAB2(SCH_1):GND
  138  GND            VSS<47>  @BASEBOARD_FAB2_LIB.BASEBOARD_FAB2(SCH_1):GND
  147  GND            VSS<46>  @BASEBOARD_FAB2_LIB.BASEBOARD_FAB2(SCH_1):GND
  149  GND            VSS<45>  @BASEBOARD_FAB2_LIB.BASEBOARD_FAB2(SCH_1):GND
  151  GND            VSS<44>  @BASEBOARD_FAB2_LIB.BASEBOARD_FAB2(SCH_1):GND
  154  GND            VSS<43>  @BASEBOARD_FAB2_LIB.BASEBOARD_FAB2(SCH_1):GND
  156  GND            VSS<42>  @BASEBOARD_FAB2_LIB.BASEBOARD_FAB2(SCH_1):GND
  158  GND            VSS<41>  @BASEBOARD_FAB2_LIB.BASEBOARD_FAB2(SCH_1):GND
  160  GND            VSS<40>  @BASEBOARD_FAB2_LIB.BASEBOARD_FAB2(SCH_1):GND
  162  GND            VSS<39>  @BASEBOARD_FAB2_LIB.BASEBOARD_FAB2(SCH_1):GND
  165  GND            VSS<38>  @BASEBOARD_FAB2_LIB.BASEBOARD_FAB2(SCH_1):GND
  167  GND            VSS<37>  @BASEBOARD_FAB2_LIB.BASEBOARD_FAB2(SCH_1):GND
  169  GND            VSS<36>  @BASEBOARD_FAB2_LIB.BASEBOARD_FAB2(SCH_1):GND
  171  GND            VSS<35>  @BASEBOARD_FAB2_LIB.BASEBOARD_FAB2(SCH_1):GND
  173  GND            VSS<34>  @BASEBOARD_FAB2_LIB.BASEBOARD_FAB2(SCH_1):GND
  176  GND            VSS<33>  @BASEBOARD_FAB2_LIB.BASEBOARD_FAB2(SCH_1):GND
  178  GND            VSS<32>  @BASEBOARD_FAB2_LIB.BASEBOARD_FAB2(SCH_1):GND
  180  GND            VSS<31>  @BASEBOARD_FAB2_LIB.BASEBOARD_FAB2(SCH_1):GND
  182  GND            VSS<30>  @BASEBOARD_FAB2_LIB.BASEBOARD_FAB2(SCH_1):GND
  184  GND            VSS<29>  @BASEBOARD_FAB2_LIB.BASEBOARD_FAB2(SCH_1):GND
  187  GND            VSS<28>  @BASEBOARD_FAB2_LIB.BASEBOARD_FAB2(SCH_1):GND
  189  GND            VSS<27>  @BASEBOARD_FAB2_LIB.BASEBOARD_FAB2(SCH_1):GND
  191  GND            VSS<26>  @BASEBOARD_FAB2_LIB.BASEBOARD_FAB2(SCH_1):GND
  193  GND            VSS<25>  @BASEBOARD_FAB2_LIB.BASEBOARD_FAB2(SCH_1):GND
  195  GND            VSS<24>  @BASEBOARD_FAB2_LIB.BASEBOARD_FAB2(SCH_1):GND
  198  GND            VSS<23>  @BASEBOARD_FAB2_LIB.BASEBOARD_FAB2(SCH_1):GND
  200  GND            VSS<22>  @BASEBOARD_FAB2_LIB.BASEBOARD_FAB2(SCH_1):GND
  202  GND            VSS<21>  @BASEBOARD_FAB2_LIB.BASEBOARD_FAB2(SCH_1):GND
  239  GND            VSS<20>  @BASEBOARD_FAB2_LIB.BASEBOARD_FAB2(SCH_1):GND
  241  GND            VSS<19>  @BASEBOARD_FAB2_LIB.BASEBOARD_FAB2(SCH_1):GND
  243  GND            VSS<18>  @BASEBOARD_FAB2_LIB.BASEBOARD_FAB2(SCH_1):GND
  246  GND            VSS<17>  @BASEBOARD_FAB2_LIB.BASEBOARD_FAB2(SCH_1):GND
  248  GND            VSS<16>  @BASEBOARD_FAB2_LIB.BASEBOARD_FAB2(SCH_1):GND
  250  GND            VSS<15>  @BASEBOARD_FAB2_LIB.BASEBOARD_FAB2(SCH_1):GND
  252  GND            VSS<14>  @BASEBOARD_FAB2_LIB.BASEBOARD_FAB2(SCH_1):GND
  254  GND            VSS<13>  @BASEBOARD_FAB2_LIB.BASEBOARD_FAB2(SCH_1):GND
  257  GND            VSS<12>  @BASEBOARD_FAB2_LIB.BASEBOARD_FAB2(SCH_1):GND
  259  GND            VSS<11>  @BASEBOARD_FAB2_LIB.BASEBOARD_FAB2(SCH_1):GND
  261  GND            VSS<10>  @BASEBOARD_FAB2_LIB.BASEBOARD_FAB2(SCH_1):GND
  263  GND            VSS<9>  @BASEBOARD_FAB2_LIB.BASEBOARD_FAB2(SCH_1):GND
  265  GND            VSS<8>  @BASEBOARD_FAB2_LIB.BASEBOARD_FAB2(SCH_1):GND
  268  GND            VSS<7>  @BASEBOARD_FAB2_LIB.BASEBOARD_FAB2(SCH_1):GND
  270  GND            VSS<6>  @BASEBOARD_FAB2_LIB.BASEBOARD_FAB2(SCH_1):GND
  272  GND            VSS<5>  @BASEBOARD_FAB2_LIB.BASEBOARD_FAB2(SCH_1):GND
  274  GND            VSS<4>  @BASEBOARD_FAB2_LIB.BASEBOARD_FAB2(SCH_1):GND
  276  GND            VSS<3>  @BASEBOARD_FAB2_LIB.BASEBOARD_FAB2(SCH_1):GND
  279  GND            VSS<2>  @BASEBOARD_FAB2_LIB.BASEBOARD_FAB2(SCH_1):GND
  281  GND            VSS<1>  @BASEBOARD_FAB2_LIB.BASEBOARD_FAB2(SCH_1):GND
  283  GND            VSS<0>  @BASEBOARD_FAB2_LIB.BASEBOARD_FAB2(SCH_1):GND

SCONN288_H44441004_PIP  I66  J1A2   [SCONN288_H44441004_PIP-SCONN,HA]
    7  M_L_DQS_DP<9>  DQS9P  @BASEBOARD_FAB2_LIB.BASEBOARD_FAB2(SCH_1):M_L_DQS_DP<9>
  197  M_L_DQS_DP<8>  DQS8P  @BASEBOARD_FAB2_LIB.BASEBOARD_FAB2(SCH_1):M_L_DQS_DP<8>
  278  M_L_DQS_DP<7>  DQS7P  @BASEBOARD_FAB2_LIB.BASEBOARD_FAB2(SCH_1):M_L_DQS_DP<7>
  267  M_L_DQS_DP<6>  DQS6P  @BASEBOARD_FAB2_LIB.BASEBOARD_FAB2(SCH_1):M_L_DQS_DP<6>
  256  M_L_DQS_DP<5>  DQS5P  @BASEBOARD_FAB2_LIB.BASEBOARD_FAB2(SCH_1):M_L_DQS_DP<5>
  245  M_L_DQS_DP<4>  DQS4P  @BASEBOARD_FAB2_LIB.BASEBOARD_FAB2(SCH_1):M_L_DQS_DP<4>
  186  M_L_DQS_DP<3>  DQS3P  @BASEBOARD_FAB2_LIB.BASEBOARD_FAB2(SCH_1):M_L_DQS_DP<3>
  175  M_L_DQS_DP<2>  DQS2P  @BASEBOARD_FAB2_LIB.BASEBOARD_FAB2(SCH_1):M_L_DQS_DP<2>
  164  M_L_DQS_DP<1>  DQS1P  @BASEBOARD_FAB2_LIB.BASEBOARD_FAB2(SCH_1):M_L_DQS_DP<1>
   51  M_L_DQS_DP<17>  DQS17P  @BASEBOARD_FAB2_LIB.BASEBOARD_FAB2(SCH_1):M_L_DQS_DP<17>
  132  M_L_DQS_DP<16>  DQS16P  @BASEBOARD_FAB2_LIB.BASEBOARD_FAB2(SCH_1):M_L_DQS_DP<16>
  121  M_L_DQS_DP<15>  DQS15P  @BASEBOARD_FAB2_LIB.BASEBOARD_FAB2(SCH_1):M_L_DQS_DP<15>
  110  M_L_DQS_DP<14>  DQS14P  @BASEBOARD_FAB2_LIB.BASEBOARD_FAB2(SCH_1):M_L_DQS_DP<14>
   99  M_L_DQS_DP<13>  DQS13P  @BASEBOARD_FAB2_LIB.BASEBOARD_FAB2(SCH_1):M_L_DQS_DP<13>
   40  M_L_DQS_DP<12>  DQS12P  @BASEBOARD_FAB2_LIB.BASEBOARD_FAB2(SCH_1):M_L_DQS_DP<12>
   29  M_L_DQS_DP<11>  DQS11P  @BASEBOARD_FAB2_LIB.BASEBOARD_FAB2(SCH_1):M_L_DQS_DP<11>
   18  M_L_DQS_DP<10>  DQS10P  @BASEBOARD_FAB2_LIB.BASEBOARD_FAB2(SCH_1):M_L_DQS_DP<10>
  153  M_L_DQS_DP<0>  DQS0P  @BASEBOARD_FAB2_LIB.BASEBOARD_FAB2(SCH_1):M_L_DQS_DP<0>
    8  M_L_DQS_DN<9>  DQS9N  @BASEBOARD_FAB2_LIB.BASEBOARD_FAB2(SCH_1):M_L_DQS_DN<9>
  196  M_L_DQS_DN<8>  DQS8N  @BASEBOARD_FAB2_LIB.BASEBOARD_FAB2(SCH_1):M_L_DQS_DN<8>
  277  M_L_DQS_DN<7>  DQS7N  @BASEBOARD_FAB2_LIB.BASEBOARD_FAB2(SCH_1):M_L_DQS_DN<7>
  266  M_L_DQS_DN<6>  DQS6N  @BASEBOARD_FAB2_LIB.BASEBOARD_FAB2(SCH_1):M_L_DQS_DN<6>
  255  M_L_DQS_DN<5>  DQS5N  @BASEBOARD_FAB2_LIB.BASEBOARD_FAB2(SCH_1):M_L_DQS_DN<5>
  244  M_L_DQS_DN<4>  DQS4N  @BASEBOARD_FAB2_LIB.BASEBOARD_FAB2(SCH_1):M_L_DQS_DN<4>
  185  M_L_DQS_DN<3>  DQS3N  @BASEBOARD_FAB2_LIB.BASEBOARD_FAB2(SCH_1):M_L_DQS_DN<3>
  174  M_L_DQS_DN<2>  DQS2N  @BASEBOARD_FAB2_LIB.BASEBOARD_FAB2(SCH_1):M_L_DQS_DN<2>
  163  M_L_DQS_DN<1>  DQS1N  @BASEBOARD_FAB2_LIB.BASEBOARD_FAB2(SCH_1):M_L_DQS_DN<1>
   52  M_L_DQS_DN<17>  DQS17N  @BASEBOARD_FAB2_LIB.BASEBOARD_FAB2(SCH_1):M_L_DQS_DN<17>
  133  M_L_DQS_DN<16>  DQS16N  @BASEBOARD_FAB2_LIB.BASEBOARD_FAB2(SCH_1):M_L_DQS_DN<16>
  122  M_L_DQS_DN<15>  DQS15N  @BASEBOARD_FAB2_LIB.BASEBOARD_FAB2(SCH_1):M_L_DQS_DN<15>
  111  M_L_DQS_DN<14>  DQS14N  @BASEBOARD_FAB2_LIB.BASEBOARD_FAB2(SCH_1):M_L_DQS_DN<14>
  100  M_L_DQS_DN<13>  DQS13N  @BASEBOARD_FAB2_LIB.BASEBOARD_FAB2(SCH_1):M_L_DQS_DN<13>
   41  M_L_DQS_DN<12>  DQS12N  @BASEBOARD_FAB2_LIB.BASEBOARD_FAB2(SCH_1):M_L_DQS_DN<12>
   30  M_L_DQS_DN<11>  DQS11N  @BASEBOARD_FAB2_LIB.BASEBOARD_FAB2(SCH_1):M_L_DQS_DN<11>
   19  M_L_DQS_DN<10>  DQS10N  @BASEBOARD_FAB2_LIB.BASEBOARD_FAB2(SCH_1):M_L_DQS_DN<10>
  152  M_L_DQS_DN<0>  DQS0N  @BASEBOARD_FAB2_LIB.BASEBOARD_FAB2(SCH_1):M_L_DQS_DN<0>

SCONN288_H44441004_PIP  I111  J1A2   [SCONN288_H44441004_PIP-SCONN,HA]
  144  TP_CH_L_DIMM_L0_RFU_2  RFU<2>  @BASEBOARD_FAB2_LIB.BASEBOARD_FAB2(SCH_1):TP_CH_L_DIMM_L0_RFU_2
  227  TP_CH_L_DIMM_L0_RFU_1  RFU<1>  @BASEBOARD_FAB2_LIB.BASEBOARD_FAB2(SCH_1):TP_CH_L_DIMM_L0_RFU_1
  205  TP_CH_L_DIMM_L0_RFU_0  RFU<0>  @BASEBOARD_FAB2_LIB.BASEBOARD_FAB2(SCH_1):TP_CH_L_DIMM_L0_RFU_0
  285  SMB_DDR_KLM_VPP_SDA    SDA  @BASEBOARD_FAB2_LIB.BASEBOARD_FAB2(SCH_1):SMB_DDR_KLM_VPP_SDA
  141  SMB_DDR_KLM_VPP_SCL    SCL  @BASEBOARD_FAB2_LIB.BASEBOARD_FAB2(SCH_1):SMB_DDR_KLM_VPP_SCL
  284  PVPP_KLM       VDDSPD  @BASEBOARD_FAB2_LIB.BASEBOARD_FAB2(SCH_1):PVPP_KLM
  140  PVPP_KLM       SA<1>  @BASEBOARD_FAB2_LIB.BASEBOARD_FAB2(SCH_1):PVPP_KLM
  146  M_L_VREF       VREFCA  @BASEBOARD_FAB2_LIB.BASEBOARD_FAB2(SCH_1):M_L_VREF
  222  M_L_PAR          PAR  @BASEBOARD_FAB2_LIB.BASEBOARD_FAB2(SCH_1):M_L_PAR
   91  M_L_ODT<1>     ODT<1>  @BASEBOARD_FAB2_LIB.BASEBOARD_FAB2(SCH_1):M_L_ODT<1>
   87  M_L_ODT<0>     ODT<0>  @BASEBOARD_FAB2_LIB.BASEBOARD_FAB2(SCH_1):M_L_ODT<0>
   66  M_L_MA<9>         A9  @BASEBOARD_FAB2_LIB.BASEBOARD_FAB2(SCH_1):M_L_MA<9>
   68  M_L_MA<8>         A8  @BASEBOARD_FAB2_LIB.BASEBOARD_FAB2(SCH_1):M_L_MA<8>
  211  M_L_MA<7>         A7  @BASEBOARD_FAB2_LIB.BASEBOARD_FAB2(SCH_1):M_L_MA<7>
   69  M_L_MA<6>         A6  @BASEBOARD_FAB2_LIB.BASEBOARD_FAB2(SCH_1):M_L_MA<6>
  213  M_L_MA<5>         A5  @BASEBOARD_FAB2_LIB.BASEBOARD_FAB2(SCH_1):M_L_MA<5>
  214  M_L_MA<4>         A4  @BASEBOARD_FAB2_LIB.BASEBOARD_FAB2(SCH_1):M_L_MA<4>
   71  M_L_MA<3>         A3  @BASEBOARD_FAB2_LIB.BASEBOARD_FAB2(SCH_1):M_L_MA<3>
  216  M_L_MA<2>         A2  @BASEBOARD_FAB2_LIB.BASEBOARD_FAB2(SCH_1):M_L_MA<2>
   72  M_L_MA<1>         A1  @BASEBOARD_FAB2_LIB.BASEBOARD_FAB2(SCH_1):M_L_MA<1>
  234  M_L_MA<17>       A17  @BASEBOARD_FAB2_LIB.BASEBOARD_FAB2(SCH_1):M_L_MA<17>
   82  M_L_MA<16>     A16_RAS_N  @BASEBOARD_FAB2_LIB.BASEBOARD_FAB2(SCH_1):M_L_MA<16>
   86  M_L_MA<15>     A15_CAS_N  @BASEBOARD_FAB2_LIB.BASEBOARD_FAB2(SCH_1):M_L_MA<15>
  228  M_L_MA<14>     A14_WE_N  @BASEBOARD_FAB2_LIB.BASEBOARD_FAB2(SCH_1):M_L_MA<14>
  232  M_L_MA<13>       A13  @BASEBOARD_FAB2_LIB.BASEBOARD_FAB2(SCH_1):M_L_MA<13>
   65  M_L_MA<12>       A12  @BASEBOARD_FAB2_LIB.BASEBOARD_FAB2(SCH_1):M_L_MA<12>
  210  M_L_MA<11>       A11  @BASEBOARD_FAB2_LIB.BASEBOARD_FAB2(SCH_1):M_L_MA<11>
  225  M_L_MA<10>       A10  @BASEBOARD_FAB2_LIB.BASEBOARD_FAB2(SCH_1):M_L_MA<10>
   79  M_L_MA<0>         A0  @BASEBOARD_FAB2_LIB.BASEBOARD_FAB2(SCH_1):M_L_MA<0>
   54  M_L_ECC<7>     CB<6>  @BASEBOARD_FAB2_LIB.BASEBOARD_FAB2(SCH_1):M_L_ECC<7>
  199  M_L_ECC<6>     CB<7>  @BASEBOARD_FAB2_LIB.BASEBOARD_FAB2(SCH_1):M_L_ECC<6>
   47  M_L_ECC<5>     CB<4>  @BASEBOARD_FAB2_LIB.BASEBOARD_FAB2(SCH_1):M_L_ECC<5>
  192  M_L_ECC<4>     CB<5>  @BASEBOARD_FAB2_LIB.BASEBOARD_FAB2(SCH_1):M_L_ECC<4>
   56  M_L_ECC<3>     CB<2>  @BASEBOARD_FAB2_LIB.BASEBOARD_FAB2(SCH_1):M_L_ECC<3>
  201  M_L_ECC<2>     CB<3>  @BASEBOARD_FAB2_LIB.BASEBOARD_FAB2(SCH_1):M_L_ECC<2>
   49  M_L_ECC<1>     CB<0>  @BASEBOARD_FAB2_LIB.BASEBOARD_FAB2(SCH_1):M_L_ECC<1>
  194  M_L_ECC<0>     CB<1>  @BASEBOARD_FAB2_LIB.BASEBOARD_FAB2(SCH_1):M_L_ECC<0>
   16  M_L_DQ<9>      DQ<8>  @BASEBOARD_FAB2_LIB.BASEBOARD_FAB2(SCH_1):M_L_DQ<9>
  161  M_L_DQ<8>      DQ<9>  @BASEBOARD_FAB2_LIB.BASEBOARD_FAB2(SCH_1):M_L_DQ<8>
   10  M_L_DQ<7>      DQ<6>  @BASEBOARD_FAB2_LIB.BASEBOARD_FAB2(SCH_1):M_L_DQ<7>
  155  M_L_DQ<6>      DQ<7>  @BASEBOARD_FAB2_LIB.BASEBOARD_FAB2(SCH_1):M_L_DQ<6>
  135  M_L_DQ<63>     DQ<62>  @BASEBOARD_FAB2_LIB.BASEBOARD_FAB2(SCH_1):M_L_DQ<63>
  280  M_L_DQ<62>     DQ<63>  @BASEBOARD_FAB2_LIB.BASEBOARD_FAB2(SCH_1):M_L_DQ<62>
  128  M_L_DQ<61>     DQ<60>  @BASEBOARD_FAB2_LIB.BASEBOARD_FAB2(SCH_1):M_L_DQ<61>
  273  M_L_DQ<60>     DQ<61>  @BASEBOARD_FAB2_LIB.BASEBOARD_FAB2(SCH_1):M_L_DQ<60>
    3  M_L_DQ<5>      DQ<4>  @BASEBOARD_FAB2_LIB.BASEBOARD_FAB2(SCH_1):M_L_DQ<5>
  137  M_L_DQ<59>     DQ<58>  @BASEBOARD_FAB2_LIB.BASEBOARD_FAB2(SCH_1):M_L_DQ<59>
  282  M_L_DQ<58>     DQ<59>  @BASEBOARD_FAB2_LIB.BASEBOARD_FAB2(SCH_1):M_L_DQ<58>
  130  M_L_DQ<57>     DQ<56>  @BASEBOARD_FAB2_LIB.BASEBOARD_FAB2(SCH_1):M_L_DQ<57>
  275  M_L_DQ<56>     DQ<57>  @BASEBOARD_FAB2_LIB.BASEBOARD_FAB2(SCH_1):M_L_DQ<56>
  124  M_L_DQ<55>     DQ<54>  @BASEBOARD_FAB2_LIB.BASEBOARD_FAB2(SCH_1):M_L_DQ<55>
  269  M_L_DQ<54>     DQ<55>  @BASEBOARD_FAB2_LIB.BASEBOARD_FAB2(SCH_1):M_L_DQ<54>
  117  M_L_DQ<53>     DQ<52>  @BASEBOARD_FAB2_LIB.BASEBOARD_FAB2(SCH_1):M_L_DQ<53>
  262  M_L_DQ<52>     DQ<53>  @BASEBOARD_FAB2_LIB.BASEBOARD_FAB2(SCH_1):M_L_DQ<52>
  126  M_L_DQ<51>     DQ<50>  @BASEBOARD_FAB2_LIB.BASEBOARD_FAB2(SCH_1):M_L_DQ<51>
  271  M_L_DQ<50>     DQ<51>  @BASEBOARD_FAB2_LIB.BASEBOARD_FAB2(SCH_1):M_L_DQ<50>
  148  M_L_DQ<4>      DQ<5>  @BASEBOARD_FAB2_LIB.BASEBOARD_FAB2(SCH_1):M_L_DQ<4>
  119  M_L_DQ<49>     DQ<48>  @BASEBOARD_FAB2_LIB.BASEBOARD_FAB2(SCH_1):M_L_DQ<49>
  264  M_L_DQ<48>     DQ<49>  @BASEBOARD_FAB2_LIB.BASEBOARD_FAB2(SCH_1):M_L_DQ<48>
  113  M_L_DQ<47>     DQ<46>  @BASEBOARD_FAB2_LIB.BASEBOARD_FAB2(SCH_1):M_L_DQ<47>
  258  M_L_DQ<46>     DQ<47>  @BASEBOARD_FAB2_LIB.BASEBOARD_FAB2(SCH_1):M_L_DQ<46>
  106  M_L_DQ<45>     DQ<44>  @BASEBOARD_FAB2_LIB.BASEBOARD_FAB2(SCH_1):M_L_DQ<45>
  251  M_L_DQ<44>     DQ<45>  @BASEBOARD_FAB2_LIB.BASEBOARD_FAB2(SCH_1):M_L_DQ<44>
  115  M_L_DQ<43>     DQ<42>  @BASEBOARD_FAB2_LIB.BASEBOARD_FAB2(SCH_1):M_L_DQ<43>
  260  M_L_DQ<42>     DQ<43>  @BASEBOARD_FAB2_LIB.BASEBOARD_FAB2(SCH_1):M_L_DQ<42>
  108  M_L_DQ<41>     DQ<40>  @BASEBOARD_FAB2_LIB.BASEBOARD_FAB2(SCH_1):M_L_DQ<41>
  253  M_L_DQ<40>     DQ<41>  @BASEBOARD_FAB2_LIB.BASEBOARD_FAB2(SCH_1):M_L_DQ<40>
   12  M_L_DQ<3>      DQ<2>  @BASEBOARD_FAB2_LIB.BASEBOARD_FAB2(SCH_1):M_L_DQ<3>
  102  M_L_DQ<39>     DQ<38>  @BASEBOARD_FAB2_LIB.BASEBOARD_FAB2(SCH_1):M_L_DQ<39>
  247  M_L_DQ<38>     DQ<39>  @BASEBOARD_FAB2_LIB.BASEBOARD_FAB2(SCH_1):M_L_DQ<38>
   95  M_L_DQ<37>     DQ<36>  @BASEBOARD_FAB2_LIB.BASEBOARD_FAB2(SCH_1):M_L_DQ<37>
  240  M_L_DQ<36>     DQ<37>  @BASEBOARD_FAB2_LIB.BASEBOARD_FAB2(SCH_1):M_L_DQ<36>
  104  M_L_DQ<35>     DQ<34>  @BASEBOARD_FAB2_LIB.BASEBOARD_FAB2(SCH_1):M_L_DQ<35>
  249  M_L_DQ<34>     DQ<35>  @BASEBOARD_FAB2_LIB.BASEBOARD_FAB2(SCH_1):M_L_DQ<34>
   97  M_L_DQ<33>     DQ<32>  @BASEBOARD_FAB2_LIB.BASEBOARD_FAB2(SCH_1):M_L_DQ<33>
  242  M_L_DQ<32>     DQ<33>  @BASEBOARD_FAB2_LIB.BASEBOARD_FAB2(SCH_1):M_L_DQ<32>
   43  M_L_DQ<31>     DQ<30>  @BASEBOARD_FAB2_LIB.BASEBOARD_FAB2(SCH_1):M_L_DQ<31>
  188  M_L_DQ<30>     DQ<31>  @BASEBOARD_FAB2_LIB.BASEBOARD_FAB2(SCH_1):M_L_DQ<30>
  157  M_L_DQ<2>      DQ<3>  @BASEBOARD_FAB2_LIB.BASEBOARD_FAB2(SCH_1):M_L_DQ<2>
   36  M_L_DQ<29>     DQ<28>  @BASEBOARD_FAB2_LIB.BASEBOARD_FAB2(SCH_1):M_L_DQ<29>
  181  M_L_DQ<28>     DQ<29>  @BASEBOARD_FAB2_LIB.BASEBOARD_FAB2(SCH_1):M_L_DQ<28>
   45  M_L_DQ<27>     DQ<26>  @BASEBOARD_FAB2_LIB.BASEBOARD_FAB2(SCH_1):M_L_DQ<27>
  190  M_L_DQ<26>     DQ<27>  @BASEBOARD_FAB2_LIB.BASEBOARD_FAB2(SCH_1):M_L_DQ<26>
   38  M_L_DQ<25>     DQ<24>  @BASEBOARD_FAB2_LIB.BASEBOARD_FAB2(SCH_1):M_L_DQ<25>
  183  M_L_DQ<24>     DQ<25>  @BASEBOARD_FAB2_LIB.BASEBOARD_FAB2(SCH_1):M_L_DQ<24>
   32  M_L_DQ<23>     DQ<22>  @BASEBOARD_FAB2_LIB.BASEBOARD_FAB2(SCH_1):M_L_DQ<23>
  177  M_L_DQ<22>     DQ<23>  @BASEBOARD_FAB2_LIB.BASEBOARD_FAB2(SCH_1):M_L_DQ<22>
   25  M_L_DQ<21>     DQ<20>  @BASEBOARD_FAB2_LIB.BASEBOARD_FAB2(SCH_1):M_L_DQ<21>
  170  M_L_DQ<20>     DQ<21>  @BASEBOARD_FAB2_LIB.BASEBOARD_FAB2(SCH_1):M_L_DQ<20>
    5  M_L_DQ<1>      DQ<0>  @BASEBOARD_FAB2_LIB.BASEBOARD_FAB2(SCH_1):M_L_DQ<1>
   34  M_L_DQ<19>     DQ<18>  @BASEBOARD_FAB2_LIB.BASEBOARD_FAB2(SCH_1):M_L_DQ<19>
  179  M_L_DQ<18>     DQ<19>  @BASEBOARD_FAB2_LIB.BASEBOARD_FAB2(SCH_1):M_L_DQ<18>
   27  M_L_DQ<17>     DQ<16>  @BASEBOARD_FAB2_LIB.BASEBOARD_FAB2(SCH_1):M_L_DQ<17>
  172  M_L_DQ<16>     DQ<17>  @BASEBOARD_FAB2_LIB.BASEBOARD_FAB2(SCH_1):M_L_DQ<16>
   21  M_L_DQ<15>     DQ<14>  @BASEBOARD_FAB2_LIB.BASEBOARD_FAB2(SCH_1):M_L_DQ<15>
  166  M_L_DQ<14>     DQ<15>  @BASEBOARD_FAB2_LIB.BASEBOARD_FAB2(SCH_1):M_L_DQ<14>
   14  M_L_DQ<13>     DQ<12>  @BASEBOARD_FAB2_LIB.BASEBOARD_FAB2(SCH_1):M_L_DQ<13>
  159  M_L_DQ<12>     DQ<13>  @BASEBOARD_FAB2_LIB.BASEBOARD_FAB2(SCH_1):M_L_DQ<12>
   23  M_L_DQ<11>     DQ<10>  @BASEBOARD_FAB2_LIB.BASEBOARD_FAB2(SCH_1):M_L_DQ<11>
  168  M_L_DQ<10>     DQ<11>  @BASEBOARD_FAB2_LIB.BASEBOARD_FAB2(SCH_1):M_L_DQ<10>
  150  M_L_DQ<0>      DQ<1>  @BASEBOARD_FAB2_LIB.BASEBOARD_FAB2(SCH_1):M_L_DQ<0>
  237  M_L_CS_N<3>    S3_N_C<1>  @BASEBOARD_FAB2_LIB.BASEBOARD_FAB2(SCH_1):M_L_CS_N<3>
   93  M_L_CS_N<2>    S2_N_C<0>  @BASEBOARD_FAB2_LIB.BASEBOARD_FAB2(SCH_1):M_L_CS_N<2>
   89  M_L_CS_N<1>     S1_N  @BASEBOARD_FAB2_LIB.BASEBOARD_FAB2(SCH_1):M_L_CS_N<1>
   84  M_L_CS_N<0>     S0_N  @BASEBOARD_FAB2_LIB.BASEBOARD_FAB2(SCH_1):M_L_CS_N<0>
  218  M_L_CLK_DP<1>   CK1P  @BASEBOARD_FAB2_LIB.BASEBOARD_FAB2(SCH_1):M_L_CLK_DP<1>
   74  M_L_CLK_DP<0>   CK0P  @BASEBOARD_FAB2_LIB.BASEBOARD_FAB2(SCH_1):M_L_CLK_DP<0>
  219  M_L_CLK_DN<1>   CK1N  @BASEBOARD_FAB2_LIB.BASEBOARD_FAB2(SCH_1):M_L_CLK_DN<1>
   75  M_L_CLK_DN<0>   CK0N  @BASEBOARD_FAB2_LIB.BASEBOARD_FAB2(SCH_1):M_L_CLK_DN<0>
  203  M_L_CKE<1>     CKE<1>  @BASEBOARD_FAB2_LIB.BASEBOARD_FAB2(SCH_1):M_L_CKE<1>
   60  M_L_CKE<0>     CKE<0>  @BASEBOARD_FAB2_LIB.BASEBOARD_FAB2(SCH_1):M_L_CKE<0>
  235  M_L_C<2>        C<2>  @BASEBOARD_FAB2_LIB.BASEBOARD_FAB2(SCH_1):M_L_C<2>
  207  M_L_BG<1>      BG<1>  @BASEBOARD_FAB2_LIB.BASEBOARD_FAB2(SCH_1):M_L_BG<1>
   63  M_L_BG<0>      BG<0>  @BASEBOARD_FAB2_LIB.BASEBOARD_FAB2(SCH_1):M_L_BG<0>
  224  M_L_BA<1>      BA<1>  @BASEBOARD_FAB2_LIB.BASEBOARD_FAB2(SCH_1):M_L_BA<1>
   81  M_L_BA<0>      BA<0>  @BASEBOARD_FAB2_LIB.BASEBOARD_FAB2(SCH_1):M_L_BA<0>
  208  M_L_ALERT_N    ALERT_N  @BASEBOARD_FAB2_LIB.BASEBOARD_FAB2(SCH_1):M_L_ALERT_N
   62  M_L_ACT_N      ACT_N  @BASEBOARD_FAB2_LIB.BASEBOARD_FAB2(SCH_1):M_L_ACT_N
   58  M_KLM_RST_N    RESET_N  @BASEBOARD_FAB2_LIB.BASEBOARD_FAB2(SCH_1):M_KLM_RST_N
  238  GND            SA<2>  @BASEBOARD_FAB2_LIB.BASEBOARD_FAB2(SCH_1):GND
  139  GND            SA<0>  @BASEBOARD_FAB2_LIB.BASEBOARD_FAB2(SCH_1):GND
   78  FM_DIMM_EVENT_COD_N  EVENT_N  @BASEBOARD_FAB2_LIB.BASEBOARD_FAB2(SCH_1):FM_DIMM_EVENT_COD_N
  230  FM_ADR_COMPLETE_KLM_N  SAVE_N_NC  @BASEBOARD_FAB2_LIB.BASEBOARD_FAB2(SCH_1):FM_ADR_COMPLETE_KLM_N

SCONN288_H44441004_PIP  I167  J1B1   [SCONN288_H44441004_PIP-SCONN,HA]
   77  PVTT_KLM       VTT<1>  @BASEBOARD_FAB2_LIB.BASEBOARD_FAB2(SCH_1):PVTT_KLM
  221  PVTT_KLM       VTT<0>  @BASEBOARD_FAB2_LIB.BASEBOARD_FAB2(SCH_1):PVTT_KLM
  142  PVPP_KLM       VPP<4>  @BASEBOARD_FAB2_LIB.BASEBOARD_FAB2(SCH_1):PVPP_KLM
  143  PVPP_KLM       VPP<3>  @BASEBOARD_FAB2_LIB.BASEBOARD_FAB2(SCH_1):PVPP_KLM
  288  PVPP_KLM       VPP<2>  @BASEBOARD_FAB2_LIB.BASEBOARD_FAB2(SCH_1):PVPP_KLM
  286  PVPP_KLM       VPP<1>  @BASEBOARD_FAB2_LIB.BASEBOARD_FAB2(SCH_1):PVPP_KLM
  287  PVPP_KLM       VPP<0>  @BASEBOARD_FAB2_LIB.BASEBOARD_FAB2(SCH_1):PVPP_KLM
   59  PVDDQ_KLM      VDD<25>  @BASEBOARD_FAB2_LIB.BASEBOARD_FAB2(SCH_1):PVDDQ_KLM
   61  PVDDQ_KLM      VDD<24>  @BASEBOARD_FAB2_LIB.BASEBOARD_FAB2(SCH_1):PVDDQ_KLM
   64  PVDDQ_KLM      VDD<23>  @BASEBOARD_FAB2_LIB.BASEBOARD_FAB2(SCH_1):PVDDQ_KLM
   67  PVDDQ_KLM      VDD<22>  @BASEBOARD_FAB2_LIB.BASEBOARD_FAB2(SCH_1):PVDDQ_KLM
   70  PVDDQ_KLM      VDD<21>  @BASEBOARD_FAB2_LIB.BASEBOARD_FAB2(SCH_1):PVDDQ_KLM
   73  PVDDQ_KLM      VDD<20>  @BASEBOARD_FAB2_LIB.BASEBOARD_FAB2(SCH_1):PVDDQ_KLM
   76  PVDDQ_KLM      VDD<19>  @BASEBOARD_FAB2_LIB.BASEBOARD_FAB2(SCH_1):PVDDQ_KLM
   80  PVDDQ_KLM      VDD<18>  @BASEBOARD_FAB2_LIB.BASEBOARD_FAB2(SCH_1):PVDDQ_KLM
   83  PVDDQ_KLM      VDD<17>  @BASEBOARD_FAB2_LIB.BASEBOARD_FAB2(SCH_1):PVDDQ_KLM
   85  PVDDQ_KLM      VDD<16>  @BASEBOARD_FAB2_LIB.BASEBOARD_FAB2(SCH_1):PVDDQ_KLM
   88  PVDDQ_KLM      VDD<15>  @BASEBOARD_FAB2_LIB.BASEBOARD_FAB2(SCH_1):PVDDQ_KLM
   90  PVDDQ_KLM      VDD<14>  @BASEBOARD_FAB2_LIB.BASEBOARD_FAB2(SCH_1):PVDDQ_KLM
   92  PVDDQ_KLM      VDD<13>  @BASEBOARD_FAB2_LIB.BASEBOARD_FAB2(SCH_1):PVDDQ_KLM
  204  PVDDQ_KLM      VDD<12>  @BASEBOARD_FAB2_LIB.BASEBOARD_FAB2(SCH_1):PVDDQ_KLM
  206  PVDDQ_KLM      VDD<11>  @BASEBOARD_FAB2_LIB.BASEBOARD_FAB2(SCH_1):PVDDQ_KLM
  209  PVDDQ_KLM      VDD<10>  @BASEBOARD_FAB2_LIB.BASEBOARD_FAB2(SCH_1):PVDDQ_KLM
  212  PVDDQ_KLM      VDD<9>  @BASEBOARD_FAB2_LIB.BASEBOARD_FAB2(SCH_1):PVDDQ_KLM
  215  PVDDQ_KLM      VDD<8>  @BASEBOARD_FAB2_LIB.BASEBOARD_FAB2(SCH_1):PVDDQ_KLM
  217  PVDDQ_KLM      VDD<7>  @BASEBOARD_FAB2_LIB.BASEBOARD_FAB2(SCH_1):PVDDQ_KLM
  220  PVDDQ_KLM      VDD<6>  @BASEBOARD_FAB2_LIB.BASEBOARD_FAB2(SCH_1):PVDDQ_KLM
  223  PVDDQ_KLM      VDD<5>  @BASEBOARD_FAB2_LIB.BASEBOARD_FAB2(SCH_1):PVDDQ_KLM
  226  PVDDQ_KLM      VDD<4>  @BASEBOARD_FAB2_LIB.BASEBOARD_FAB2(SCH_1):PVDDQ_KLM
  229  PVDDQ_KLM      VDD<3>  @BASEBOARD_FAB2_LIB.BASEBOARD_FAB2(SCH_1):PVDDQ_KLM
  231  PVDDQ_KLM      VDD<2>  @BASEBOARD_FAB2_LIB.BASEBOARD_FAB2(SCH_1):PVDDQ_KLM
  233  PVDDQ_KLM      VDD<1>  @BASEBOARD_FAB2_LIB.BASEBOARD_FAB2(SCH_1):PVDDQ_KLM
  236  PVDDQ_KLM      VDD<0>  @BASEBOARD_FAB2_LIB.BASEBOARD_FAB2(SCH_1):PVDDQ_KLM
    1  P12V_NVDIMM_KLM  12V<1>  @BASEBOARD_FAB2_LIB.BASEBOARD_FAB2(SCH_1):P12V_NVDIMM_KLM
  145  P12V_NVDIMM_KLM  12V<0>  @BASEBOARD_FAB2_LIB.BASEBOARD_FAB2(SCH_1):P12V_NVDIMM_KLM

SCONN288_H44441004_PIP  I43  J1B1   [SCONN288_H44441004_PIP-SCONN,HA]
    2  GND            VSS<93>  @BASEBOARD_FAB2_LIB.BASEBOARD_FAB2(SCH_1):GND
    4  GND            VSS<92>  @BASEBOARD_FAB2_LIB.BASEBOARD_FAB2(SCH_1):GND
    6  GND            VSS<91>  @BASEBOARD_FAB2_LIB.BASEBOARD_FAB2(SCH_1):GND
    9  GND            VSS<90>  @BASEBOARD_FAB2_LIB.BASEBOARD_FAB2(SCH_1):GND
   11  GND            VSS<89>  @BASEBOARD_FAB2_LIB.BASEBOARD_FAB2(SCH_1):GND
   13  GND            VSS<88>  @BASEBOARD_FAB2_LIB.BASEBOARD_FAB2(SCH_1):GND
   15  GND            VSS<87>  @BASEBOARD_FAB2_LIB.BASEBOARD_FAB2(SCH_1):GND
   17  GND            VSS<86>  @BASEBOARD_FAB2_LIB.BASEBOARD_FAB2(SCH_1):GND
   20  GND            VSS<85>  @BASEBOARD_FAB2_LIB.BASEBOARD_FAB2(SCH_1):GND
   22  GND            VSS<84>  @BASEBOARD_FAB2_LIB.BASEBOARD_FAB2(SCH_1):GND
   24  GND            VSS<83>  @BASEBOARD_FAB2_LIB.BASEBOARD_FAB2(SCH_1):GND
   26  GND            VSS<82>  @BASEBOARD_FAB2_LIB.BASEBOARD_FAB2(SCH_1):GND
   28  GND            VSS<81>  @BASEBOARD_FAB2_LIB.BASEBOARD_FAB2(SCH_1):GND
   31  GND            VSS<80>  @BASEBOARD_FAB2_LIB.BASEBOARD_FAB2(SCH_1):GND
   33  GND            VSS<79>  @BASEBOARD_FAB2_LIB.BASEBOARD_FAB2(SCH_1):GND
   35  GND            VSS<78>  @BASEBOARD_FAB2_LIB.BASEBOARD_FAB2(SCH_1):GND
   37  GND            VSS<77>  @BASEBOARD_FAB2_LIB.BASEBOARD_FAB2(SCH_1):GND
   39  GND            VSS<76>  @BASEBOARD_FAB2_LIB.BASEBOARD_FAB2(SCH_1):GND
   42  GND            VSS<75>  @BASEBOARD_FAB2_LIB.BASEBOARD_FAB2(SCH_1):GND
   44  GND            VSS<74>  @BASEBOARD_FAB2_LIB.BASEBOARD_FAB2(SCH_1):GND
   46  GND            VSS<73>  @BASEBOARD_FAB2_LIB.BASEBOARD_FAB2(SCH_1):GND
   48  GND            VSS<72>  @BASEBOARD_FAB2_LIB.BASEBOARD_FAB2(SCH_1):GND
   50  GND            VSS<71>  @BASEBOARD_FAB2_LIB.BASEBOARD_FAB2(SCH_1):GND
   53  GND            VSS<70>  @BASEBOARD_FAB2_LIB.BASEBOARD_FAB2(SCH_1):GND
   55  GND            VSS<69>  @BASEBOARD_FAB2_LIB.BASEBOARD_FAB2(SCH_1):GND
   57  GND            VSS<68>  @BASEBOARD_FAB2_LIB.BASEBOARD_FAB2(SCH_1):GND
   94  GND            VSS<67>  @BASEBOARD_FAB2_LIB.BASEBOARD_FAB2(SCH_1):GND
   96  GND            VSS<66>  @BASEBOARD_FAB2_LIB.BASEBOARD_FAB2(SCH_1):GND
   98  GND            VSS<65>  @BASEBOARD_FAB2_LIB.BASEBOARD_FAB2(SCH_1):GND
  101  GND            VSS<64>  @BASEBOARD_FAB2_LIB.BASEBOARD_FAB2(SCH_1):GND
  103  GND            VSS<63>  @BASEBOARD_FAB2_LIB.BASEBOARD_FAB2(SCH_1):GND
  105  GND            VSS<62>  @BASEBOARD_FAB2_LIB.BASEBOARD_FAB2(SCH_1):GND
  107  GND            VSS<61>  @BASEBOARD_FAB2_LIB.BASEBOARD_FAB2(SCH_1):GND
  109  GND            VSS<60>  @BASEBOARD_FAB2_LIB.BASEBOARD_FAB2(SCH_1):GND
  112  GND            VSS<59>  @BASEBOARD_FAB2_LIB.BASEBOARD_FAB2(SCH_1):GND
  114  GND            VSS<58>  @BASEBOARD_FAB2_LIB.BASEBOARD_FAB2(SCH_1):GND
  116  GND            VSS<57>  @BASEBOARD_FAB2_LIB.BASEBOARD_FAB2(SCH_1):GND
  118  GND            VSS<56>  @BASEBOARD_FAB2_LIB.BASEBOARD_FAB2(SCH_1):GND
  120  GND            VSS<55>  @BASEBOARD_FAB2_LIB.BASEBOARD_FAB2(SCH_1):GND
  123  GND            VSS<54>  @BASEBOARD_FAB2_LIB.BASEBOARD_FAB2(SCH_1):GND
  125  GND            VSS<53>  @BASEBOARD_FAB2_LIB.BASEBOARD_FAB2(SCH_1):GND
  127  GND            VSS<52>  @BASEBOARD_FAB2_LIB.BASEBOARD_FAB2(SCH_1):GND
  129  GND            VSS<51>  @BASEBOARD_FAB2_LIB.BASEBOARD_FAB2(SCH_1):GND
  131  GND            VSS<50>  @BASEBOARD_FAB2_LIB.BASEBOARD_FAB2(SCH_1):GND
  134  GND            VSS<49>  @BASEBOARD_FAB2_LIB.BASEBOARD_FAB2(SCH_1):GND
  136  GND            VSS<48>  @BASEBOARD_FAB2_LIB.BASEBOARD_FAB2(SCH_1):GND
  138  GND            VSS<47>  @BASEBOARD_FAB2_LIB.BASEBOARD_FAB2(SCH_1):GND
  147  GND            VSS<46>  @BASEBOARD_FAB2_LIB.BASEBOARD_FAB2(SCH_1):GND
  149  GND            VSS<45>  @BASEBOARD_FAB2_LIB.BASEBOARD_FAB2(SCH_1):GND
  151  GND            VSS<44>  @BASEBOARD_FAB2_LIB.BASEBOARD_FAB2(SCH_1):GND
  154  GND            VSS<43>  @BASEBOARD_FAB2_LIB.BASEBOARD_FAB2(SCH_1):GND
  156  GND            VSS<42>  @BASEBOARD_FAB2_LIB.BASEBOARD_FAB2(SCH_1):GND
  158  GND            VSS<41>  @BASEBOARD_FAB2_LIB.BASEBOARD_FAB2(SCH_1):GND
  160  GND            VSS<40>  @BASEBOARD_FAB2_LIB.BASEBOARD_FAB2(SCH_1):GND
  162  GND            VSS<39>  @BASEBOARD_FAB2_LIB.BASEBOARD_FAB2(SCH_1):GND
  165  GND            VSS<38>  @BASEBOARD_FAB2_LIB.BASEBOARD_FAB2(SCH_1):GND
  167  GND            VSS<37>  @BASEBOARD_FAB2_LIB.BASEBOARD_FAB2(SCH_1):GND
  169  GND            VSS<36>  @BASEBOARD_FAB2_LIB.BASEBOARD_FAB2(SCH_1):GND
  171  GND            VSS<35>  @BASEBOARD_FAB2_LIB.BASEBOARD_FAB2(SCH_1):GND
  173  GND            VSS<34>  @BASEBOARD_FAB2_LIB.BASEBOARD_FAB2(SCH_1):GND
  176  GND            VSS<33>  @BASEBOARD_FAB2_LIB.BASEBOARD_FAB2(SCH_1):GND
  178  GND            VSS<32>  @BASEBOARD_FAB2_LIB.BASEBOARD_FAB2(SCH_1):GND
  180  GND            VSS<31>  @BASEBOARD_FAB2_LIB.BASEBOARD_FAB2(SCH_1):GND
  182  GND            VSS<30>  @BASEBOARD_FAB2_LIB.BASEBOARD_FAB2(SCH_1):GND
  184  GND            VSS<29>  @BASEBOARD_FAB2_LIB.BASEBOARD_FAB2(SCH_1):GND
  187  GND            VSS<28>  @BASEBOARD_FAB2_LIB.BASEBOARD_FAB2(SCH_1):GND
  189  GND            VSS<27>  @BASEBOARD_FAB2_LIB.BASEBOARD_FAB2(SCH_1):GND
  191  GND            VSS<26>  @BASEBOARD_FAB2_LIB.BASEBOARD_FAB2(SCH_1):GND
  193  GND            VSS<25>  @BASEBOARD_FAB2_LIB.BASEBOARD_FAB2(SCH_1):GND
  195  GND            VSS<24>  @BASEBOARD_FAB2_LIB.BASEBOARD_FAB2(SCH_1):GND
  198  GND            VSS<23>  @BASEBOARD_FAB2_LIB.BASEBOARD_FAB2(SCH_1):GND
  200  GND            VSS<22>  @BASEBOARD_FAB2_LIB.BASEBOARD_FAB2(SCH_1):GND
  202  GND            VSS<21>  @BASEBOARD_FAB2_LIB.BASEBOARD_FAB2(SCH_1):GND
  239  GND            VSS<20>  @BASEBOARD_FAB2_LIB.BASEBOARD_FAB2(SCH_1):GND
  241  GND            VSS<19>  @BASEBOARD_FAB2_LIB.BASEBOARD_FAB2(SCH_1):GND
  243  GND            VSS<18>  @BASEBOARD_FAB2_LIB.BASEBOARD_FAB2(SCH_1):GND
  246  GND            VSS<17>  @BASEBOARD_FAB2_LIB.BASEBOARD_FAB2(SCH_1):GND
  248  GND            VSS<16>  @BASEBOARD_FAB2_LIB.BASEBOARD_FAB2(SCH_1):GND
  250  GND            VSS<15>  @BASEBOARD_FAB2_LIB.BASEBOARD_FAB2(SCH_1):GND
  252  GND            VSS<14>  @BASEBOARD_FAB2_LIB.BASEBOARD_FAB2(SCH_1):GND
  254  GND            VSS<13>  @BASEBOARD_FAB2_LIB.BASEBOARD_FAB2(SCH_1):GND
  257  GND            VSS<12>  @BASEBOARD_FAB2_LIB.BASEBOARD_FAB2(SCH_1):GND
  259  GND            VSS<11>  @BASEBOARD_FAB2_LIB.BASEBOARD_FAB2(SCH_1):GND
  261  GND            VSS<10>  @BASEBOARD_FAB2_LIB.BASEBOARD_FAB2(SCH_1):GND
  263  GND            VSS<9>  @BASEBOARD_FAB2_LIB.BASEBOARD_FAB2(SCH_1):GND
  265  GND            VSS<8>  @BASEBOARD_FAB2_LIB.BASEBOARD_FAB2(SCH_1):GND
  268  GND            VSS<7>  @BASEBOARD_FAB2_LIB.BASEBOARD_FAB2(SCH_1):GND
  270  GND            VSS<6>  @BASEBOARD_FAB2_LIB.BASEBOARD_FAB2(SCH_1):GND
  272  GND            VSS<5>  @BASEBOARD_FAB2_LIB.BASEBOARD_FAB2(SCH_1):GND
  274  GND            VSS<4>  @BASEBOARD_FAB2_LIB.BASEBOARD_FAB2(SCH_1):GND
  276  GND            VSS<3>  @BASEBOARD_FAB2_LIB.BASEBOARD_FAB2(SCH_1):GND
  279  GND            VSS<2>  @BASEBOARD_FAB2_LIB.BASEBOARD_FAB2(SCH_1):GND
  281  GND            VSS<1>  @BASEBOARD_FAB2_LIB.BASEBOARD_FAB2(SCH_1):GND
  283  GND            VSS<0>  @BASEBOARD_FAB2_LIB.BASEBOARD_FAB2(SCH_1):GND

SCONN288_H44441004_PIP  I66  J1B1   [SCONN288_H44441004_PIP-SCONN,HA]
    7  M_K_DQS_DP<9>  DQS9P  @BASEBOARD_FAB2_LIB.BASEBOARD_FAB2(SCH_1):M_K_DQS_DP<9>
  197  M_K_DQS_DP<8>  DQS8P  @BASEBOARD_FAB2_LIB.BASEBOARD_FAB2(SCH_1):M_K_DQS_DP<8>
  278  M_K_DQS_DP<7>  DQS7P  @BASEBOARD_FAB2_LIB.BASEBOARD_FAB2(SCH_1):M_K_DQS_DP<7>
  267  M_K_DQS_DP<6>  DQS6P  @BASEBOARD_FAB2_LIB.BASEBOARD_FAB2(SCH_1):M_K_DQS_DP<6>
  256  M_K_DQS_DP<5>  DQS5P  @BASEBOARD_FAB2_LIB.BASEBOARD_FAB2(SCH_1):M_K_DQS_DP<5>
  245  M_K_DQS_DP<4>  DQS4P  @BASEBOARD_FAB2_LIB.BASEBOARD_FAB2(SCH_1):M_K_DQS_DP<4>
  186  M_K_DQS_DP<3>  DQS3P  @BASEBOARD_FAB2_LIB.BASEBOARD_FAB2(SCH_1):M_K_DQS_DP<3>
  175  M_K_DQS_DP<2>  DQS2P  @BASEBOARD_FAB2_LIB.BASEBOARD_FAB2(SCH_1):M_K_DQS_DP<2>
  164  M_K_DQS_DP<1>  DQS1P  @BASEBOARD_FAB2_LIB.BASEBOARD_FAB2(SCH_1):M_K_DQS_DP<1>
   51  M_K_DQS_DP<17>  DQS17P  @BASEBOARD_FAB2_LIB.BASEBOARD_FAB2(SCH_1):M_K_DQS_DP<17>
  132  M_K_DQS_DP<16>  DQS16P  @BASEBOARD_FAB2_LIB.BASEBOARD_FAB2(SCH_1):M_K_DQS_DP<16>
  121  M_K_DQS_DP<15>  DQS15P  @BASEBOARD_FAB2_LIB.BASEBOARD_FAB2(SCH_1):M_K_DQS_DP<15>
  110  M_K_DQS_DP<14>  DQS14P  @BASEBOARD_FAB2_LIB.BASEBOARD_FAB2(SCH_1):M_K_DQS_DP<14>
   99  M_K_DQS_DP<13>  DQS13P  @BASEBOARD_FAB2_LIB.BASEBOARD_FAB2(SCH_1):M_K_DQS_DP<13>
   40  M_K_DQS_DP<12>  DQS12P  @BASEBOARD_FAB2_LIB.BASEBOARD_FAB2(SCH_1):M_K_DQS_DP<12>
   29  M_K_DQS_DP<11>  DQS11P  @BASEBOARD_FAB2_LIB.BASEBOARD_FAB2(SCH_1):M_K_DQS_DP<11>
   18  M_K_DQS_DP<10>  DQS10P  @BASEBOARD_FAB2_LIB.BASEBOARD_FAB2(SCH_1):M_K_DQS_DP<10>
  153  M_K_DQS_DP<0>  DQS0P  @BASEBOARD_FAB2_LIB.BASEBOARD_FAB2(SCH_1):M_K_DQS_DP<0>
    8  M_K_DQS_DN<9>  DQS9N  @BASEBOARD_FAB2_LIB.BASEBOARD_FAB2(SCH_1):M_K_DQS_DN<9>
  196  M_K_DQS_DN<8>  DQS8N  @BASEBOARD_FAB2_LIB.BASEBOARD_FAB2(SCH_1):M_K_DQS_DN<8>
  277  M_K_DQS_DN<7>  DQS7N  @BASEBOARD_FAB2_LIB.BASEBOARD_FAB2(SCH_1):M_K_DQS_DN<7>
  266  M_K_DQS_DN<6>  DQS6N  @BASEBOARD_FAB2_LIB.BASEBOARD_FAB2(SCH_1):M_K_DQS_DN<6>
  255  M_K_DQS_DN<5>  DQS5N  @BASEBOARD_FAB2_LIB.BASEBOARD_FAB2(SCH_1):M_K_DQS_DN<5>
  244  M_K_DQS_DN<4>  DQS4N  @BASEBOARD_FAB2_LIB.BASEBOARD_FAB2(SCH_1):M_K_DQS_DN<4>
  185  M_K_DQS_DN<3>  DQS3N  @BASEBOARD_FAB2_LIB.BASEBOARD_FAB2(SCH_1):M_K_DQS_DN<3>
  174  M_K_DQS_DN<2>  DQS2N  @BASEBOARD_FAB2_LIB.BASEBOARD_FAB2(SCH_1):M_K_DQS_DN<2>
  163  M_K_DQS_DN<1>  DQS1N  @BASEBOARD_FAB2_LIB.BASEBOARD_FAB2(SCH_1):M_K_DQS_DN<1>
   52  M_K_DQS_DN<17>  DQS17N  @BASEBOARD_FAB2_LIB.BASEBOARD_FAB2(SCH_1):M_K_DQS_DN<17>
  133  M_K_DQS_DN<16>  DQS16N  @BASEBOARD_FAB2_LIB.BASEBOARD_FAB2(SCH_1):M_K_DQS_DN<16>
  122  M_K_DQS_DN<15>  DQS15N  @BASEBOARD_FAB2_LIB.BASEBOARD_FAB2(SCH_1):M_K_DQS_DN<15>
  111  M_K_DQS_DN<14>  DQS14N  @BASEBOARD_FAB2_LIB.BASEBOARD_FAB2(SCH_1):M_K_DQS_DN<14>
  100  M_K_DQS_DN<13>  DQS13N  @BASEBOARD_FAB2_LIB.BASEBOARD_FAB2(SCH_1):M_K_DQS_DN<13>
   41  M_K_DQS_DN<12>  DQS12N  @BASEBOARD_FAB2_LIB.BASEBOARD_FAB2(SCH_1):M_K_DQS_DN<12>
   30  M_K_DQS_DN<11>  DQS11N  @BASEBOARD_FAB2_LIB.BASEBOARD_FAB2(SCH_1):M_K_DQS_DN<11>
   19  M_K_DQS_DN<10>  DQS10N  @BASEBOARD_FAB2_LIB.BASEBOARD_FAB2(SCH_1):M_K_DQS_DN<10>
  152  M_K_DQS_DN<0>  DQS0N  @BASEBOARD_FAB2_LIB.BASEBOARD_FAB2(SCH_1):M_K_DQS_DN<0>

SCONN288_H44441004_PIP  I111  J1B1   [SCONN288_H44441004_PIP-SCONN,HA]
  144  TP_CH_K_DIMM_K0_RFU_2  RFU<2>  @BASEBOARD_FAB2_LIB.BASEBOARD_FAB2(SCH_1):TP_CH_K_DIMM_K0_RFU_2
  227  TP_CH_K_DIMM_K0_RFU_1  RFU<1>  @BASEBOARD_FAB2_LIB.BASEBOARD_FAB2(SCH_1):TP_CH_K_DIMM_K0_RFU_1
  205  TP_CH_K_DIMM_K0_RFU_0  RFU<0>  @BASEBOARD_FAB2_LIB.BASEBOARD_FAB2(SCH_1):TP_CH_K_DIMM_K0_RFU_0
  285  SMB_DDR_KLM_VPP_SDA    SDA  @BASEBOARD_FAB2_LIB.BASEBOARD_FAB2(SCH_1):SMB_DDR_KLM_VPP_SDA
  141  SMB_DDR_KLM_VPP_SCL    SCL  @BASEBOARD_FAB2_LIB.BASEBOARD_FAB2(SCH_1):SMB_DDR_KLM_VPP_SCL
  284  PVPP_KLM       VDDSPD  @BASEBOARD_FAB2_LIB.BASEBOARD_FAB2(SCH_1):PVPP_KLM
  146  M_K_VREF       VREFCA  @BASEBOARD_FAB2_LIB.BASEBOARD_FAB2(SCH_1):M_K_VREF
  222  M_K_PAR          PAR  @BASEBOARD_FAB2_LIB.BASEBOARD_FAB2(SCH_1):M_K_PAR
   91  M_K_ODT<1>     ODT<1>  @BASEBOARD_FAB2_LIB.BASEBOARD_FAB2(SCH_1):M_K_ODT<1>
   87  M_K_ODT<0>     ODT<0>  @BASEBOARD_FAB2_LIB.BASEBOARD_FAB2(SCH_1):M_K_ODT<0>
   66  M_K_MA<9>         A9  @BASEBOARD_FAB2_LIB.BASEBOARD_FAB2(SCH_1):M_K_MA<9>
   68  M_K_MA<8>         A8  @BASEBOARD_FAB2_LIB.BASEBOARD_FAB2(SCH_1):M_K_MA<8>
  211  M_K_MA<7>         A7  @BASEBOARD_FAB2_LIB.BASEBOARD_FAB2(SCH_1):M_K_MA<7>
   69  M_K_MA<6>         A6  @BASEBOARD_FAB2_LIB.BASEBOARD_FAB2(SCH_1):M_K_MA<6>
  213  M_K_MA<5>         A5  @BASEBOARD_FAB2_LIB.BASEBOARD_FAB2(SCH_1):M_K_MA<5>
  214  M_K_MA<4>         A4  @BASEBOARD_FAB2_LIB.BASEBOARD_FAB2(SCH_1):M_K_MA<4>
   71  M_K_MA<3>         A3  @BASEBOARD_FAB2_LIB.BASEBOARD_FAB2(SCH_1):M_K_MA<3>
  216  M_K_MA<2>         A2  @BASEBOARD_FAB2_LIB.BASEBOARD_FAB2(SCH_1):M_K_MA<2>
   72  M_K_MA<1>         A1  @BASEBOARD_FAB2_LIB.BASEBOARD_FAB2(SCH_1):M_K_MA<1>
  234  M_K_MA<17>       A17  @BASEBOARD_FAB2_LIB.BASEBOARD_FAB2(SCH_1):M_K_MA<17>
   82  M_K_MA<16>     A16_RAS_N  @BASEBOARD_FAB2_LIB.BASEBOARD_FAB2(SCH_1):M_K_MA<16>
   86  M_K_MA<15>     A15_CAS_N  @BASEBOARD_FAB2_LIB.BASEBOARD_FAB2(SCH_1):M_K_MA<15>
  228  M_K_MA<14>     A14_WE_N  @BASEBOARD_FAB2_LIB.BASEBOARD_FAB2(SCH_1):M_K_MA<14>
  232  M_K_MA<13>       A13  @BASEBOARD_FAB2_LIB.BASEBOARD_FAB2(SCH_1):M_K_MA<13>
   65  M_K_MA<12>       A12  @BASEBOARD_FAB2_LIB.BASEBOARD_FAB2(SCH_1):M_K_MA<12>
  210  M_K_MA<11>       A11  @BASEBOARD_FAB2_LIB.BASEBOARD_FAB2(SCH_1):M_K_MA<11>
  225  M_K_MA<10>       A10  @BASEBOARD_FAB2_LIB.BASEBOARD_FAB2(SCH_1):M_K_MA<10>
   79  M_K_MA<0>         A0  @BASEBOARD_FAB2_LIB.BASEBOARD_FAB2(SCH_1):M_K_MA<0>
   54  M_K_ECC<7>     CB<6>  @BASEBOARD_FAB2_LIB.BASEBOARD_FAB2(SCH_1):M_K_ECC<7>
  199  M_K_ECC<6>     CB<7>  @BASEBOARD_FAB2_LIB.BASEBOARD_FAB2(SCH_1):M_K_ECC<6>
   47  M_K_ECC<5>     CB<4>  @BASEBOARD_FAB2_LIB.BASEBOARD_FAB2(SCH_1):M_K_ECC<5>
  192  M_K_ECC<4>     CB<5>  @BASEBOARD_FAB2_LIB.BASEBOARD_FAB2(SCH_1):M_K_ECC<4>
   56  M_K_ECC<3>     CB<2>  @BASEBOARD_FAB2_LIB.BASEBOARD_FAB2(SCH_1):M_K_ECC<3>
  201  M_K_ECC<2>     CB<3>  @BASEBOARD_FAB2_LIB.BASEBOARD_FAB2(SCH_1):M_K_ECC<2>
   49  M_K_ECC<1>     CB<0>  @BASEBOARD_FAB2_LIB.BASEBOARD_FAB2(SCH_1):M_K_ECC<1>
  194  M_K_ECC<0>     CB<1>  @BASEBOARD_FAB2_LIB.BASEBOARD_FAB2(SCH_1):M_K_ECC<0>
   16  M_K_DQ<9>      DQ<8>  @BASEBOARD_FAB2_LIB.BASEBOARD_FAB2(SCH_1):M_K_DQ<9>
  161  M_K_DQ<8>      DQ<9>  @BASEBOARD_FAB2_LIB.BASEBOARD_FAB2(SCH_1):M_K_DQ<8>
   10  M_K_DQ<7>      DQ<6>  @BASEBOARD_FAB2_LIB.BASEBOARD_FAB2(SCH_1):M_K_DQ<7>
  155  M_K_DQ<6>      DQ<7>  @BASEBOARD_FAB2_LIB.BASEBOARD_FAB2(SCH_1):M_K_DQ<6>
  135  M_K_DQ<63>     DQ<62>  @BASEBOARD_FAB2_LIB.BASEBOARD_FAB2(SCH_1):M_K_DQ<63>
  280  M_K_DQ<62>     DQ<63>  @BASEBOARD_FAB2_LIB.BASEBOARD_FAB2(SCH_1):M_K_DQ<62>
  128  M_K_DQ<61>     DQ<60>  @BASEBOARD_FAB2_LIB.BASEBOARD_FAB2(SCH_1):M_K_DQ<61>
  273  M_K_DQ<60>     DQ<61>  @BASEBOARD_FAB2_LIB.BASEBOARD_FAB2(SCH_1):M_K_DQ<60>
    3  M_K_DQ<5>      DQ<4>  @BASEBOARD_FAB2_LIB.BASEBOARD_FAB2(SCH_1):M_K_DQ<5>
  137  M_K_DQ<59>     DQ<58>  @BASEBOARD_FAB2_LIB.BASEBOARD_FAB2(SCH_1):M_K_DQ<59>
  282  M_K_DQ<58>     DQ<59>  @BASEBOARD_FAB2_LIB.BASEBOARD_FAB2(SCH_1):M_K_DQ<58>
  130  M_K_DQ<57>     DQ<56>  @BASEBOARD_FAB2_LIB.BASEBOARD_FAB2(SCH_1):M_K_DQ<57>
  275  M_K_DQ<56>     DQ<57>  @BASEBOARD_FAB2_LIB.BASEBOARD_FAB2(SCH_1):M_K_DQ<56>
  124  M_K_DQ<55>     DQ<54>  @BASEBOARD_FAB2_LIB.BASEBOARD_FAB2(SCH_1):M_K_DQ<55>
  269  M_K_DQ<54>     DQ<55>  @BASEBOARD_FAB2_LIB.BASEBOARD_FAB2(SCH_1):M_K_DQ<54>
  117  M_K_DQ<53>     DQ<52>  @BASEBOARD_FAB2_LIB.BASEBOARD_FAB2(SCH_1):M_K_DQ<53>
  262  M_K_DQ<52>     DQ<53>  @BASEBOARD_FAB2_LIB.BASEBOARD_FAB2(SCH_1):M_K_DQ<52>
  126  M_K_DQ<51>     DQ<50>  @BASEBOARD_FAB2_LIB.BASEBOARD_FAB2(SCH_1):M_K_DQ<51>
  271  M_K_DQ<50>     DQ<51>  @BASEBOARD_FAB2_LIB.BASEBOARD_FAB2(SCH_1):M_K_DQ<50>
  148  M_K_DQ<4>      DQ<5>  @BASEBOARD_FAB2_LIB.BASEBOARD_FAB2(SCH_1):M_K_DQ<4>
  119  M_K_DQ<49>     DQ<48>  @BASEBOARD_FAB2_LIB.BASEBOARD_FAB2(SCH_1):M_K_DQ<49>
  264  M_K_DQ<48>     DQ<49>  @BASEBOARD_FAB2_LIB.BASEBOARD_FAB2(SCH_1):M_K_DQ<48>
  113  M_K_DQ<47>     DQ<46>  @BASEBOARD_FAB2_LIB.BASEBOARD_FAB2(SCH_1):M_K_DQ<47>
  258  M_K_DQ<46>     DQ<47>  @BASEBOARD_FAB2_LIB.BASEBOARD_FAB2(SCH_1):M_K_DQ<46>
  106  M_K_DQ<45>     DQ<44>  @BASEBOARD_FAB2_LIB.BASEBOARD_FAB2(SCH_1):M_K_DQ<45>
  251  M_K_DQ<44>     DQ<45>  @BASEBOARD_FAB2_LIB.BASEBOARD_FAB2(SCH_1):M_K_DQ<44>
  115  M_K_DQ<43>     DQ<42>  @BASEBOARD_FAB2_LIB.BASEBOARD_FAB2(SCH_1):M_K_DQ<43>
  260  M_K_DQ<42>     DQ<43>  @BASEBOARD_FAB2_LIB.BASEBOARD_FAB2(SCH_1):M_K_DQ<42>
  108  M_K_DQ<41>     DQ<40>  @BASEBOARD_FAB2_LIB.BASEBOARD_FAB2(SCH_1):M_K_DQ<41>
  253  M_K_DQ<40>     DQ<41>  @BASEBOARD_FAB2_LIB.BASEBOARD_FAB2(SCH_1):M_K_DQ<40>
   12  M_K_DQ<3>      DQ<2>  @BASEBOARD_FAB2_LIB.BASEBOARD_FAB2(SCH_1):M_K_DQ<3>
  102  M_K_DQ<39>     DQ<38>  @BASEBOARD_FAB2_LIB.BASEBOARD_FAB2(SCH_1):M_K_DQ<39>
  247  M_K_DQ<38>     DQ<39>  @BASEBOARD_FAB2_LIB.BASEBOARD_FAB2(SCH_1):M_K_DQ<38>
   95  M_K_DQ<37>     DQ<36>  @BASEBOARD_FAB2_LIB.BASEBOARD_FAB2(SCH_1):M_K_DQ<37>
  240  M_K_DQ<36>     DQ<37>  @BASEBOARD_FAB2_LIB.BASEBOARD_FAB2(SCH_1):M_K_DQ<36>
  104  M_K_DQ<35>     DQ<34>  @BASEBOARD_FAB2_LIB.BASEBOARD_FAB2(SCH_1):M_K_DQ<35>
  249  M_K_DQ<34>     DQ<35>  @BASEBOARD_FAB2_LIB.BASEBOARD_FAB2(SCH_1):M_K_DQ<34>
   97  M_K_DQ<33>     DQ<32>  @BASEBOARD_FAB2_LIB.BASEBOARD_FAB2(SCH_1):M_K_DQ<33>
  242  M_K_DQ<32>     DQ<33>  @BASEBOARD_FAB2_LIB.BASEBOARD_FAB2(SCH_1):M_K_DQ<32>
   43  M_K_DQ<31>     DQ<30>  @BASEBOARD_FAB2_LIB.BASEBOARD_FAB2(SCH_1):M_K_DQ<31>
  188  M_K_DQ<30>     DQ<31>  @BASEBOARD_FAB2_LIB.BASEBOARD_FAB2(SCH_1):M_K_DQ<30>
  157  M_K_DQ<2>      DQ<3>  @BASEBOARD_FAB2_LIB.BASEBOARD_FAB2(SCH_1):M_K_DQ<2>
   36  M_K_DQ<29>     DQ<28>  @BASEBOARD_FAB2_LIB.BASEBOARD_FAB2(SCH_1):M_K_DQ<29>
  181  M_K_DQ<28>     DQ<29>  @BASEBOARD_FAB2_LIB.BASEBOARD_FAB2(SCH_1):M_K_DQ<28>
   45  M_K_DQ<27>     DQ<26>  @BASEBOARD_FAB2_LIB.BASEBOARD_FAB2(SCH_1):M_K_DQ<27>
  190  M_K_DQ<26>     DQ<27>  @BASEBOARD_FAB2_LIB.BASEBOARD_FAB2(SCH_1):M_K_DQ<26>
   38  M_K_DQ<25>     DQ<24>  @BASEBOARD_FAB2_LIB.BASEBOARD_FAB2(SCH_1):M_K_DQ<25>
  183  M_K_DQ<24>     DQ<25>  @BASEBOARD_FAB2_LIB.BASEBOARD_FAB2(SCH_1):M_K_DQ<24>
   32  M_K_DQ<23>     DQ<22>  @BASEBOARD_FAB2_LIB.BASEBOARD_FAB2(SCH_1):M_K_DQ<23>
  177  M_K_DQ<22>     DQ<23>  @BASEBOARD_FAB2_LIB.BASEBOARD_FAB2(SCH_1):M_K_DQ<22>
   25  M_K_DQ<21>     DQ<20>  @BASEBOARD_FAB2_LIB.BASEBOARD_FAB2(SCH_1):M_K_DQ<21>
  170  M_K_DQ<20>     DQ<21>  @BASEBOARD_FAB2_LIB.BASEBOARD_FAB2(SCH_1):M_K_DQ<20>
    5  M_K_DQ<1>      DQ<0>  @BASEBOARD_FAB2_LIB.BASEBOARD_FAB2(SCH_1):M_K_DQ<1>
   34  M_K_DQ<19>     DQ<18>  @BASEBOARD_FAB2_LIB.BASEBOARD_FAB2(SCH_1):M_K_DQ<19>
  179  M_K_DQ<18>     DQ<19>  @BASEBOARD_FAB2_LIB.BASEBOARD_FAB2(SCH_1):M_K_DQ<18>
   27  M_K_DQ<17>     DQ<16>  @BASEBOARD_FAB2_LIB.BASEBOARD_FAB2(SCH_1):M_K_DQ<17>
  172  M_K_DQ<16>     DQ<17>  @BASEBOARD_FAB2_LIB.BASEBOARD_FAB2(SCH_1):M_K_DQ<16>
   21  M_K_DQ<15>     DQ<14>  @BASEBOARD_FAB2_LIB.BASEBOARD_FAB2(SCH_1):M_K_DQ<15>
  166  M_K_DQ<14>     DQ<15>  @BASEBOARD_FAB2_LIB.BASEBOARD_FAB2(SCH_1):M_K_DQ<14>
   14  M_K_DQ<13>     DQ<12>  @BASEBOARD_FAB2_LIB.BASEBOARD_FAB2(SCH_1):M_K_DQ<13>
  159  M_K_DQ<12>     DQ<13>  @BASEBOARD_FAB2_LIB.BASEBOARD_FAB2(SCH_1):M_K_DQ<12>
   23  M_K_DQ<11>     DQ<10>  @BASEBOARD_FAB2_LIB.BASEBOARD_FAB2(SCH_1):M_K_DQ<11>
  168  M_K_DQ<10>     DQ<11>  @BASEBOARD_FAB2_LIB.BASEBOARD_FAB2(SCH_1):M_K_DQ<10>
  150  M_K_DQ<0>      DQ<1>  @BASEBOARD_FAB2_LIB.BASEBOARD_FAB2(SCH_1):M_K_DQ<0>
  237  M_K_CS_N<3>    S3_N_C<1>  @BASEBOARD_FAB2_LIB.BASEBOARD_FAB2(SCH_1):M_K_CS_N<3>
   93  M_K_CS_N<2>    S2_N_C<0>  @BASEBOARD_FAB2_LIB.BASEBOARD_FAB2(SCH_1):M_K_CS_N<2>
   89  M_K_CS_N<1>     S1_N  @BASEBOARD_FAB2_LIB.BASEBOARD_FAB2(SCH_1):M_K_CS_N<1>
   84  M_K_CS_N<0>     S0_N  @BASEBOARD_FAB2_LIB.BASEBOARD_FAB2(SCH_1):M_K_CS_N<0>
  218  M_K_CLK_DP<1>   CK1P  @BASEBOARD_FAB2_LIB.BASEBOARD_FAB2(SCH_1):M_K_CLK_DP<1>
   74  M_K_CLK_DP<0>   CK0P  @BASEBOARD_FAB2_LIB.BASEBOARD_FAB2(SCH_1):M_K_CLK_DP<0>
  219  M_K_CLK_DN<1>   CK1N  @BASEBOARD_FAB2_LIB.BASEBOARD_FAB2(SCH_1):M_K_CLK_DN<1>
   75  M_K_CLK_DN<0>   CK0N  @BASEBOARD_FAB2_LIB.BASEBOARD_FAB2(SCH_1):M_K_CLK_DN<0>
  203  M_K_CKE<1>     CKE<1>  @BASEBOARD_FAB2_LIB.BASEBOARD_FAB2(SCH_1):M_K_CKE<1>
   60  M_K_CKE<0>     CKE<0>  @BASEBOARD_FAB2_LIB.BASEBOARD_FAB2(SCH_1):M_K_CKE<0>
  235  M_K_C<2>        C<2>  @BASEBOARD_FAB2_LIB.BASEBOARD_FAB2(SCH_1):M_K_C<2>
  207  M_K_BG<1>      BG<1>  @BASEBOARD_FAB2_LIB.BASEBOARD_FAB2(SCH_1):M_K_BG<1>
   63  M_K_BG<0>      BG<0>  @BASEBOARD_FAB2_LIB.BASEBOARD_FAB2(SCH_1):M_K_BG<0>
  224  M_K_BA<1>      BA<1>  @BASEBOARD_FAB2_LIB.BASEBOARD_FAB2(SCH_1):M_K_BA<1>
   81  M_K_BA<0>      BA<0>  @BASEBOARD_FAB2_LIB.BASEBOARD_FAB2(SCH_1):M_K_BA<0>
  208  M_K_ALERT_N    ALERT_N  @BASEBOARD_FAB2_LIB.BASEBOARD_FAB2(SCH_1):M_K_ALERT_N
   62  M_K_ACT_N      ACT_N  @BASEBOARD_FAB2_LIB.BASEBOARD_FAB2(SCH_1):M_K_ACT_N
   58  M_KLM_RST_N    RESET_N  @BASEBOARD_FAB2_LIB.BASEBOARD_FAB2(SCH_1):M_KLM_RST_N
  238  GND            SA<2>  @BASEBOARD_FAB2_LIB.BASEBOARD_FAB2(SCH_1):GND
  140  GND            SA<1>  @BASEBOARD_FAB2_LIB.BASEBOARD_FAB2(SCH_1):GND
  139  GND            SA<0>  @BASEBOARD_FAB2_LIB.BASEBOARD_FAB2(SCH_1):GND
   78  FM_DIMM_EVENT_COD_N  EVENT_N  @BASEBOARD_FAB2_LIB.BASEBOARD_FAB2(SCH_1):FM_DIMM_EVENT_COD_N
  230  FM_ADR_COMPLETE_KLM_N  SAVE_N_NC  @BASEBOARD_FAB2_LIB.BASEBOARD_FAB2(SCH_1):FM_ADR_COMPLETE_KLM_N

CONN6_C74770005  I32  J1B2   [CONN6_C74770005_PIP-HDR,C74770A]
    6  TP_FAN_1         IO6  @BASEBOARD_FAB2_LIB.BASEBOARD_FAB2(SCH_1):TP_FAN_1
    2  P12V_FAN         IO2  @BASEBOARD_FAB2_LIB.BASEBOARD_FAB2(SCH_1):P12V_FAN
    1  GND              IO1  @BASEBOARD_FAB2_LIB.BASEBOARD_FAB2(SCH_1):GND
    5  FAN_TACH3_CPU1_D1    IO5  @BASEBOARD_FAB2_LIB.BASEBOARD_FAB2(SCH_1):FAN_TACH3_CPU1_D1
    3  FAN_TACH2_CPU1_D1    IO3  @BASEBOARD_FAB2_LIB.BASEBOARD_FAB2(SCH_1):FAN_TACH2_CPU1_D1
    4  FAN_PWM_OUT_SYS1_R    IO4  @BASEBOARD_FAB2_LIB.BASEBOARD_FAB2(SCH_1):FAN_PWM_OUT_SYS1_R

CONN3_C95678002_PIP  I123  J1B3   [CONN3_C95678002_PIP-CONN,C9567A]
    2  A_HSC_OCP_SEL    IO2  @BASEBOARD_FAB2_LIB.BASEBOARD_FAB2(SCH_1):A_HSC_OCP_SEL
    3  A_HSC_LOW_EN     IO3  @BASEBOARD_FAB2_LIB.BASEBOARD_FAB2(SCH_1):A_HSC_LOW_EN
    1  A_HSC_HIGH_EN    IO1  @BASEBOARD_FAB2_LIB.BASEBOARD_FAB2(SCH_1):A_HSC_HIGH_EN

SCONN3_D53458001_SM  I124  J1B4   [SCONN3_D53458001_SM-EMPTY,D534A]
    2  A_HSC_OCP_SEL    IO2  @BASEBOARD_FAB2_LIB.BASEBOARD_FAB2(SCH_1):A_HSC_OCP_SEL
    3  A_HSC_LOW_EN     IO3  @BASEBOARD_FAB2_LIB.BASEBOARD_FAB2(SCH_1):A_HSC_LOW_EN
    1  A_HSC_HIGH_EN    IO1  @BASEBOARD_FAB2_LIB.BASEBOARD_FAB2(SCH_1):A_HSC_HIGH_EN

CONN76_H22707001_THMT1  I18  J1C1   [CONN76_H22707001_THMT1-CONN,H2A]
   I4  TP_IOI4         IOI4  @BASEBOARD_FAB2_LIB.BASEBOARD_FAB2(SCH_1):TP_IOI4
   H4  TP_IOH4         IOH4  @BASEBOARD_FAB2_LIB.BASEBOARD_FAB2(SCH_1):TP_IOH4
   H3  TP_IOH3         IOH3  @BASEBOARD_FAB2_LIB.BASEBOARD_FAB2(SCH_1):TP_IOH3
   G3  TP_IOG3         IOG3  @BASEBOARD_FAB2_LIB.BASEBOARD_FAB2(SCH_1):TP_IOG3
   F4  TP_IOF4         IOF4  @BASEBOARD_FAB2_LIB.BASEBOARD_FAB2(SCH_1):TP_IOF4
   E4  TP_IOE4         IOE4  @BASEBOARD_FAB2_LIB.BASEBOARD_FAB2(SCH_1):TP_IOE4
   A5  TP_IOA5         IOA5  @BASEBOARD_FAB2_LIB.BASEBOARD_FAB2(SCH_1):TP_IOA5
   B4  TP_FM_WAKE_N    IOB4  @BASEBOARD_FAB2_LIB.BASEBOARD_FAB2(SCH_1):TP_FM_WAKE_N
   B6  SMB_PEHPCPU1_STBY_LVC3_SDA   IOB6  @BASEBOARD_FAB2_LIB.BASEBOARD_FAB2(SCH_1):SMB_PEHPCPU1_STBY_LVC3_SDA
   C6  SMB_PEHPCPU1_STBY_LVC3_SCL   IOC6  @BASEBOARD_FAB2_LIB.BASEBOARD_FAB2(SCH_1):SMB_PEHPCPU1_STBY_LVC3_SCL
   D5  SMB_LAN_STBY_LVC3_SDA   IOD5  @BASEBOARD_FAB2_LIB.BASEBOARD_FAB2(SCH_1):SMB_LAN_STBY_LVC3_SDA
   E5  SMB_LAN_STBY_LVC3_SCL   IOE5  @BASEBOARD_FAB2_LIB.BASEBOARD_FAB2(SCH_1):SMB_LAN_STBY_LVC3_SCL
   E1  P3E_CPU1_PE3_MP_RXP<9>   IOE1  @BASEBOARD_FAB2_LIB.BASEBOARD_FAB2(SCH_1):P3E_CPU1_PE3_MP_RXP<9>
   B1  P3E_CPU1_PE3_MP_RXP<8>   IOB1  @BASEBOARD_FAB2_LIB.BASEBOARD_FAB2(SCH_1):P3E_CPU1_PE3_MP_RXP<8>
   E3  P3E_CPU1_PE3_MP_RXP<15>   IOE3  @BASEBOARD_FAB2_LIB.BASEBOARD_FAB2(SCH_1):P3E_CPU1_PE3_MP_RXP<15>
   A3  P3E_CPU1_PE3_MP_RXP<14>   IOA3  @BASEBOARD_FAB2_LIB.BASEBOARD_FAB2(SCH_1):P3E_CPU1_PE3_MP_RXP<14>
   H2  P3E_CPU1_PE3_MP_RXP<13>   IOH2  @BASEBOARD_FAB2_LIB.BASEBOARD_FAB2(SCH_1):P3E_CPU1_PE3_MP_RXP<13>
   F2  P3E_CPU1_PE3_MP_RXP<12>   IOF2  @BASEBOARD_FAB2_LIB.BASEBOARD_FAB2(SCH_1):P3E_CPU1_PE3_MP_RXP<12>
   C2  P3E_CPU1_PE3_MP_RXP<11>   IOC2  @BASEBOARD_FAB2_LIB.BASEBOARD_FAB2(SCH_1):P3E_CPU1_PE3_MP_RXP<11>
   G1  P3E_CPU1_PE3_MP_RXP<10>   IOG1  @BASEBOARD_FAB2_LIB.BASEBOARD_FAB2(SCH_1):P3E_CPU1_PE3_MP_RXP<10>
   D1  P3E_CPU1_PE3_MP_RXN<9>   IOD1  @BASEBOARD_FAB2_LIB.BASEBOARD_FAB2(SCH_1):P3E_CPU1_PE3_MP_RXN<9>
   A1  P3E_CPU1_PE3_MP_RXN<8>   IOA1  @BASEBOARD_FAB2_LIB.BASEBOARD_FAB2(SCH_1):P3E_CPU1_PE3_MP_RXN<8>
   D3  P3E_CPU1_PE3_MP_RXN<15>   IOD3  @BASEBOARD_FAB2_LIB.BASEBOARD_FAB2(SCH_1):P3E_CPU1_PE3_MP_RXN<15>
   B3  P3E_CPU1_PE3_MP_RXN<14>   IOB3  @BASEBOARD_FAB2_LIB.BASEBOARD_FAB2(SCH_1):P3E_CPU1_PE3_MP_RXN<14>
   I2  P3E_CPU1_PE3_MP_RXN<13>   IOI2  @BASEBOARD_FAB2_LIB.BASEBOARD_FAB2(SCH_1):P3E_CPU1_PE3_MP_RXN<13>
   E2  P3E_CPU1_PE3_MP_RXN<12>   IOE2  @BASEBOARD_FAB2_LIB.BASEBOARD_FAB2(SCH_1):P3E_CPU1_PE3_MP_RXN<12>
   B2  P3E_CPU1_PE3_MP_RXN<11>   IOB2  @BASEBOARD_FAB2_LIB.BASEBOARD_FAB2(SCH_1):P3E_CPU1_PE3_MP_RXN<11>
   H1  P3E_CPU1_PE3_MP_RXN<10>   IOH1  @BASEBOARD_FAB2_LIB.BASEBOARD_FAB2(SCH_1):P3E_CPU1_PE3_MP_RXN<10>
   F8  P3E_CPU1_PE3_MP_C_TXP<9>   IOF8  @BASEBOARD_FAB2_LIB.BASEBOARD_FAB2(SCH_1):P3E_CPU1_PE3_MP_C_TXP<9>
   C8  P3E_CPU1_PE3_MP_C_TXP<8>   IOC8  @BASEBOARD_FAB2_LIB.BASEBOARD_FAB2(SCH_1):P3E_CPU1_PE3_MP_C_TXP<8>
   I6  P3E_CPU1_PE3_MP_C_TXP<15>   IOI6  @BASEBOARD_FAB2_LIB.BASEBOARD_FAB2(SCH_1):P3E_CPU1_PE3_MP_C_TXP<15>
   F6  P3E_CPU1_PE3_MP_C_TXP<14>   IOF6  @BASEBOARD_FAB2_LIB.BASEBOARD_FAB2(SCH_1):P3E_CPU1_PE3_MP_C_TXP<14>
   H7  P3E_CPU1_PE3_MP_C_TXP<13>   IOH7  @BASEBOARD_FAB2_LIB.BASEBOARD_FAB2(SCH_1):P3E_CPU1_PE3_MP_C_TXP<13>
   E7  P3E_CPU1_PE3_MP_C_TXP<12>   IOE7  @BASEBOARD_FAB2_LIB.BASEBOARD_FAB2(SCH_1):P3E_CPU1_PE3_MP_C_TXP<12>
   B7  P3E_CPU1_PE3_MP_C_TXP<11>   IOB7  @BASEBOARD_FAB2_LIB.BASEBOARD_FAB2(SCH_1):P3E_CPU1_PE3_MP_C_TXP<11>
   H8  P3E_CPU1_PE3_MP_C_TXP<10>   IOH8  @BASEBOARD_FAB2_LIB.BASEBOARD_FAB2(SCH_1):P3E_CPU1_PE3_MP_C_TXP<10>
   E8  P3E_CPU1_PE3_MP_C_TXN<9>   IOE8  @BASEBOARD_FAB2_LIB.BASEBOARD_FAB2(SCH_1):P3E_CPU1_PE3_MP_C_TXN<9>
   B8  P3E_CPU1_PE3_MP_C_TXN<8>   IOB8  @BASEBOARD_FAB2_LIB.BASEBOARD_FAB2(SCH_1):P3E_CPU1_PE3_MP_C_TXN<8>
   H6  P3E_CPU1_PE3_MP_C_TXN<15>   IOH6  @BASEBOARD_FAB2_LIB.BASEBOARD_FAB2(SCH_1):P3E_CPU1_PE3_MP_C_TXN<15>
   E6  P3E_CPU1_PE3_MP_C_TXN<14>   IOE6  @BASEBOARD_FAB2_LIB.BASEBOARD_FAB2(SCH_1):P3E_CPU1_PE3_MP_C_TXN<14>
   G7  P3E_CPU1_PE3_MP_C_TXN<13>   IOG7  @BASEBOARD_FAB2_LIB.BASEBOARD_FAB2(SCH_1):P3E_CPU1_PE3_MP_C_TXN<13>
   D7  P3E_CPU1_PE3_MP_C_TXN<12>   IOD7  @BASEBOARD_FAB2_LIB.BASEBOARD_FAB2(SCH_1):P3E_CPU1_PE3_MP_C_TXN<12>
   A7  P3E_CPU1_PE3_MP_C_TXN<11>   IOA7  @BASEBOARD_FAB2_LIB.BASEBOARD_FAB2(SCH_1):P3E_CPU1_PE3_MP_C_TXN<11>
   I8  P3E_CPU1_PE3_MP_C_TXN<10>   IOI8  @BASEBOARD_FAB2_LIB.BASEBOARD_FAB2(SCH_1):P3E_CPU1_PE3_MP_C_TXN<10>
   B5  IRQ_BOARD_BMC_ALERT_N   IOB5  @BASEBOARD_FAB2_LIB.BASEBOARD_FAB2(SCH_1):IRQ_BOARD_BMC_ALERT_N
   J8  GND            GNDJ8  @BASEBOARD_FAB2_LIB.BASEBOARD_FAB2(SCH_1):GND
   J6  GND            GNDJ6  @BASEBOARD_FAB2_LIB.BASEBOARD_FAB2(SCH_1):GND
   J4  GND            GNDJ4  @BASEBOARD_FAB2_LIB.BASEBOARD_FAB2(SCH_1):GND
   J2  GND            GNDJ2  @BASEBOARD_FAB2_LIB.BASEBOARD_FAB2(SCH_1):GND
   I7  GND            GNDI7  @BASEBOARD_FAB2_LIB.BASEBOARD_FAB2(SCH_1):GND
   I5  GND            GNDI5  @BASEBOARD_FAB2_LIB.BASEBOARD_FAB2(SCH_1):GND
   I3  GND            GNDI3  @BASEBOARD_FAB2_LIB.BASEBOARD_FAB2(SCH_1):GND
   I1  GND            GNDI1  @BASEBOARD_FAB2_LIB.BASEBOARD_FAB2(SCH_1):GND
   G8  GND            GNDG8  @BASEBOARD_FAB2_LIB.BASEBOARD_FAB2(SCH_1):GND
   G6  GND            GNDG6  @BASEBOARD_FAB2_LIB.BASEBOARD_FAB2(SCH_1):GND
   G4  GND            GNDG4  @BASEBOARD_FAB2_LIB.BASEBOARD_FAB2(SCH_1):GND
   G2  GND            GNDG2  @BASEBOARD_FAB2_LIB.BASEBOARD_FAB2(SCH_1):GND
   F7  GND            GNDF7  @BASEBOARD_FAB2_LIB.BASEBOARD_FAB2(SCH_1):GND
   F5  GND            GNDF5  @BASEBOARD_FAB2_LIB.BASEBOARD_FAB2(SCH_1):GND
   F3  GND            GNDF3  @BASEBOARD_FAB2_LIB.BASEBOARD_FAB2(SCH_1):GND
   F1  GND            GNDF1  @BASEBOARD_FAB2_LIB.BASEBOARD_FAB2(SCH_1):GND
   D8  GND            GNDD8  @BASEBOARD_FAB2_LIB.BASEBOARD_FAB2(SCH_1):GND
   D6  GND            GNDD6  @BASEBOARD_FAB2_LIB.BASEBOARD_FAB2(SCH_1):GND
   D4  GND            GNDD4  @BASEBOARD_FAB2_LIB.BASEBOARD_FAB2(SCH_1):GND
   D2  GND            GNDD2  @BASEBOARD_FAB2_LIB.BASEBOARD_FAB2(SCH_1):GND
   C7  GND            GNDC7  @BASEBOARD_FAB2_LIB.BASEBOARD_FAB2(SCH_1):GND
   C5  GND            GNDC5  @BASEBOARD_FAB2_LIB.BASEBOARD_FAB2(SCH_1):GND
   C3  GND            GNDC3  @BASEBOARD_FAB2_LIB.BASEBOARD_FAB2(SCH_1):GND
   C1  GND            GNDC1  @BASEBOARD_FAB2_LIB.BASEBOARD_FAB2(SCH_1):GND
   A8  GND            GNDA8  @BASEBOARD_FAB2_LIB.BASEBOARD_FAB2(SCH_1):GND
   A6  GND            GNDA6  @BASEBOARD_FAB2_LIB.BASEBOARD_FAB2(SCH_1):GND
   A4  GND            GNDA4  @BASEBOARD_FAB2_LIB.BASEBOARD_FAB2(SCH_1):GND
   A2  GND            GNDA2  @BASEBOARD_FAB2_LIB.BASEBOARD_FAB2(SCH_1):GND
   H5  FM_XRC_READY_N   IOH5  @BASEBOARD_FAB2_LIB.BASEBOARD_FAB2(SCH_1):FM_XRC_READY_N
   G5  FM_XRC_PRESENT_N   IOG5  @BASEBOARD_FAB2_LIB.BASEBOARD_FAB2(SCH_1):FM_XRC_PRESENT_N
   C4  FM_BB_BMC_MP_GPIO   IOC4  @BASEBOARD_FAB2_LIB.BASEBOARD_FAB2(SCH_1):FM_BB_BMC_MP_GPIO

CONN12_G98257001_THMT  I78  J1D1   [CONN12_G98257001_THMT-CONN,G98A]
   B3  P12V_PSU          B3  @BASEBOARD_FAB2_LIB.BASEBOARD_FAB2(SCH_1):P12V_PSU
   B2  P12V_PSU          B2  @BASEBOARD_FAB2_LIB.BASEBOARD_FAB2(SCH_1):P12V_PSU
   B1  P12V_PSU          B1  @BASEBOARD_FAB2_LIB.BASEBOARD_FAB2(SCH_1):P12V_PSU
   A3  P12V_PSU          A3  @BASEBOARD_FAB2_LIB.BASEBOARD_FAB2(SCH_1):P12V_PSU
   A2  P12V_PSU          A2  @BASEBOARD_FAB2_LIB.BASEBOARD_FAB2(SCH_1):P12V_PSU
   A1  P12V_PSU          A1  @BASEBOARD_FAB2_LIB.BASEBOARD_FAB2(SCH_1):P12V_PSU
   D3  GND               D3  @BASEBOARD_FAB2_LIB.BASEBOARD_FAB2(SCH_1):GND
   D2  GND               D2  @BASEBOARD_FAB2_LIB.BASEBOARD_FAB2(SCH_1):GND
   D1  GND               D1  @BASEBOARD_FAB2_LIB.BASEBOARD_FAB2(SCH_1):GND
   C3  GND               C3  @BASEBOARD_FAB2_LIB.BASEBOARD_FAB2(SCH_1):GND
   C2  GND               C2  @BASEBOARD_FAB2_LIB.BASEBOARD_FAB2(SCH_1):GND
   C1  GND               C1  @BASEBOARD_FAB2_LIB.BASEBOARD_FAB2(SCH_1):GND

CONN12_G98257001_THMT  I29  J1E1   [CONN12_G98257001_THMT-CONN,G98A]
   B3  P12V_PSU          B3  @BASEBOARD_FAB2_LIB.BASEBOARD_FAB2(SCH_1):P12V_PSU
   B2  P12V_PSU          B2  @BASEBOARD_FAB2_LIB.BASEBOARD_FAB2(SCH_1):P12V_PSU
   B1  P12V_PSU          B1  @BASEBOARD_FAB2_LIB.BASEBOARD_FAB2(SCH_1):P12V_PSU
   A3  P12V_PSU          A3  @BASEBOARD_FAB2_LIB.BASEBOARD_FAB2(SCH_1):P12V_PSU
   A2  P12V_PSU          A2  @BASEBOARD_FAB2_LIB.BASEBOARD_FAB2(SCH_1):P12V_PSU
   A1  P12V_PSU          A1  @BASEBOARD_FAB2_LIB.BASEBOARD_FAB2(SCH_1):P12V_PSU
   D3  GND               D3  @BASEBOARD_FAB2_LIB.BASEBOARD_FAB2(SCH_1):GND
   D2  GND               D2  @BASEBOARD_FAB2_LIB.BASEBOARD_FAB2(SCH_1):GND
   D1  GND               D1  @BASEBOARD_FAB2_LIB.BASEBOARD_FAB2(SCH_1):GND
   C3  GND               C3  @BASEBOARD_FAB2_LIB.BASEBOARD_FAB2(SCH_1):GND
   C2  GND               C2  @BASEBOARD_FAB2_LIB.BASEBOARD_FAB2(SCH_1):GND
   C1  GND               C1  @BASEBOARD_FAB2_LIB.BASEBOARD_FAB2(SCH_1):GND

CONN76_H22707001_THMT1  I111  J1F1   [CONN76_H22707001_THMT1-CONN,H2A]
   G3  SPA_MID_DBG_TX_R   IOG3  @BASEBOARD_FAB2_LIB.BASEBOARD_FAB2(SCH_1):SPA_MID_DBG_TX_R
   H3  SPA_MID_DBG_RX_R   IOH3  @BASEBOARD_FAB2_LIB.BASEBOARD_FAB2(SCH_1):SPA_MID_DBG_RX_R
   B6  SMB_BMC_PMBUS_STBY_LVC3_SDA   IOB6  @BASEBOARD_FAB2_LIB.BASEBOARD_FAB2(SCH_1):SMB_BMC_PMBUS_STBY_LVC3_SDA
   C6  SMB_BMC_PMBUS_STBY_LVC3_SCL   IOC6  @BASEBOARD_FAB2_LIB.BASEBOARD_FAB2(SCH_1):SMB_BMC_PMBUS_STBY_LVC3_SCL
   I5  RST_PCIE_MIDPLANE_N  GNDI5  @BASEBOARD_FAB2_LIB.BASEBOARD_FAB2(SCH_1):RST_PCIE_MIDPLANE_N
   E3  P3E_CPU1_PE3_MP_RXP<7>   IOE3  @BASEBOARD_FAB2_LIB.BASEBOARD_FAB2(SCH_1):P3E_CPU1_PE3_MP_RXP<7>
   A3  P3E_CPU1_PE3_MP_RXP<6>   IOA3  @BASEBOARD_FAB2_LIB.BASEBOARD_FAB2(SCH_1):P3E_CPU1_PE3_MP_RXP<6>
   H2  P3E_CPU1_PE3_MP_RXP<5>   IOH2  @BASEBOARD_FAB2_LIB.BASEBOARD_FAB2(SCH_1):P3E_CPU1_PE3_MP_RXP<5>
   F2  P3E_CPU1_PE3_MP_RXP<4>   IOF2  @BASEBOARD_FAB2_LIB.BASEBOARD_FAB2(SCH_1):P3E_CPU1_PE3_MP_RXP<4>
   C2  P3E_CPU1_PE3_MP_RXP<3>   IOC2  @BASEBOARD_FAB2_LIB.BASEBOARD_FAB2(SCH_1):P3E_CPU1_PE3_MP_RXP<3>
   G1  P3E_CPU1_PE3_MP_RXP<2>   IOG1  @BASEBOARD_FAB2_LIB.BASEBOARD_FAB2(SCH_1):P3E_CPU1_PE3_MP_RXP<2>
   E1  P3E_CPU1_PE3_MP_RXP<1>   IOE1  @BASEBOARD_FAB2_LIB.BASEBOARD_FAB2(SCH_1):P3E_CPU1_PE3_MP_RXP<1>
   B1  P3E_CPU1_PE3_MP_RXP<0>   IOB1  @BASEBOARD_FAB2_LIB.BASEBOARD_FAB2(SCH_1):P3E_CPU1_PE3_MP_RXP<0>
   D3  P3E_CPU1_PE3_MP_RXN<7>   IOD3  @BASEBOARD_FAB2_LIB.BASEBOARD_FAB2(SCH_1):P3E_CPU1_PE3_MP_RXN<7>
   B3  P3E_CPU1_PE3_MP_RXN<6>   IOB3  @BASEBOARD_FAB2_LIB.BASEBOARD_FAB2(SCH_1):P3E_CPU1_PE3_MP_RXN<6>
   I2  P3E_CPU1_PE3_MP_RXN<5>   IOI2  @BASEBOARD_FAB2_LIB.BASEBOARD_FAB2(SCH_1):P3E_CPU1_PE3_MP_RXN<5>
   E2  P3E_CPU1_PE3_MP_RXN<4>   IOE2  @BASEBOARD_FAB2_LIB.BASEBOARD_FAB2(SCH_1):P3E_CPU1_PE3_MP_RXN<4>
   B2  P3E_CPU1_PE3_MP_RXN<3>   IOB2  @BASEBOARD_FAB2_LIB.BASEBOARD_FAB2(SCH_1):P3E_CPU1_PE3_MP_RXN<3>
   H1  P3E_CPU1_PE3_MP_RXN<2>   IOH1  @BASEBOARD_FAB2_LIB.BASEBOARD_FAB2(SCH_1):P3E_CPU1_PE3_MP_RXN<2>
   D1  P3E_CPU1_PE3_MP_RXN<1>   IOD1  @BASEBOARD_FAB2_LIB.BASEBOARD_FAB2(SCH_1):P3E_CPU1_PE3_MP_RXN<1>
   A1  P3E_CPU1_PE3_MP_RXN<0>   IOA1  @BASEBOARD_FAB2_LIB.BASEBOARD_FAB2(SCH_1):P3E_CPU1_PE3_MP_RXN<0>
   H6  P3E_CPU1_PE3_MP_C_TXP<7>   IOH6  @BASEBOARD_FAB2_LIB.BASEBOARD_FAB2(SCH_1):P3E_CPU1_PE3_MP_C_TXP<7>
   F6  P3E_CPU1_PE3_MP_C_TXP<6>   IOF6  @BASEBOARD_FAB2_LIB.BASEBOARD_FAB2(SCH_1):P3E_CPU1_PE3_MP_C_TXP<6>
   G7  P3E_CPU1_PE3_MP_C_TXP<5>   IOG7  @BASEBOARD_FAB2_LIB.BASEBOARD_FAB2(SCH_1):P3E_CPU1_PE3_MP_C_TXP<5>
   E7  P3E_CPU1_PE3_MP_C_TXP<4>   IOE7  @BASEBOARD_FAB2_LIB.BASEBOARD_FAB2(SCH_1):P3E_CPU1_PE3_MP_C_TXP<4>
   B7  P3E_CPU1_PE3_MP_C_TXP<3>   IOB7  @BASEBOARD_FAB2_LIB.BASEBOARD_FAB2(SCH_1):P3E_CPU1_PE3_MP_C_TXP<3>
   I8  P3E_CPU1_PE3_MP_C_TXP<2>   IOI8  @BASEBOARD_FAB2_LIB.BASEBOARD_FAB2(SCH_1):P3E_CPU1_PE3_MP_C_TXP<2>
   F8  P3E_CPU1_PE3_MP_C_TXP<1>   IOF8  @BASEBOARD_FAB2_LIB.BASEBOARD_FAB2(SCH_1):P3E_CPU1_PE3_MP_C_TXP<1>
   C8  P3E_CPU1_PE3_MP_C_TXP<0>   IOC8  @BASEBOARD_FAB2_LIB.BASEBOARD_FAB2(SCH_1):P3E_CPU1_PE3_MP_C_TXP<0>
   I6  P3E_CPU1_PE3_MP_C_TXN<7>   IOI6  @BASEBOARD_FAB2_LIB.BASEBOARD_FAB2(SCH_1):P3E_CPU1_PE3_MP_C_TXN<7>
   E6  P3E_CPU1_PE3_MP_C_TXN<6>   IOE6  @BASEBOARD_FAB2_LIB.BASEBOARD_FAB2(SCH_1):P3E_CPU1_PE3_MP_C_TXN<6>
   H7  P3E_CPU1_PE3_MP_C_TXN<5>   IOH7  @BASEBOARD_FAB2_LIB.BASEBOARD_FAB2(SCH_1):P3E_CPU1_PE3_MP_C_TXN<5>
   D7  P3E_CPU1_PE3_MP_C_TXN<4>   IOD7  @BASEBOARD_FAB2_LIB.BASEBOARD_FAB2(SCH_1):P3E_CPU1_PE3_MP_C_TXN<4>
   A7  P3E_CPU1_PE3_MP_C_TXN<3>   IOA7  @BASEBOARD_FAB2_LIB.BASEBOARD_FAB2(SCH_1):P3E_CPU1_PE3_MP_C_TXN<3>
   H8  P3E_CPU1_PE3_MP_C_TXN<2>   IOH8  @BASEBOARD_FAB2_LIB.BASEBOARD_FAB2(SCH_1):P3E_CPU1_PE3_MP_C_TXN<2>
   E8  P3E_CPU1_PE3_MP_C_TXN<1>   IOE8  @BASEBOARD_FAB2_LIB.BASEBOARD_FAB2(SCH_1):P3E_CPU1_PE3_MP_C_TXN<1>
   B8  P3E_CPU1_PE3_MP_C_TXN<0>   IOB8  @BASEBOARD_FAB2_LIB.BASEBOARD_FAB2(SCH_1):P3E_CPU1_PE3_MP_C_TXN<0>
   A5  NIC_MDI_MNG_TX_DP   IOA5  @BASEBOARD_FAB2_LIB.BASEBOARD_FAB2(SCH_1):NIC_MDI_MNG_TX_DP
   B5  NIC_MDI_MNG_TX_DN   IOB5  @BASEBOARD_FAB2_LIB.BASEBOARD_FAB2(SCH_1):NIC_MDI_MNG_TX_DN
   D5  NIC_MDI_MNG_RX_DP   IOD5  @BASEBOARD_FAB2_LIB.BASEBOARD_FAB2(SCH_1):NIC_MDI_MNG_RX_DP
   E5  NIC_MDI_MNG_RX_DN   IOE5  @BASEBOARD_FAB2_LIB.BASEBOARD_FAB2(SCH_1):NIC_MDI_MNG_RX_DN
   A6  IRQ_SML1_PMBUS_ALERT_R_N  GNDA6  @BASEBOARD_FAB2_LIB.BASEBOARD_FAB2(SCH_1):IRQ_SML1_PMBUS_ALERT_R_N
   J8  GND            GNDJ8  @BASEBOARD_FAB2_LIB.BASEBOARD_FAB2(SCH_1):GND
   J6  GND            GNDJ6  @BASEBOARD_FAB2_LIB.BASEBOARD_FAB2(SCH_1):GND
   J4  GND            GNDJ4  @BASEBOARD_FAB2_LIB.BASEBOARD_FAB2(SCH_1):GND
   J2  GND            GNDJ2  @BASEBOARD_FAB2_LIB.BASEBOARD_FAB2(SCH_1):GND
   I7  GND            GNDI7  @BASEBOARD_FAB2_LIB.BASEBOARD_FAB2(SCH_1):GND
   I1  GND            GNDI1  @BASEBOARD_FAB2_LIB.BASEBOARD_FAB2(SCH_1):GND
   G8  GND            GNDG8  @BASEBOARD_FAB2_LIB.BASEBOARD_FAB2(SCH_1):GND
   G6  GND            GNDG6  @BASEBOARD_FAB2_LIB.BASEBOARD_FAB2(SCH_1):GND
   G4  GND            GNDG4  @BASEBOARD_FAB2_LIB.BASEBOARD_FAB2(SCH_1):GND
   G2  GND            GNDG2  @BASEBOARD_FAB2_LIB.BASEBOARD_FAB2(SCH_1):GND
   F7  GND            GNDF7  @BASEBOARD_FAB2_LIB.BASEBOARD_FAB2(SCH_1):GND
   F3  GND            GNDF3  @BASEBOARD_FAB2_LIB.BASEBOARD_FAB2(SCH_1):GND
   F1  GND            GNDF1  @BASEBOARD_FAB2_LIB.BASEBOARD_FAB2(SCH_1):GND
   D8  GND            GNDD8  @BASEBOARD_FAB2_LIB.BASEBOARD_FAB2(SCH_1):GND
   D6  GND            GNDD6  @BASEBOARD_FAB2_LIB.BASEBOARD_FAB2(SCH_1):GND
   D2  GND            GNDD2  @BASEBOARD_FAB2_LIB.BASEBOARD_FAB2(SCH_1):GND
   C7  GND            GNDC7  @BASEBOARD_FAB2_LIB.BASEBOARD_FAB2(SCH_1):GND
   C5  GND            GNDC5  @BASEBOARD_FAB2_LIB.BASEBOARD_FAB2(SCH_1):GND
   C3  GND            GNDC3  @BASEBOARD_FAB2_LIB.BASEBOARD_FAB2(SCH_1):GND
   C1  GND            GNDC1  @BASEBOARD_FAB2_LIB.BASEBOARD_FAB2(SCH_1):GND
   A8  GND            GNDA8  @BASEBOARD_FAB2_LIB.BASEBOARD_FAB2(SCH_1):GND
   A2  GND            GNDA2  @BASEBOARD_FAB2_LIB.BASEBOARD_FAB2(SCH_1):GND
   H5  FM_MB_SLOT_ID2   IOH5  @BASEBOARD_FAB2_LIB.BASEBOARD_FAB2(SCH_1):FM_MB_SLOT_ID2
   G5  FM_MB_SLOT_ID1   IOG5  @BASEBOARD_FAB2_LIB.BASEBOARD_FAB2(SCH_1):FM_MB_SLOT_ID1
   F5  FM_MB_SLOT_ID0  GNDF5  @BASEBOARD_FAB2_LIB.BASEBOARD_FAB2(SCH_1):FM_MB_SLOT_ID0
   E4  FM_MATED_IN_N   IOE4  @BASEBOARD_FAB2_LIB.BASEBOARD_FAB2(SCH_1):FM_MATED_IN_N
   I3  FM_ENABLE_FAN_POWER  GNDI3  @BASEBOARD_FAB2_LIB.BASEBOARD_FAB2(SCH_1):FM_ENABLE_FAN_POWER
   A4  FAN_TACH3_R    GNDA4  @BASEBOARD_FAB2_LIB.BASEBOARD_FAB2(SCH_1):FAN_TACH3_R
   B4  FAN_TACH2_R     IOB4  @BASEBOARD_FAB2_LIB.BASEBOARD_FAB2(SCH_1):FAN_TACH2_R
   C4  FAN_TACH1_R     IOC4  @BASEBOARD_FAB2_LIB.BASEBOARD_FAB2(SCH_1):FAN_TACH1_R
   D4  FAN_TACH0_R    GNDD4  @BASEBOARD_FAB2_LIB.BASEBOARD_FAB2(SCH_1):FAN_TACH0_R
   F4  FAN_PWM_OUT_SYS0_R1   IOF4  @BASEBOARD_FAB2_LIB.BASEBOARD_FAB2(SCH_1):FAN_PWM_OUT_SYS0_R1
   H4  CLK_100M_AIRMAX8_PE1_DP   IOH4  @BASEBOARD_FAB2_LIB.BASEBOARD_FAB2(SCH_1):CLK_100M_AIRMAX8_PE1_DP
   I4  CLK_100M_AIRMAX8_PE1_DN   IOI4  @BASEBOARD_FAB2_LIB.BASEBOARD_FAB2(SCH_1):CLK_100M_AIRMAX8_PE1_DN

CONN6_C74770005  I1   J1F2   [CONN6_C74770005_PIP-HDR,C74770A]
    6  TP_FAN_0         IO6  @BASEBOARD_FAB2_LIB.BASEBOARD_FAB2(SCH_1):TP_FAN_0
    2  P12V_FAN         IO2  @BASEBOARD_FAB2_LIB.BASEBOARD_FAB2(SCH_1):P12V_FAN
    1  GND              IO1  @BASEBOARD_FAB2_LIB.BASEBOARD_FAB2(SCH_1):GND
    5  FAN_TACH1_CPU1_D1    IO5  @BASEBOARD_FAB2_LIB.BASEBOARD_FAB2(SCH_1):FAN_TACH1_CPU1_D1
    3  FAN_TACH0_CPU0_D1    IO3  @BASEBOARD_FAB2_LIB.BASEBOARD_FAB2(SCH_1):FAN_TACH0_CPU0_D1
    4  FAN_PWM_OUT_SYS0_R    IO4  @BASEBOARD_FAB2_LIB.BASEBOARD_FAB2(SCH_1):FAN_PWM_OUT_SYS0_R

CONN8_H62179001_PIP  I189  J1F3   [CONN8_H62179001_PIP-CONN,H6217A]
    6  SMB_BMC_PMBUS_STBY_LVC3_SDA    IO6  @BASEBOARD_FAB2_LIB.BASEBOARD_FAB2(SCH_1):SMB_BMC_PMBUS_STBY_LVC3_SDA
    7  SMB_BMC_PMBUS_STBY_LVC3_SCL    IO7  @BASEBOARD_FAB2_LIB.BASEBOARD_FAB2(SCH_1):SMB_BMC_PMBUS_STBY_LVC3_SCL
    1  P3V3_STBY        IO1  @BASEBOARD_FAB2_LIB.BASEBOARD_FAB2(SCH_1):P3V3_STBY
    5  IRQ_SML1_PMBUS_ALERT_R_N    IO5  @BASEBOARD_FAB2_LIB.BASEBOARD_FAB2(SCH_1):IRQ_SML1_PMBUS_ALERT_R_N
    8  GND              IO8  @BASEBOARD_FAB2_LIB.BASEBOARD_FAB2(SCH_1):GND
    2  FM_MP_PS_REDUNDANT_LOST_N    IO2  @BASEBOARD_FAB2_LIB.BASEBOARD_FAB2(SCH_1):FM_MP_PS_REDUNDANT_LOST_N
    3  FM_MP_PS_FAIL_N    IO3  @BASEBOARD_FAB2_LIB.BASEBOARD_FAB2(SCH_1):FM_MP_PS_FAIL_N
    4  FM_MATED_IN_N    IO4  @BASEBOARD_FAB2_LIB.BASEBOARD_FAB2(SCH_1):FM_MATED_IN_N

SCONN288_H44441004_PIP  I171  J1G1   [SCONN288_H44441004_PIP-SCONN,HA]
   77  PVTT_GHJ       VTT<1>  @BASEBOARD_FAB2_LIB.BASEBOARD_FAB2(SCH_1):PVTT_GHJ
  221  PVTT_GHJ       VTT<0>  @BASEBOARD_FAB2_LIB.BASEBOARD_FAB2(SCH_1):PVTT_GHJ
  142  PVPP_GHJ       VPP<4>  @BASEBOARD_FAB2_LIB.BASEBOARD_FAB2(SCH_1):PVPP_GHJ
  143  PVPP_GHJ       VPP<3>  @BASEBOARD_FAB2_LIB.BASEBOARD_FAB2(SCH_1):PVPP_GHJ
  288  PVPP_GHJ       VPP<2>  @BASEBOARD_FAB2_LIB.BASEBOARD_FAB2(SCH_1):PVPP_GHJ
  286  PVPP_GHJ       VPP<1>  @BASEBOARD_FAB2_LIB.BASEBOARD_FAB2(SCH_1):PVPP_GHJ
  287  PVPP_GHJ       VPP<0>  @BASEBOARD_FAB2_LIB.BASEBOARD_FAB2(SCH_1):PVPP_GHJ
   59  PVDDQ_GHJ      VDD<25>  @BASEBOARD_FAB2_LIB.BASEBOARD_FAB2(SCH_1):PVDDQ_GHJ
   61  PVDDQ_GHJ      VDD<24>  @BASEBOARD_FAB2_LIB.BASEBOARD_FAB2(SCH_1):PVDDQ_GHJ
   64  PVDDQ_GHJ      VDD<23>  @BASEBOARD_FAB2_LIB.BASEBOARD_FAB2(SCH_1):PVDDQ_GHJ
   67  PVDDQ_GHJ      VDD<22>  @BASEBOARD_FAB2_LIB.BASEBOARD_FAB2(SCH_1):PVDDQ_GHJ
   70  PVDDQ_GHJ      VDD<21>  @BASEBOARD_FAB2_LIB.BASEBOARD_FAB2(SCH_1):PVDDQ_GHJ
   73  PVDDQ_GHJ      VDD<20>  @BASEBOARD_FAB2_LIB.BASEBOARD_FAB2(SCH_1):PVDDQ_GHJ
   76  PVDDQ_GHJ      VDD<19>  @BASEBOARD_FAB2_LIB.BASEBOARD_FAB2(SCH_1):PVDDQ_GHJ
   80  PVDDQ_GHJ      VDD<18>  @BASEBOARD_FAB2_LIB.BASEBOARD_FAB2(SCH_1):PVDDQ_GHJ
   83  PVDDQ_GHJ      VDD<17>  @BASEBOARD_FAB2_LIB.BASEBOARD_FAB2(SCH_1):PVDDQ_GHJ
   85  PVDDQ_GHJ      VDD<16>  @BASEBOARD_FAB2_LIB.BASEBOARD_FAB2(SCH_1):PVDDQ_GHJ
   88  PVDDQ_GHJ      VDD<15>  @BASEBOARD_FAB2_LIB.BASEBOARD_FAB2(SCH_1):PVDDQ_GHJ
   90  PVDDQ_GHJ      VDD<14>  @BASEBOARD_FAB2_LIB.BASEBOARD_FAB2(SCH_1):PVDDQ_GHJ
   92  PVDDQ_GHJ      VDD<13>  @BASEBOARD_FAB2_LIB.BASEBOARD_FAB2(SCH_1):PVDDQ_GHJ
  204  PVDDQ_GHJ      VDD<12>  @BASEBOARD_FAB2_LIB.BASEBOARD_FAB2(SCH_1):PVDDQ_GHJ
  206  PVDDQ_GHJ      VDD<11>  @BASEBOARD_FAB2_LIB.BASEBOARD_FAB2(SCH_1):PVDDQ_GHJ
  209  PVDDQ_GHJ      VDD<10>  @BASEBOARD_FAB2_LIB.BASEBOARD_FAB2(SCH_1):PVDDQ_GHJ
  212  PVDDQ_GHJ      VDD<9>  @BASEBOARD_FAB2_LIB.BASEBOARD_FAB2(SCH_1):PVDDQ_GHJ
  215  PVDDQ_GHJ      VDD<8>  @BASEBOARD_FAB2_LIB.BASEBOARD_FAB2(SCH_1):PVDDQ_GHJ
  217  PVDDQ_GHJ      VDD<7>  @BASEBOARD_FAB2_LIB.BASEBOARD_FAB2(SCH_1):PVDDQ_GHJ
  220  PVDDQ_GHJ      VDD<6>  @BASEBOARD_FAB2_LIB.BASEBOARD_FAB2(SCH_1):PVDDQ_GHJ
  223  PVDDQ_GHJ      VDD<5>  @BASEBOARD_FAB2_LIB.BASEBOARD_FAB2(SCH_1):PVDDQ_GHJ
  226  PVDDQ_GHJ      VDD<4>  @BASEBOARD_FAB2_LIB.BASEBOARD_FAB2(SCH_1):PVDDQ_GHJ
  229  PVDDQ_GHJ      VDD<3>  @BASEBOARD_FAB2_LIB.BASEBOARD_FAB2(SCH_1):PVDDQ_GHJ
  231  PVDDQ_GHJ      VDD<2>  @BASEBOARD_FAB2_LIB.BASEBOARD_FAB2(SCH_1):PVDDQ_GHJ
  233  PVDDQ_GHJ      VDD<1>  @BASEBOARD_FAB2_LIB.BASEBOARD_FAB2(SCH_1):PVDDQ_GHJ
  236  PVDDQ_GHJ      VDD<0>  @BASEBOARD_FAB2_LIB.BASEBOARD_FAB2(SCH_1):PVDDQ_GHJ
    1  P12V_NVDIMM_GHJ  12V<1>  @BASEBOARD_FAB2_LIB.BASEBOARD_FAB2(SCH_1):P12V_NVDIMM_GHJ
  145  P12V_NVDIMM_GHJ  12V<0>  @BASEBOARD_FAB2_LIB.BASEBOARD_FAB2(SCH_1):P12V_NVDIMM_GHJ

SCONN288_H44441004_PIP  I43  J1G1   [SCONN288_H44441004_PIP-SCONN,HA]
    2  GND            VSS<93>  @BASEBOARD_FAB2_LIB.BASEBOARD_FAB2(SCH_1):GND
    4  GND            VSS<92>  @BASEBOARD_FAB2_LIB.BASEBOARD_FAB2(SCH_1):GND
    6  GND            VSS<91>  @BASEBOARD_FAB2_LIB.BASEBOARD_FAB2(SCH_1):GND
    9  GND            VSS<90>  @BASEBOARD_FAB2_LIB.BASEBOARD_FAB2(SCH_1):GND
   11  GND            VSS<89>  @BASEBOARD_FAB2_LIB.BASEBOARD_FAB2(SCH_1):GND
   13  GND            VSS<88>  @BASEBOARD_FAB2_LIB.BASEBOARD_FAB2(SCH_1):GND
   15  GND            VSS<87>  @BASEBOARD_FAB2_LIB.BASEBOARD_FAB2(SCH_1):GND
   17  GND            VSS<86>  @BASEBOARD_FAB2_LIB.BASEBOARD_FAB2(SCH_1):GND
   20  GND            VSS<85>  @BASEBOARD_FAB2_LIB.BASEBOARD_FAB2(SCH_1):GND
   22  GND            VSS<84>  @BASEBOARD_FAB2_LIB.BASEBOARD_FAB2(SCH_1):GND
   24  GND            VSS<83>  @BASEBOARD_FAB2_LIB.BASEBOARD_FAB2(SCH_1):GND
   26  GND            VSS<82>  @BASEBOARD_FAB2_LIB.BASEBOARD_FAB2(SCH_1):GND
   28  GND            VSS<81>  @BASEBOARD_FAB2_LIB.BASEBOARD_FAB2(SCH_1):GND
   31  GND            VSS<80>  @BASEBOARD_FAB2_LIB.BASEBOARD_FAB2(SCH_1):GND
   33  GND            VSS<79>  @BASEBOARD_FAB2_LIB.BASEBOARD_FAB2(SCH_1):GND
   35  GND            VSS<78>  @BASEBOARD_FAB2_LIB.BASEBOARD_FAB2(SCH_1):GND
   37  GND            VSS<77>  @BASEBOARD_FAB2_LIB.BASEBOARD_FAB2(SCH_1):GND
   39  GND            VSS<76>  @BASEBOARD_FAB2_LIB.BASEBOARD_FAB2(SCH_1):GND
   42  GND            VSS<75>  @BASEBOARD_FAB2_LIB.BASEBOARD_FAB2(SCH_1):GND
   44  GND            VSS<74>  @BASEBOARD_FAB2_LIB.BASEBOARD_FAB2(SCH_1):GND
   46  GND            VSS<73>  @BASEBOARD_FAB2_LIB.BASEBOARD_FAB2(SCH_1):GND
   48  GND            VSS<72>  @BASEBOARD_FAB2_LIB.BASEBOARD_FAB2(SCH_1):GND
   50  GND            VSS<71>  @BASEBOARD_FAB2_LIB.BASEBOARD_FAB2(SCH_1):GND
   53  GND            VSS<70>  @BASEBOARD_FAB2_LIB.BASEBOARD_FAB2(SCH_1):GND
   55  GND            VSS<69>  @BASEBOARD_FAB2_LIB.BASEBOARD_FAB2(SCH_1):GND
   57  GND            VSS<68>  @BASEBOARD_FAB2_LIB.BASEBOARD_FAB2(SCH_1):GND
   94  GND            VSS<67>  @BASEBOARD_FAB2_LIB.BASEBOARD_FAB2(SCH_1):GND
   96  GND            VSS<66>  @BASEBOARD_FAB2_LIB.BASEBOARD_FAB2(SCH_1):GND
   98  GND            VSS<65>  @BASEBOARD_FAB2_LIB.BASEBOARD_FAB2(SCH_1):GND
  101  GND            VSS<64>  @BASEBOARD_FAB2_LIB.BASEBOARD_FAB2(SCH_1):GND
  103  GND            VSS<63>  @BASEBOARD_FAB2_LIB.BASEBOARD_FAB2(SCH_1):GND
  105  GND            VSS<62>  @BASEBOARD_FAB2_LIB.BASEBOARD_FAB2(SCH_1):GND
  107  GND            VSS<61>  @BASEBOARD_FAB2_LIB.BASEBOARD_FAB2(SCH_1):GND
  109  GND            VSS<60>  @BASEBOARD_FAB2_LIB.BASEBOARD_FAB2(SCH_1):GND
  112  GND            VSS<59>  @BASEBOARD_FAB2_LIB.BASEBOARD_FAB2(SCH_1):GND
  114  GND            VSS<58>  @BASEBOARD_FAB2_LIB.BASEBOARD_FAB2(SCH_1):GND
  116  GND            VSS<57>  @BASEBOARD_FAB2_LIB.BASEBOARD_FAB2(SCH_1):GND
  118  GND            VSS<56>  @BASEBOARD_FAB2_LIB.BASEBOARD_FAB2(SCH_1):GND
  120  GND            VSS<55>  @BASEBOARD_FAB2_LIB.BASEBOARD_FAB2(SCH_1):GND
  123  GND            VSS<54>  @BASEBOARD_FAB2_LIB.BASEBOARD_FAB2(SCH_1):GND
  125  GND            VSS<53>  @BASEBOARD_FAB2_LIB.BASEBOARD_FAB2(SCH_1):GND
  127  GND            VSS<52>  @BASEBOARD_FAB2_LIB.BASEBOARD_FAB2(SCH_1):GND
  129  GND            VSS<51>  @BASEBOARD_FAB2_LIB.BASEBOARD_FAB2(SCH_1):GND
  131  GND            VSS<50>  @BASEBOARD_FAB2_LIB.BASEBOARD_FAB2(SCH_1):GND
  134  GND            VSS<49>  @BASEBOARD_FAB2_LIB.BASEBOARD_FAB2(SCH_1):GND
  136  GND            VSS<48>  @BASEBOARD_FAB2_LIB.BASEBOARD_FAB2(SCH_1):GND
  138  GND            VSS<47>  @BASEBOARD_FAB2_LIB.BASEBOARD_FAB2(SCH_1):GND
  147  GND            VSS<46>  @BASEBOARD_FAB2_LIB.BASEBOARD_FAB2(SCH_1):GND
  149  GND            VSS<45>  @BASEBOARD_FAB2_LIB.BASEBOARD_FAB2(SCH_1):GND
  151  GND            VSS<44>  @BASEBOARD_FAB2_LIB.BASEBOARD_FAB2(SCH_1):GND
  154  GND            VSS<43>  @BASEBOARD_FAB2_LIB.BASEBOARD_FAB2(SCH_1):GND
  156  GND            VSS<42>  @BASEBOARD_FAB2_LIB.BASEBOARD_FAB2(SCH_1):GND
  158  GND            VSS<41>  @BASEBOARD_FAB2_LIB.BASEBOARD_FAB2(SCH_1):GND
  160  GND            VSS<40>  @BASEBOARD_FAB2_LIB.BASEBOARD_FAB2(SCH_1):GND
  162  GND            VSS<39>  @BASEBOARD_FAB2_LIB.BASEBOARD_FAB2(SCH_1):GND
  165  GND            VSS<38>  @BASEBOARD_FAB2_LIB.BASEBOARD_FAB2(SCH_1):GND
  167  GND            VSS<37>  @BASEBOARD_FAB2_LIB.BASEBOARD_FAB2(SCH_1):GND
  169  GND            VSS<36>  @BASEBOARD_FAB2_LIB.BASEBOARD_FAB2(SCH_1):GND
  171  GND            VSS<35>  @BASEBOARD_FAB2_LIB.BASEBOARD_FAB2(SCH_1):GND
  173  GND            VSS<34>  @BASEBOARD_FAB2_LIB.BASEBOARD_FAB2(SCH_1):GND
  176  GND            VSS<33>  @BASEBOARD_FAB2_LIB.BASEBOARD_FAB2(SCH_1):GND
  178  GND            VSS<32>  @BASEBOARD_FAB2_LIB.BASEBOARD_FAB2(SCH_1):GND
  180  GND            VSS<31>  @BASEBOARD_FAB2_LIB.BASEBOARD_FAB2(SCH_1):GND
  182  GND            VSS<30>  @BASEBOARD_FAB2_LIB.BASEBOARD_FAB2(SCH_1):GND
  184  GND            VSS<29>  @BASEBOARD_FAB2_LIB.BASEBOARD_FAB2(SCH_1):GND
  187  GND            VSS<28>  @BASEBOARD_FAB2_LIB.BASEBOARD_FAB2(SCH_1):GND
  189  GND            VSS<27>  @BASEBOARD_FAB2_LIB.BASEBOARD_FAB2(SCH_1):GND
  191  GND            VSS<26>  @BASEBOARD_FAB2_LIB.BASEBOARD_FAB2(SCH_1):GND
  193  GND            VSS<25>  @BASEBOARD_FAB2_LIB.BASEBOARD_FAB2(SCH_1):GND
  195  GND            VSS<24>  @BASEBOARD_FAB2_LIB.BASEBOARD_FAB2(SCH_1):GND
  198  GND            VSS<23>  @BASEBOARD_FAB2_LIB.BASEBOARD_FAB2(SCH_1):GND
  200  GND            VSS<22>  @BASEBOARD_FAB2_LIB.BASEBOARD_FAB2(SCH_1):GND
  202  GND            VSS<21>  @BASEBOARD_FAB2_LIB.BASEBOARD_FAB2(SCH_1):GND
  239  GND            VSS<20>  @BASEBOARD_FAB2_LIB.BASEBOARD_FAB2(SCH_1):GND
  241  GND            VSS<19>  @BASEBOARD_FAB2_LIB.BASEBOARD_FAB2(SCH_1):GND
  243  GND            VSS<18>  @BASEBOARD_FAB2_LIB.BASEBOARD_FAB2(SCH_1):GND
  246  GND            VSS<17>  @BASEBOARD_FAB2_LIB.BASEBOARD_FAB2(SCH_1):GND
  248  GND            VSS<16>  @BASEBOARD_FAB2_LIB.BASEBOARD_FAB2(SCH_1):GND
  250  GND            VSS<15>  @BASEBOARD_FAB2_LIB.BASEBOARD_FAB2(SCH_1):GND
  252  GND            VSS<14>  @BASEBOARD_FAB2_LIB.BASEBOARD_FAB2(SCH_1):GND
  254  GND            VSS<13>  @BASEBOARD_FAB2_LIB.BASEBOARD_FAB2(SCH_1):GND
  257  GND            VSS<12>  @BASEBOARD_FAB2_LIB.BASEBOARD_FAB2(SCH_1):GND
  259  GND            VSS<11>  @BASEBOARD_FAB2_LIB.BASEBOARD_FAB2(SCH_1):GND
  261  GND            VSS<10>  @BASEBOARD_FAB2_LIB.BASEBOARD_FAB2(SCH_1):GND
  263  GND            VSS<9>  @BASEBOARD_FAB2_LIB.BASEBOARD_FAB2(SCH_1):GND
  265  GND            VSS<8>  @BASEBOARD_FAB2_LIB.BASEBOARD_FAB2(SCH_1):GND
  268  GND            VSS<7>  @BASEBOARD_FAB2_LIB.BASEBOARD_FAB2(SCH_1):GND
  270  GND            VSS<6>  @BASEBOARD_FAB2_LIB.BASEBOARD_FAB2(SCH_1):GND
  272  GND            VSS<5>  @BASEBOARD_FAB2_LIB.BASEBOARD_FAB2(SCH_1):GND
  274  GND            VSS<4>  @BASEBOARD_FAB2_LIB.BASEBOARD_FAB2(SCH_1):GND
  276  GND            VSS<3>  @BASEBOARD_FAB2_LIB.BASEBOARD_FAB2(SCH_1):GND
  279  GND            VSS<2>  @BASEBOARD_FAB2_LIB.BASEBOARD_FAB2(SCH_1):GND
  281  GND            VSS<1>  @BASEBOARD_FAB2_LIB.BASEBOARD_FAB2(SCH_1):GND
  283  GND            VSS<0>  @BASEBOARD_FAB2_LIB.BASEBOARD_FAB2(SCH_1):GND

SCONN288_H44441004_PIP  I66  J1G1   [SCONN288_H44441004_PIP-SCONN,HA]
    7  M_G_DQS_DP<9>  DQS9P  @BASEBOARD_FAB2_LIB.BASEBOARD_FAB2(SCH_1):M_G_DQS_DP<9>
  197  M_G_DQS_DP<8>  DQS8P  @BASEBOARD_FAB2_LIB.BASEBOARD_FAB2(SCH_1):M_G_DQS_DP<8>
  278  M_G_DQS_DP<7>  DQS7P  @BASEBOARD_FAB2_LIB.BASEBOARD_FAB2(SCH_1):M_G_DQS_DP<7>
  267  M_G_DQS_DP<6>  DQS6P  @BASEBOARD_FAB2_LIB.BASEBOARD_FAB2(SCH_1):M_G_DQS_DP<6>
  256  M_G_DQS_DP<5>  DQS5P  @BASEBOARD_FAB2_LIB.BASEBOARD_FAB2(SCH_1):M_G_DQS_DP<5>
  245  M_G_DQS_DP<4>  DQS4P  @BASEBOARD_FAB2_LIB.BASEBOARD_FAB2(SCH_1):M_G_DQS_DP<4>
  186  M_G_DQS_DP<3>  DQS3P  @BASEBOARD_FAB2_LIB.BASEBOARD_FAB2(SCH_1):M_G_DQS_DP<3>
  175  M_G_DQS_DP<2>  DQS2P  @BASEBOARD_FAB2_LIB.BASEBOARD_FAB2(SCH_1):M_G_DQS_DP<2>
  164  M_G_DQS_DP<1>  DQS1P  @BASEBOARD_FAB2_LIB.BASEBOARD_FAB2(SCH_1):M_G_DQS_DP<1>
   51  M_G_DQS_DP<17>  DQS17P  @BASEBOARD_FAB2_LIB.BASEBOARD_FAB2(SCH_1):M_G_DQS_DP<17>
  132  M_G_DQS_DP<16>  DQS16P  @BASEBOARD_FAB2_LIB.BASEBOARD_FAB2(SCH_1):M_G_DQS_DP<16>
  121  M_G_DQS_DP<15>  DQS15P  @BASEBOARD_FAB2_LIB.BASEBOARD_FAB2(SCH_1):M_G_DQS_DP<15>
  110  M_G_DQS_DP<14>  DQS14P  @BASEBOARD_FAB2_LIB.BASEBOARD_FAB2(SCH_1):M_G_DQS_DP<14>
   99  M_G_DQS_DP<13>  DQS13P  @BASEBOARD_FAB2_LIB.BASEBOARD_FAB2(SCH_1):M_G_DQS_DP<13>
   40  M_G_DQS_DP<12>  DQS12P  @BASEBOARD_FAB2_LIB.BASEBOARD_FAB2(SCH_1):M_G_DQS_DP<12>
   29  M_G_DQS_DP<11>  DQS11P  @BASEBOARD_FAB2_LIB.BASEBOARD_FAB2(SCH_1):M_G_DQS_DP<11>
   18  M_G_DQS_DP<10>  DQS10P  @BASEBOARD_FAB2_LIB.BASEBOARD_FAB2(SCH_1):M_G_DQS_DP<10>
  153  M_G_DQS_DP<0>  DQS0P  @BASEBOARD_FAB2_LIB.BASEBOARD_FAB2(SCH_1):M_G_DQS_DP<0>
    8  M_G_DQS_DN<9>  DQS9N  @BASEBOARD_FAB2_LIB.BASEBOARD_FAB2(SCH_1):M_G_DQS_DN<9>
  196  M_G_DQS_DN<8>  DQS8N  @BASEBOARD_FAB2_LIB.BASEBOARD_FAB2(SCH_1):M_G_DQS_DN<8>
  277  M_G_DQS_DN<7>  DQS7N  @BASEBOARD_FAB2_LIB.BASEBOARD_FAB2(SCH_1):M_G_DQS_DN<7>
  266  M_G_DQS_DN<6>  DQS6N  @BASEBOARD_FAB2_LIB.BASEBOARD_FAB2(SCH_1):M_G_DQS_DN<6>
  255  M_G_DQS_DN<5>  DQS5N  @BASEBOARD_FAB2_LIB.BASEBOARD_FAB2(SCH_1):M_G_DQS_DN<5>
  244  M_G_DQS_DN<4>  DQS4N  @BASEBOARD_FAB2_LIB.BASEBOARD_FAB2(SCH_1):M_G_DQS_DN<4>
  185  M_G_DQS_DN<3>  DQS3N  @BASEBOARD_FAB2_LIB.BASEBOARD_FAB2(SCH_1):M_G_DQS_DN<3>
  174  M_G_DQS_DN<2>  DQS2N  @BASEBOARD_FAB2_LIB.BASEBOARD_FAB2(SCH_1):M_G_DQS_DN<2>
  163  M_G_DQS_DN<1>  DQS1N  @BASEBOARD_FAB2_LIB.BASEBOARD_FAB2(SCH_1):M_G_DQS_DN<1>
   52  M_G_DQS_DN<17>  DQS17N  @BASEBOARD_FAB2_LIB.BASEBOARD_FAB2(SCH_1):M_G_DQS_DN<17>
  133  M_G_DQS_DN<16>  DQS16N  @BASEBOARD_FAB2_LIB.BASEBOARD_FAB2(SCH_1):M_G_DQS_DN<16>
  122  M_G_DQS_DN<15>  DQS15N  @BASEBOARD_FAB2_LIB.BASEBOARD_FAB2(SCH_1):M_G_DQS_DN<15>
  111  M_G_DQS_DN<14>  DQS14N  @BASEBOARD_FAB2_LIB.BASEBOARD_FAB2(SCH_1):M_G_DQS_DN<14>
  100  M_G_DQS_DN<13>  DQS13N  @BASEBOARD_FAB2_LIB.BASEBOARD_FAB2(SCH_1):M_G_DQS_DN<13>
   41  M_G_DQS_DN<12>  DQS12N  @BASEBOARD_FAB2_LIB.BASEBOARD_FAB2(SCH_1):M_G_DQS_DN<12>
   30  M_G_DQS_DN<11>  DQS11N  @BASEBOARD_FAB2_LIB.BASEBOARD_FAB2(SCH_1):M_G_DQS_DN<11>
   19  M_G_DQS_DN<10>  DQS10N  @BASEBOARD_FAB2_LIB.BASEBOARD_FAB2(SCH_1):M_G_DQS_DN<10>
  152  M_G_DQS_DN<0>  DQS0N  @BASEBOARD_FAB2_LIB.BASEBOARD_FAB2(SCH_1):M_G_DQS_DN<0>

SCONN288_H44441004_PIP  I111  J1G1   [SCONN288_H44441004_PIP-SCONN,HA]
  144  TP_CH_G_DIMM_G0_RFU_2  RFU<2>  @BASEBOARD_FAB2_LIB.BASEBOARD_FAB2(SCH_1):TP_CH_G_DIMM_G0_RFU_2
  227  TP_CH_G_DIMM_G0_RFU_1  RFU<1>  @BASEBOARD_FAB2_LIB.BASEBOARD_FAB2(SCH_1):TP_CH_G_DIMM_G0_RFU_1
  205  TP_CH_G_DIMM_G0_RFU_0  RFU<0>  @BASEBOARD_FAB2_LIB.BASEBOARD_FAB2(SCH_1):TP_CH_G_DIMM_G0_RFU_0
  285  SMB_DDR_GHJ_VPP_SDA    SDA  @BASEBOARD_FAB2_LIB.BASEBOARD_FAB2(SCH_1):SMB_DDR_GHJ_VPP_SDA
  141  SMB_DDR_GHJ_VPP_SCL    SCL  @BASEBOARD_FAB2_LIB.BASEBOARD_FAB2(SCH_1):SMB_DDR_GHJ_VPP_SCL
  284  PVPP_GHJ       VDDSPD  @BASEBOARD_FAB2_LIB.BASEBOARD_FAB2(SCH_1):PVPP_GHJ
  146  M_G_VREF       VREFCA  @BASEBOARD_FAB2_LIB.BASEBOARD_FAB2(SCH_1):M_G_VREF
  222  M_G_PAR          PAR  @BASEBOARD_FAB2_LIB.BASEBOARD_FAB2(SCH_1):M_G_PAR
   91  M_G_ODT<1>     ODT<1>  @BASEBOARD_FAB2_LIB.BASEBOARD_FAB2(SCH_1):M_G_ODT<1>
   87  M_G_ODT<0>     ODT<0>  @BASEBOARD_FAB2_LIB.BASEBOARD_FAB2(SCH_1):M_G_ODT<0>
   66  M_G_MA<9>         A9  @BASEBOARD_FAB2_LIB.BASEBOARD_FAB2(SCH_1):M_G_MA<9>
   68  M_G_MA<8>         A8  @BASEBOARD_FAB2_LIB.BASEBOARD_FAB2(SCH_1):M_G_MA<8>
  211  M_G_MA<7>         A7  @BASEBOARD_FAB2_LIB.BASEBOARD_FAB2(SCH_1):M_G_MA<7>
   69  M_G_MA<6>         A6  @BASEBOARD_FAB2_LIB.BASEBOARD_FAB2(SCH_1):M_G_MA<6>
  213  M_G_MA<5>         A5  @BASEBOARD_FAB2_LIB.BASEBOARD_FAB2(SCH_1):M_G_MA<5>
  214  M_G_MA<4>         A4  @BASEBOARD_FAB2_LIB.BASEBOARD_FAB2(SCH_1):M_G_MA<4>
   71  M_G_MA<3>         A3  @BASEBOARD_FAB2_LIB.BASEBOARD_FAB2(SCH_1):M_G_MA<3>
  216  M_G_MA<2>         A2  @BASEBOARD_FAB2_LIB.BASEBOARD_FAB2(SCH_1):M_G_MA<2>
   72  M_G_MA<1>         A1  @BASEBOARD_FAB2_LIB.BASEBOARD_FAB2(SCH_1):M_G_MA<1>
  234  M_G_MA<17>       A17  @BASEBOARD_FAB2_LIB.BASEBOARD_FAB2(SCH_1):M_G_MA<17>
   82  M_G_MA<16>     A16_RAS_N  @BASEBOARD_FAB2_LIB.BASEBOARD_FAB2(SCH_1):M_G_MA<16>
   86  M_G_MA<15>     A15_CAS_N  @BASEBOARD_FAB2_LIB.BASEBOARD_FAB2(SCH_1):M_G_MA<15>
  228  M_G_MA<14>     A14_WE_N  @BASEBOARD_FAB2_LIB.BASEBOARD_FAB2(SCH_1):M_G_MA<14>
  232  M_G_MA<13>       A13  @BASEBOARD_FAB2_LIB.BASEBOARD_FAB2(SCH_1):M_G_MA<13>
   65  M_G_MA<12>       A12  @BASEBOARD_FAB2_LIB.BASEBOARD_FAB2(SCH_1):M_G_MA<12>
  210  M_G_MA<11>       A11  @BASEBOARD_FAB2_LIB.BASEBOARD_FAB2(SCH_1):M_G_MA<11>
  225  M_G_MA<10>       A10  @BASEBOARD_FAB2_LIB.BASEBOARD_FAB2(SCH_1):M_G_MA<10>
   79  M_G_MA<0>         A0  @BASEBOARD_FAB2_LIB.BASEBOARD_FAB2(SCH_1):M_G_MA<0>
   54  M_G_ECC<7>     CB<6>  @BASEBOARD_FAB2_LIB.BASEBOARD_FAB2(SCH_1):M_G_ECC<7>
  199  M_G_ECC<6>     CB<7>  @BASEBOARD_FAB2_LIB.BASEBOARD_FAB2(SCH_1):M_G_ECC<6>
   47  M_G_ECC<5>     CB<4>  @BASEBOARD_FAB2_LIB.BASEBOARD_FAB2(SCH_1):M_G_ECC<5>
  192  M_G_ECC<4>     CB<5>  @BASEBOARD_FAB2_LIB.BASEBOARD_FAB2(SCH_1):M_G_ECC<4>
   56  M_G_ECC<3>     CB<2>  @BASEBOARD_FAB2_LIB.BASEBOARD_FAB2(SCH_1):M_G_ECC<3>
  201  M_G_ECC<2>     CB<3>  @BASEBOARD_FAB2_LIB.BASEBOARD_FAB2(SCH_1):M_G_ECC<2>
   49  M_G_ECC<1>     CB<0>  @BASEBOARD_FAB2_LIB.BASEBOARD_FAB2(SCH_1):M_G_ECC<1>
  194  M_G_ECC<0>     CB<1>  @BASEBOARD_FAB2_LIB.BASEBOARD_FAB2(SCH_1):M_G_ECC<0>
   16  M_G_DQ<9>      DQ<8>  @BASEBOARD_FAB2_LIB.BASEBOARD_FAB2(SCH_1):M_G_DQ<9>
  161  M_G_DQ<8>      DQ<9>  @BASEBOARD_FAB2_LIB.BASEBOARD_FAB2(SCH_1):M_G_DQ<8>
   10  M_G_DQ<7>      DQ<6>  @BASEBOARD_FAB2_LIB.BASEBOARD_FAB2(SCH_1):M_G_DQ<7>
  155  M_G_DQ<6>      DQ<7>  @BASEBOARD_FAB2_LIB.BASEBOARD_FAB2(SCH_1):M_G_DQ<6>
  135  M_G_DQ<63>     DQ<62>  @BASEBOARD_FAB2_LIB.BASEBOARD_FAB2(SCH_1):M_G_DQ<63>
  280  M_G_DQ<62>     DQ<63>  @BASEBOARD_FAB2_LIB.BASEBOARD_FAB2(SCH_1):M_G_DQ<62>
  128  M_G_DQ<61>     DQ<60>  @BASEBOARD_FAB2_LIB.BASEBOARD_FAB2(SCH_1):M_G_DQ<61>
  273  M_G_DQ<60>     DQ<61>  @BASEBOARD_FAB2_LIB.BASEBOARD_FAB2(SCH_1):M_G_DQ<60>
    3  M_G_DQ<5>      DQ<4>  @BASEBOARD_FAB2_LIB.BASEBOARD_FAB2(SCH_1):M_G_DQ<5>
  137  M_G_DQ<59>     DQ<58>  @BASEBOARD_FAB2_LIB.BASEBOARD_FAB2(SCH_1):M_G_DQ<59>
  282  M_G_DQ<58>     DQ<59>  @BASEBOARD_FAB2_LIB.BASEBOARD_FAB2(SCH_1):M_G_DQ<58>
  130  M_G_DQ<57>     DQ<56>  @BASEBOARD_FAB2_LIB.BASEBOARD_FAB2(SCH_1):M_G_DQ<57>
  275  M_G_DQ<56>     DQ<57>  @BASEBOARD_FAB2_LIB.BASEBOARD_FAB2(SCH_1):M_G_DQ<56>
  124  M_G_DQ<55>     DQ<54>  @BASEBOARD_FAB2_LIB.BASEBOARD_FAB2(SCH_1):M_G_DQ<55>
  269  M_G_DQ<54>     DQ<55>  @BASEBOARD_FAB2_LIB.BASEBOARD_FAB2(SCH_1):M_G_DQ<54>
  117  M_G_DQ<53>     DQ<52>  @BASEBOARD_FAB2_LIB.BASEBOARD_FAB2(SCH_1):M_G_DQ<53>
  262  M_G_DQ<52>     DQ<53>  @BASEBOARD_FAB2_LIB.BASEBOARD_FAB2(SCH_1):M_G_DQ<52>
  126  M_G_DQ<51>     DQ<50>  @BASEBOARD_FAB2_LIB.BASEBOARD_FAB2(SCH_1):M_G_DQ<51>
  271  M_G_DQ<50>     DQ<51>  @BASEBOARD_FAB2_LIB.BASEBOARD_FAB2(SCH_1):M_G_DQ<50>
  148  M_G_DQ<4>      DQ<5>  @BASEBOARD_FAB2_LIB.BASEBOARD_FAB2(SCH_1):M_G_DQ<4>
  119  M_G_DQ<49>     DQ<48>  @BASEBOARD_FAB2_LIB.BASEBOARD_FAB2(SCH_1):M_G_DQ<49>
  264  M_G_DQ<48>     DQ<49>  @BASEBOARD_FAB2_LIB.BASEBOARD_FAB2(SCH_1):M_G_DQ<48>
  113  M_G_DQ<47>     DQ<46>  @BASEBOARD_FAB2_LIB.BASEBOARD_FAB2(SCH_1):M_G_DQ<47>
  258  M_G_DQ<46>     DQ<47>  @BASEBOARD_FAB2_LIB.BASEBOARD_FAB2(SCH_1):M_G_DQ<46>
  106  M_G_DQ<45>     DQ<44>  @BASEBOARD_FAB2_LIB.BASEBOARD_FAB2(SCH_1):M_G_DQ<45>
  251  M_G_DQ<44>     DQ<45>  @BASEBOARD_FAB2_LIB.BASEBOARD_FAB2(SCH_1):M_G_DQ<44>
  115  M_G_DQ<43>     DQ<42>  @BASEBOARD_FAB2_LIB.BASEBOARD_FAB2(SCH_1):M_G_DQ<43>
  260  M_G_DQ<42>     DQ<43>  @BASEBOARD_FAB2_LIB.BASEBOARD_FAB2(SCH_1):M_G_DQ<42>
  108  M_G_DQ<41>     DQ<40>  @BASEBOARD_FAB2_LIB.BASEBOARD_FAB2(SCH_1):M_G_DQ<41>
  253  M_G_DQ<40>     DQ<41>  @BASEBOARD_FAB2_LIB.BASEBOARD_FAB2(SCH_1):M_G_DQ<40>
   12  M_G_DQ<3>      DQ<2>  @BASEBOARD_FAB2_LIB.BASEBOARD_FAB2(SCH_1):M_G_DQ<3>
  102  M_G_DQ<39>     DQ<38>  @BASEBOARD_FAB2_LIB.BASEBOARD_FAB2(SCH_1):M_G_DQ<39>
  247  M_G_DQ<38>     DQ<39>  @BASEBOARD_FAB2_LIB.BASEBOARD_FAB2(SCH_1):M_G_DQ<38>
   95  M_G_DQ<37>     DQ<36>  @BASEBOARD_FAB2_LIB.BASEBOARD_FAB2(SCH_1):M_G_DQ<37>
  240  M_G_DQ<36>     DQ<37>  @BASEBOARD_FAB2_LIB.BASEBOARD_FAB2(SCH_1):M_G_DQ<36>
  104  M_G_DQ<35>     DQ<34>  @BASEBOARD_FAB2_LIB.BASEBOARD_FAB2(SCH_1):M_G_DQ<35>
  249  M_G_DQ<34>     DQ<35>  @BASEBOARD_FAB2_LIB.BASEBOARD_FAB2(SCH_1):M_G_DQ<34>
   97  M_G_DQ<33>     DQ<32>  @BASEBOARD_FAB2_LIB.BASEBOARD_FAB2(SCH_1):M_G_DQ<33>
  242  M_G_DQ<32>     DQ<33>  @BASEBOARD_FAB2_LIB.BASEBOARD_FAB2(SCH_1):M_G_DQ<32>
   43  M_G_DQ<31>     DQ<30>  @BASEBOARD_FAB2_LIB.BASEBOARD_FAB2(SCH_1):M_G_DQ<31>
  188  M_G_DQ<30>     DQ<31>  @BASEBOARD_FAB2_LIB.BASEBOARD_FAB2(SCH_1):M_G_DQ<30>
  157  M_G_DQ<2>      DQ<3>  @BASEBOARD_FAB2_LIB.BASEBOARD_FAB2(SCH_1):M_G_DQ<2>
   36  M_G_DQ<29>     DQ<28>  @BASEBOARD_FAB2_LIB.BASEBOARD_FAB2(SCH_1):M_G_DQ<29>
  181  M_G_DQ<28>     DQ<29>  @BASEBOARD_FAB2_LIB.BASEBOARD_FAB2(SCH_1):M_G_DQ<28>
   45  M_G_DQ<27>     DQ<26>  @BASEBOARD_FAB2_LIB.BASEBOARD_FAB2(SCH_1):M_G_DQ<27>
  190  M_G_DQ<26>     DQ<27>  @BASEBOARD_FAB2_LIB.BASEBOARD_FAB2(SCH_1):M_G_DQ<26>
   38  M_G_DQ<25>     DQ<24>  @BASEBOARD_FAB2_LIB.BASEBOARD_FAB2(SCH_1):M_G_DQ<25>
  183  M_G_DQ<24>     DQ<25>  @BASEBOARD_FAB2_LIB.BASEBOARD_FAB2(SCH_1):M_G_DQ<24>
   32  M_G_DQ<23>     DQ<22>  @BASEBOARD_FAB2_LIB.BASEBOARD_FAB2(SCH_1):M_G_DQ<23>
  177  M_G_DQ<22>     DQ<23>  @BASEBOARD_FAB2_LIB.BASEBOARD_FAB2(SCH_1):M_G_DQ<22>
   25  M_G_DQ<21>     DQ<20>  @BASEBOARD_FAB2_LIB.BASEBOARD_FAB2(SCH_1):M_G_DQ<21>
  170  M_G_DQ<20>     DQ<21>  @BASEBOARD_FAB2_LIB.BASEBOARD_FAB2(SCH_1):M_G_DQ<20>
    5  M_G_DQ<1>      DQ<0>  @BASEBOARD_FAB2_LIB.BASEBOARD_FAB2(SCH_1):M_G_DQ<1>
   34  M_G_DQ<19>     DQ<18>  @BASEBOARD_FAB2_LIB.BASEBOARD_FAB2(SCH_1):M_G_DQ<19>
  179  M_G_DQ<18>     DQ<19>  @BASEBOARD_FAB2_LIB.BASEBOARD_FAB2(SCH_1):M_G_DQ<18>
   27  M_G_DQ<17>     DQ<16>  @BASEBOARD_FAB2_LIB.BASEBOARD_FAB2(SCH_1):M_G_DQ<17>
  172  M_G_DQ<16>     DQ<17>  @BASEBOARD_FAB2_LIB.BASEBOARD_FAB2(SCH_1):M_G_DQ<16>
   21  M_G_DQ<15>     DQ<14>  @BASEBOARD_FAB2_LIB.BASEBOARD_FAB2(SCH_1):M_G_DQ<15>
  166  M_G_DQ<14>     DQ<15>  @BASEBOARD_FAB2_LIB.BASEBOARD_FAB2(SCH_1):M_G_DQ<14>
   14  M_G_DQ<13>     DQ<12>  @BASEBOARD_FAB2_LIB.BASEBOARD_FAB2(SCH_1):M_G_DQ<13>
  159  M_G_DQ<12>     DQ<13>  @BASEBOARD_FAB2_LIB.BASEBOARD_FAB2(SCH_1):M_G_DQ<12>
   23  M_G_DQ<11>     DQ<10>  @BASEBOARD_FAB2_LIB.BASEBOARD_FAB2(SCH_1):M_G_DQ<11>
  168  M_G_DQ<10>     DQ<11>  @BASEBOARD_FAB2_LIB.BASEBOARD_FAB2(SCH_1):M_G_DQ<10>
  150  M_G_DQ<0>      DQ<1>  @BASEBOARD_FAB2_LIB.BASEBOARD_FAB2(SCH_1):M_G_DQ<0>
  237  M_G_CS_N<3>    S3_N_C<1>  @BASEBOARD_FAB2_LIB.BASEBOARD_FAB2(SCH_1):M_G_CS_N<3>
   93  M_G_CS_N<2>    S2_N_C<0>  @BASEBOARD_FAB2_LIB.BASEBOARD_FAB2(SCH_1):M_G_CS_N<2>
   89  M_G_CS_N<1>     S1_N  @BASEBOARD_FAB2_LIB.BASEBOARD_FAB2(SCH_1):M_G_CS_N<1>
   84  M_G_CS_N<0>     S0_N  @BASEBOARD_FAB2_LIB.BASEBOARD_FAB2(SCH_1):M_G_CS_N<0>
  218  M_G_CLK_DP<1>   CK1P  @BASEBOARD_FAB2_LIB.BASEBOARD_FAB2(SCH_1):M_G_CLK_DP<1>
   74  M_G_CLK_DP<0>   CK0P  @BASEBOARD_FAB2_LIB.BASEBOARD_FAB2(SCH_1):M_G_CLK_DP<0>
  219  M_G_CLK_DN<1>   CK1N  @BASEBOARD_FAB2_LIB.BASEBOARD_FAB2(SCH_1):M_G_CLK_DN<1>
   75  M_G_CLK_DN<0>   CK0N  @BASEBOARD_FAB2_LIB.BASEBOARD_FAB2(SCH_1):M_G_CLK_DN<0>
  203  M_G_CKE<1>     CKE<1>  @BASEBOARD_FAB2_LIB.BASEBOARD_FAB2(SCH_1):M_G_CKE<1>
   60  M_G_CKE<0>     CKE<0>  @BASEBOARD_FAB2_LIB.BASEBOARD_FAB2(SCH_1):M_G_CKE<0>
  235  M_G_C<2>        C<2>  @BASEBOARD_FAB2_LIB.BASEBOARD_FAB2(SCH_1):M_G_C<2>
  207  M_G_BG<1>      BG<1>  @BASEBOARD_FAB2_LIB.BASEBOARD_FAB2(SCH_1):M_G_BG<1>
   63  M_G_BG<0>      BG<0>  @BASEBOARD_FAB2_LIB.BASEBOARD_FAB2(SCH_1):M_G_BG<0>
  224  M_G_BA<1>      BA<1>  @BASEBOARD_FAB2_LIB.BASEBOARD_FAB2(SCH_1):M_G_BA<1>
   81  M_G_BA<0>      BA<0>  @BASEBOARD_FAB2_LIB.BASEBOARD_FAB2(SCH_1):M_G_BA<0>
  208  M_G_ALERT_N    ALERT_N  @BASEBOARD_FAB2_LIB.BASEBOARD_FAB2(SCH_1):M_G_ALERT_N
   62  M_G_ACT_N      ACT_N  @BASEBOARD_FAB2_LIB.BASEBOARD_FAB2(SCH_1):M_G_ACT_N
   58  M_GHJ_RST_N    RESET_N  @BASEBOARD_FAB2_LIB.BASEBOARD_FAB2(SCH_1):M_GHJ_RST_N
  238  GND            SA<2>  @BASEBOARD_FAB2_LIB.BASEBOARD_FAB2(SCH_1):GND
  140  GND            SA<1>  @BASEBOARD_FAB2_LIB.BASEBOARD_FAB2(SCH_1):GND
  139  GND            SA<0>  @BASEBOARD_FAB2_LIB.BASEBOARD_FAB2(SCH_1):GND
   78  FM_DIMM_EVENT_COD_N  EVENT_N  @BASEBOARD_FAB2_LIB.BASEBOARD_FAB2(SCH_1):FM_DIMM_EVENT_COD_N
  230  FM_ADR_COMPLETE_GHJ_N  SAVE_N_NC  @BASEBOARD_FAB2_LIB.BASEBOARD_FAB2(SCH_1):FM_ADR_COMPLETE_GHJ_N

SCONN288_H44441004_PIP  I169  J1G2   [SCONN288_H44441004_PIP-SCONN,HA]
   77  PVTT_GHJ       VTT<1>  @BASEBOARD_FAB2_LIB.BASEBOARD_FAB2(SCH_1):PVTT_GHJ
  221  PVTT_GHJ       VTT<0>  @BASEBOARD_FAB2_LIB.BASEBOARD_FAB2(SCH_1):PVTT_GHJ
  142  PVPP_GHJ       VPP<4>  @BASEBOARD_FAB2_LIB.BASEBOARD_FAB2(SCH_1):PVPP_GHJ
  143  PVPP_GHJ       VPP<3>  @BASEBOARD_FAB2_LIB.BASEBOARD_FAB2(SCH_1):PVPP_GHJ
  288  PVPP_GHJ       VPP<2>  @BASEBOARD_FAB2_LIB.BASEBOARD_FAB2(SCH_1):PVPP_GHJ
  286  PVPP_GHJ       VPP<1>  @BASEBOARD_FAB2_LIB.BASEBOARD_FAB2(SCH_1):PVPP_GHJ
  287  PVPP_GHJ       VPP<0>  @BASEBOARD_FAB2_LIB.BASEBOARD_FAB2(SCH_1):PVPP_GHJ
   59  PVDDQ_GHJ      VDD<25>  @BASEBOARD_FAB2_LIB.BASEBOARD_FAB2(SCH_1):PVDDQ_GHJ
   61  PVDDQ_GHJ      VDD<24>  @BASEBOARD_FAB2_LIB.BASEBOARD_FAB2(SCH_1):PVDDQ_GHJ
   64  PVDDQ_GHJ      VDD<23>  @BASEBOARD_FAB2_LIB.BASEBOARD_FAB2(SCH_1):PVDDQ_GHJ
   67  PVDDQ_GHJ      VDD<22>  @BASEBOARD_FAB2_LIB.BASEBOARD_FAB2(SCH_1):PVDDQ_GHJ
   70  PVDDQ_GHJ      VDD<21>  @BASEBOARD_FAB2_LIB.BASEBOARD_FAB2(SCH_1):PVDDQ_GHJ
   73  PVDDQ_GHJ      VDD<20>  @BASEBOARD_FAB2_LIB.BASEBOARD_FAB2(SCH_1):PVDDQ_GHJ
   76  PVDDQ_GHJ      VDD<19>  @BASEBOARD_FAB2_LIB.BASEBOARD_FAB2(SCH_1):PVDDQ_GHJ
   80  PVDDQ_GHJ      VDD<18>  @BASEBOARD_FAB2_LIB.BASEBOARD_FAB2(SCH_1):PVDDQ_GHJ
   83  PVDDQ_GHJ      VDD<17>  @BASEBOARD_FAB2_LIB.BASEBOARD_FAB2(SCH_1):PVDDQ_GHJ
   85  PVDDQ_GHJ      VDD<16>  @BASEBOARD_FAB2_LIB.BASEBOARD_FAB2(SCH_1):PVDDQ_GHJ
   88  PVDDQ_GHJ      VDD<15>  @BASEBOARD_FAB2_LIB.BASEBOARD_FAB2(SCH_1):PVDDQ_GHJ
   90  PVDDQ_GHJ      VDD<14>  @BASEBOARD_FAB2_LIB.BASEBOARD_FAB2(SCH_1):PVDDQ_GHJ
   92  PVDDQ_GHJ      VDD<13>  @BASEBOARD_FAB2_LIB.BASEBOARD_FAB2(SCH_1):PVDDQ_GHJ
  204  PVDDQ_GHJ      VDD<12>  @BASEBOARD_FAB2_LIB.BASEBOARD_FAB2(SCH_1):PVDDQ_GHJ
  206  PVDDQ_GHJ      VDD<11>  @BASEBOARD_FAB2_LIB.BASEBOARD_FAB2(SCH_1):PVDDQ_GHJ
  209  PVDDQ_GHJ      VDD<10>  @BASEBOARD_FAB2_LIB.BASEBOARD_FAB2(SCH_1):PVDDQ_GHJ
  212  PVDDQ_GHJ      VDD<9>  @BASEBOARD_FAB2_LIB.BASEBOARD_FAB2(SCH_1):PVDDQ_GHJ
  215  PVDDQ_GHJ      VDD<8>  @BASEBOARD_FAB2_LIB.BASEBOARD_FAB2(SCH_1):PVDDQ_GHJ
  217  PVDDQ_GHJ      VDD<7>  @BASEBOARD_FAB2_LIB.BASEBOARD_FAB2(SCH_1):PVDDQ_GHJ
  220  PVDDQ_GHJ      VDD<6>  @BASEBOARD_FAB2_LIB.BASEBOARD_FAB2(SCH_1):PVDDQ_GHJ
  223  PVDDQ_GHJ      VDD<5>  @BASEBOARD_FAB2_LIB.BASEBOARD_FAB2(SCH_1):PVDDQ_GHJ
  226  PVDDQ_GHJ      VDD<4>  @BASEBOARD_FAB2_LIB.BASEBOARD_FAB2(SCH_1):PVDDQ_GHJ
  229  PVDDQ_GHJ      VDD<3>  @BASEBOARD_FAB2_LIB.BASEBOARD_FAB2(SCH_1):PVDDQ_GHJ
  231  PVDDQ_GHJ      VDD<2>  @BASEBOARD_FAB2_LIB.BASEBOARD_FAB2(SCH_1):PVDDQ_GHJ
  233  PVDDQ_GHJ      VDD<1>  @BASEBOARD_FAB2_LIB.BASEBOARD_FAB2(SCH_1):PVDDQ_GHJ
  236  PVDDQ_GHJ      VDD<0>  @BASEBOARD_FAB2_LIB.BASEBOARD_FAB2(SCH_1):PVDDQ_GHJ
    1  P12V_NVDIMM_GHJ  12V<1>  @BASEBOARD_FAB2_LIB.BASEBOARD_FAB2(SCH_1):P12V_NVDIMM_GHJ
  145  P12V_NVDIMM_GHJ  12V<0>  @BASEBOARD_FAB2_LIB.BASEBOARD_FAB2(SCH_1):P12V_NVDIMM_GHJ

SCONN288_H44441004_PIP  I43  J1G2   [SCONN288_H44441004_PIP-SCONN,HA]
    2  GND            VSS<93>  @BASEBOARD_FAB2_LIB.BASEBOARD_FAB2(SCH_1):GND
    4  GND            VSS<92>  @BASEBOARD_FAB2_LIB.BASEBOARD_FAB2(SCH_1):GND
    6  GND            VSS<91>  @BASEBOARD_FAB2_LIB.BASEBOARD_FAB2(SCH_1):GND
    9  GND            VSS<90>  @BASEBOARD_FAB2_LIB.BASEBOARD_FAB2(SCH_1):GND
   11  GND            VSS<89>  @BASEBOARD_FAB2_LIB.BASEBOARD_FAB2(SCH_1):GND
   13  GND            VSS<88>  @BASEBOARD_FAB2_LIB.BASEBOARD_FAB2(SCH_1):GND
   15  GND            VSS<87>  @BASEBOARD_FAB2_LIB.BASEBOARD_FAB2(SCH_1):GND
   17  GND            VSS<86>  @BASEBOARD_FAB2_LIB.BASEBOARD_FAB2(SCH_1):GND
   20  GND            VSS<85>  @BASEBOARD_FAB2_LIB.BASEBOARD_FAB2(SCH_1):GND
   22  GND            VSS<84>  @BASEBOARD_FAB2_LIB.BASEBOARD_FAB2(SCH_1):GND
   24  GND            VSS<83>  @BASEBOARD_FAB2_LIB.BASEBOARD_FAB2(SCH_1):GND
   26  GND            VSS<82>  @BASEBOARD_FAB2_LIB.BASEBOARD_FAB2(SCH_1):GND
   28  GND            VSS<81>  @BASEBOARD_FAB2_LIB.BASEBOARD_FAB2(SCH_1):GND
   31  GND            VSS<80>  @BASEBOARD_FAB2_LIB.BASEBOARD_FAB2(SCH_1):GND
   33  GND            VSS<79>  @BASEBOARD_FAB2_LIB.BASEBOARD_FAB2(SCH_1):GND
   35  GND            VSS<78>  @BASEBOARD_FAB2_LIB.BASEBOARD_FAB2(SCH_1):GND
   37  GND            VSS<77>  @BASEBOARD_FAB2_LIB.BASEBOARD_FAB2(SCH_1):GND
   39  GND            VSS<76>  @BASEBOARD_FAB2_LIB.BASEBOARD_FAB2(SCH_1):GND
   42  GND            VSS<75>  @BASEBOARD_FAB2_LIB.BASEBOARD_FAB2(SCH_1):GND
   44  GND            VSS<74>  @BASEBOARD_FAB2_LIB.BASEBOARD_FAB2(SCH_1):GND
   46  GND            VSS<73>  @BASEBOARD_FAB2_LIB.BASEBOARD_FAB2(SCH_1):GND
   48  GND            VSS<72>  @BASEBOARD_FAB2_LIB.BASEBOARD_FAB2(SCH_1):GND
   50  GND            VSS<71>  @BASEBOARD_FAB2_LIB.BASEBOARD_FAB2(SCH_1):GND
   53  GND            VSS<70>  @BASEBOARD_FAB2_LIB.BASEBOARD_FAB2(SCH_1):GND
   55  GND            VSS<69>  @BASEBOARD_FAB2_LIB.BASEBOARD_FAB2(SCH_1):GND
   57  GND            VSS<68>  @BASEBOARD_FAB2_LIB.BASEBOARD_FAB2(SCH_1):GND
   94  GND            VSS<67>  @BASEBOARD_FAB2_LIB.BASEBOARD_FAB2(SCH_1):GND
   96  GND            VSS<66>  @BASEBOARD_FAB2_LIB.BASEBOARD_FAB2(SCH_1):GND
   98  GND            VSS<65>  @BASEBOARD_FAB2_LIB.BASEBOARD_FAB2(SCH_1):GND
  101  GND            VSS<64>  @BASEBOARD_FAB2_LIB.BASEBOARD_FAB2(SCH_1):GND
  103  GND            VSS<63>  @BASEBOARD_FAB2_LIB.BASEBOARD_FAB2(SCH_1):GND
  105  GND            VSS<62>  @BASEBOARD_FAB2_LIB.BASEBOARD_FAB2(SCH_1):GND
  107  GND            VSS<61>  @BASEBOARD_FAB2_LIB.BASEBOARD_FAB2(SCH_1):GND
  109  GND            VSS<60>  @BASEBOARD_FAB2_LIB.BASEBOARD_FAB2(SCH_1):GND
  112  GND            VSS<59>  @BASEBOARD_FAB2_LIB.BASEBOARD_FAB2(SCH_1):GND
  114  GND            VSS<58>  @BASEBOARD_FAB2_LIB.BASEBOARD_FAB2(SCH_1):GND
  116  GND            VSS<57>  @BASEBOARD_FAB2_LIB.BASEBOARD_FAB2(SCH_1):GND
  118  GND            VSS<56>  @BASEBOARD_FAB2_LIB.BASEBOARD_FAB2(SCH_1):GND
  120  GND            VSS<55>  @BASEBOARD_FAB2_LIB.BASEBOARD_FAB2(SCH_1):GND
  123  GND            VSS<54>  @BASEBOARD_FAB2_LIB.BASEBOARD_FAB2(SCH_1):GND
  125  GND            VSS<53>  @BASEBOARD_FAB2_LIB.BASEBOARD_FAB2(SCH_1):GND
  127  GND            VSS<52>  @BASEBOARD_FAB2_LIB.BASEBOARD_FAB2(SCH_1):GND
  129  GND            VSS<51>  @BASEBOARD_FAB2_LIB.BASEBOARD_FAB2(SCH_1):GND
  131  GND            VSS<50>  @BASEBOARD_FAB2_LIB.BASEBOARD_FAB2(SCH_1):GND
  134  GND            VSS<49>  @BASEBOARD_FAB2_LIB.BASEBOARD_FAB2(SCH_1):GND
  136  GND            VSS<48>  @BASEBOARD_FAB2_LIB.BASEBOARD_FAB2(SCH_1):GND
  138  GND            VSS<47>  @BASEBOARD_FAB2_LIB.BASEBOARD_FAB2(SCH_1):GND
  147  GND            VSS<46>  @BASEBOARD_FAB2_LIB.BASEBOARD_FAB2(SCH_1):GND
  149  GND            VSS<45>  @BASEBOARD_FAB2_LIB.BASEBOARD_FAB2(SCH_1):GND
  151  GND            VSS<44>  @BASEBOARD_FAB2_LIB.BASEBOARD_FAB2(SCH_1):GND
  154  GND            VSS<43>  @BASEBOARD_FAB2_LIB.BASEBOARD_FAB2(SCH_1):GND
  156  GND            VSS<42>  @BASEBOARD_FAB2_LIB.BASEBOARD_FAB2(SCH_1):GND
  158  GND            VSS<41>  @BASEBOARD_FAB2_LIB.BASEBOARD_FAB2(SCH_1):GND
  160  GND            VSS<40>  @BASEBOARD_FAB2_LIB.BASEBOARD_FAB2(SCH_1):GND
  162  GND            VSS<39>  @BASEBOARD_FAB2_LIB.BASEBOARD_FAB2(SCH_1):GND
  165  GND            VSS<38>  @BASEBOARD_FAB2_LIB.BASEBOARD_FAB2(SCH_1):GND
  167  GND            VSS<37>  @BASEBOARD_FAB2_LIB.BASEBOARD_FAB2(SCH_1):GND
  169  GND            VSS<36>  @BASEBOARD_FAB2_LIB.BASEBOARD_FAB2(SCH_1):GND
  171  GND            VSS<35>  @BASEBOARD_FAB2_LIB.BASEBOARD_FAB2(SCH_1):GND
  173  GND            VSS<34>  @BASEBOARD_FAB2_LIB.BASEBOARD_FAB2(SCH_1):GND
  176  GND            VSS<33>  @BASEBOARD_FAB2_LIB.BASEBOARD_FAB2(SCH_1):GND
  178  GND            VSS<32>  @BASEBOARD_FAB2_LIB.BASEBOARD_FAB2(SCH_1):GND
  180  GND            VSS<31>  @BASEBOARD_FAB2_LIB.BASEBOARD_FAB2(SCH_1):GND
  182  GND            VSS<30>  @BASEBOARD_FAB2_LIB.BASEBOARD_FAB2(SCH_1):GND
  184  GND            VSS<29>  @BASEBOARD_FAB2_LIB.BASEBOARD_FAB2(SCH_1):GND
  187  GND            VSS<28>  @BASEBOARD_FAB2_LIB.BASEBOARD_FAB2(SCH_1):GND
  189  GND            VSS<27>  @BASEBOARD_FAB2_LIB.BASEBOARD_FAB2(SCH_1):GND
  191  GND            VSS<26>  @BASEBOARD_FAB2_LIB.BASEBOARD_FAB2(SCH_1):GND
  193  GND            VSS<25>  @BASEBOARD_FAB2_LIB.BASEBOARD_FAB2(SCH_1):GND
  195  GND            VSS<24>  @BASEBOARD_FAB2_LIB.BASEBOARD_FAB2(SCH_1):GND
  198  GND            VSS<23>  @BASEBOARD_FAB2_LIB.BASEBOARD_FAB2(SCH_1):GND
  200  GND            VSS<22>  @BASEBOARD_FAB2_LIB.BASEBOARD_FAB2(SCH_1):GND
  202  GND            VSS<21>  @BASEBOARD_FAB2_LIB.BASEBOARD_FAB2(SCH_1):GND
  239  GND            VSS<20>  @BASEBOARD_FAB2_LIB.BASEBOARD_FAB2(SCH_1):GND
  241  GND            VSS<19>  @BASEBOARD_FAB2_LIB.BASEBOARD_FAB2(SCH_1):GND
  243  GND            VSS<18>  @BASEBOARD_FAB2_LIB.BASEBOARD_FAB2(SCH_1):GND
  246  GND            VSS<17>  @BASEBOARD_FAB2_LIB.BASEBOARD_FAB2(SCH_1):GND
  248  GND            VSS<16>  @BASEBOARD_FAB2_LIB.BASEBOARD_FAB2(SCH_1):GND
  250  GND            VSS<15>  @BASEBOARD_FAB2_LIB.BASEBOARD_FAB2(SCH_1):GND
  252  GND            VSS<14>  @BASEBOARD_FAB2_LIB.BASEBOARD_FAB2(SCH_1):GND
  254  GND            VSS<13>  @BASEBOARD_FAB2_LIB.BASEBOARD_FAB2(SCH_1):GND
  257  GND            VSS<12>  @BASEBOARD_FAB2_LIB.BASEBOARD_FAB2(SCH_1):GND
  259  GND            VSS<11>  @BASEBOARD_FAB2_LIB.BASEBOARD_FAB2(SCH_1):GND
  261  GND            VSS<10>  @BASEBOARD_FAB2_LIB.BASEBOARD_FAB2(SCH_1):GND
  263  GND            VSS<9>  @BASEBOARD_FAB2_LIB.BASEBOARD_FAB2(SCH_1):GND
  265  GND            VSS<8>  @BASEBOARD_FAB2_LIB.BASEBOARD_FAB2(SCH_1):GND
  268  GND            VSS<7>  @BASEBOARD_FAB2_LIB.BASEBOARD_FAB2(SCH_1):GND
  270  GND            VSS<6>  @BASEBOARD_FAB2_LIB.BASEBOARD_FAB2(SCH_1):GND
  272  GND            VSS<5>  @BASEBOARD_FAB2_LIB.BASEBOARD_FAB2(SCH_1):GND
  274  GND            VSS<4>  @BASEBOARD_FAB2_LIB.BASEBOARD_FAB2(SCH_1):GND
  276  GND            VSS<3>  @BASEBOARD_FAB2_LIB.BASEBOARD_FAB2(SCH_1):GND
  279  GND            VSS<2>  @BASEBOARD_FAB2_LIB.BASEBOARD_FAB2(SCH_1):GND
  281  GND            VSS<1>  @BASEBOARD_FAB2_LIB.BASEBOARD_FAB2(SCH_1):GND
  283  GND            VSS<0>  @BASEBOARD_FAB2_LIB.BASEBOARD_FAB2(SCH_1):GND

SCONN288_H44441004_PIP  I64  J1G2   [SCONN288_H44441004_PIP-SCONN,HA]
    7  M_H_DQS_DP<9>  DQS9P  @BASEBOARD_FAB2_LIB.BASEBOARD_FAB2(SCH_1):M_H_DQS_DP<9>
  197  M_H_DQS_DP<8>  DQS8P  @BASEBOARD_FAB2_LIB.BASEBOARD_FAB2(SCH_1):M_H_DQS_DP<8>
  278  M_H_DQS_DP<7>  DQS7P  @BASEBOARD_FAB2_LIB.BASEBOARD_FAB2(SCH_1):M_H_DQS_DP<7>
  267  M_H_DQS_DP<6>  DQS6P  @BASEBOARD_FAB2_LIB.BASEBOARD_FAB2(SCH_1):M_H_DQS_DP<6>
  256  M_H_DQS_DP<5>  DQS5P  @BASEBOARD_FAB2_LIB.BASEBOARD_FAB2(SCH_1):M_H_DQS_DP<5>
  245  M_H_DQS_DP<4>  DQS4P  @BASEBOARD_FAB2_LIB.BASEBOARD_FAB2(SCH_1):M_H_DQS_DP<4>
  186  M_H_DQS_DP<3>  DQS3P  @BASEBOARD_FAB2_LIB.BASEBOARD_FAB2(SCH_1):M_H_DQS_DP<3>
  175  M_H_DQS_DP<2>  DQS2P  @BASEBOARD_FAB2_LIB.BASEBOARD_FAB2(SCH_1):M_H_DQS_DP<2>
  164  M_H_DQS_DP<1>  DQS1P  @BASEBOARD_FAB2_LIB.BASEBOARD_FAB2(SCH_1):M_H_DQS_DP<1>
   51  M_H_DQS_DP<17>  DQS17P  @BASEBOARD_FAB2_LIB.BASEBOARD_FAB2(SCH_1):M_H_DQS_DP<17>
  132  M_H_DQS_DP<16>  DQS16P  @BASEBOARD_FAB2_LIB.BASEBOARD_FAB2(SCH_1):M_H_DQS_DP<16>
  121  M_H_DQS_DP<15>  DQS15P  @BASEBOARD_FAB2_LIB.BASEBOARD_FAB2(SCH_1):M_H_DQS_DP<15>
  110  M_H_DQS_DP<14>  DQS14P  @BASEBOARD_FAB2_LIB.BASEBOARD_FAB2(SCH_1):M_H_DQS_DP<14>
   99  M_H_DQS_DP<13>  DQS13P  @BASEBOARD_FAB2_LIB.BASEBOARD_FAB2(SCH_1):M_H_DQS_DP<13>
   40  M_H_DQS_DP<12>  DQS12P  @BASEBOARD_FAB2_LIB.BASEBOARD_FAB2(SCH_1):M_H_DQS_DP<12>
   29  M_H_DQS_DP<11>  DQS11P  @BASEBOARD_FAB2_LIB.BASEBOARD_FAB2(SCH_1):M_H_DQS_DP<11>
   18  M_H_DQS_DP<10>  DQS10P  @BASEBOARD_FAB2_LIB.BASEBOARD_FAB2(SCH_1):M_H_DQS_DP<10>
  153  M_H_DQS_DP<0>  DQS0P  @BASEBOARD_FAB2_LIB.BASEBOARD_FAB2(SCH_1):M_H_DQS_DP<0>
    8  M_H_DQS_DN<9>  DQS9N  @BASEBOARD_FAB2_LIB.BASEBOARD_FAB2(SCH_1):M_H_DQS_DN<9>
  196  M_H_DQS_DN<8>  DQS8N  @BASEBOARD_FAB2_LIB.BASEBOARD_FAB2(SCH_1):M_H_DQS_DN<8>
  277  M_H_DQS_DN<7>  DQS7N  @BASEBOARD_FAB2_LIB.BASEBOARD_FAB2(SCH_1):M_H_DQS_DN<7>
  266  M_H_DQS_DN<6>  DQS6N  @BASEBOARD_FAB2_LIB.BASEBOARD_FAB2(SCH_1):M_H_DQS_DN<6>
  255  M_H_DQS_DN<5>  DQS5N  @BASEBOARD_FAB2_LIB.BASEBOARD_FAB2(SCH_1):M_H_DQS_DN<5>
  244  M_H_DQS_DN<4>  DQS4N  @BASEBOARD_FAB2_LIB.BASEBOARD_FAB2(SCH_1):M_H_DQS_DN<4>
  185  M_H_DQS_DN<3>  DQS3N  @BASEBOARD_FAB2_LIB.BASEBOARD_FAB2(SCH_1):M_H_DQS_DN<3>
  174  M_H_DQS_DN<2>  DQS2N  @BASEBOARD_FAB2_LIB.BASEBOARD_FAB2(SCH_1):M_H_DQS_DN<2>
  163  M_H_DQS_DN<1>  DQS1N  @BASEBOARD_FAB2_LIB.BASEBOARD_FAB2(SCH_1):M_H_DQS_DN<1>
   52  M_H_DQS_DN<17>  DQS17N  @BASEBOARD_FAB2_LIB.BASEBOARD_FAB2(SCH_1):M_H_DQS_DN<17>
  133  M_H_DQS_DN<16>  DQS16N  @BASEBOARD_FAB2_LIB.BASEBOARD_FAB2(SCH_1):M_H_DQS_DN<16>
  122  M_H_DQS_DN<15>  DQS15N  @BASEBOARD_FAB2_LIB.BASEBOARD_FAB2(SCH_1):M_H_DQS_DN<15>
  111  M_H_DQS_DN<14>  DQS14N  @BASEBOARD_FAB2_LIB.BASEBOARD_FAB2(SCH_1):M_H_DQS_DN<14>
  100  M_H_DQS_DN<13>  DQS13N  @BASEBOARD_FAB2_LIB.BASEBOARD_FAB2(SCH_1):M_H_DQS_DN<13>
   41  M_H_DQS_DN<12>  DQS12N  @BASEBOARD_FAB2_LIB.BASEBOARD_FAB2(SCH_1):M_H_DQS_DN<12>
   30  M_H_DQS_DN<11>  DQS11N  @BASEBOARD_FAB2_LIB.BASEBOARD_FAB2(SCH_1):M_H_DQS_DN<11>
   19  M_H_DQS_DN<10>  DQS10N  @BASEBOARD_FAB2_LIB.BASEBOARD_FAB2(SCH_1):M_H_DQS_DN<10>
  152  M_H_DQS_DN<0>  DQS0N  @BASEBOARD_FAB2_LIB.BASEBOARD_FAB2(SCH_1):M_H_DQS_DN<0>

SCONN288_H44441004_PIP  I111  J1G2   [SCONN288_H44441004_PIP-SCONN,HA]
  144  TP_CH_H_DIMM_H0_RFU_2  RFU<2>  @BASEBOARD_FAB2_LIB.BASEBOARD_FAB2(SCH_1):TP_CH_H_DIMM_H0_RFU_2
  227  TP_CH_H_DIMM_H0_RFU_1  RFU<1>  @BASEBOARD_FAB2_LIB.BASEBOARD_FAB2(SCH_1):TP_CH_H_DIMM_H0_RFU_1
  205  TP_CH_H_DIMM_H0_RFU_0  RFU<0>  @BASEBOARD_FAB2_LIB.BASEBOARD_FAB2(SCH_1):TP_CH_H_DIMM_H0_RFU_0
  285  SMB_DDR_GHJ_VPP_SDA    SDA  @BASEBOARD_FAB2_LIB.BASEBOARD_FAB2(SCH_1):SMB_DDR_GHJ_VPP_SDA
  141  SMB_DDR_GHJ_VPP_SCL    SCL  @BASEBOARD_FAB2_LIB.BASEBOARD_FAB2(SCH_1):SMB_DDR_GHJ_VPP_SCL
  284  PVPP_GHJ       VDDSPD  @BASEBOARD_FAB2_LIB.BASEBOARD_FAB2(SCH_1):PVPP_GHJ
  140  PVPP_GHJ       SA<1>  @BASEBOARD_FAB2_LIB.BASEBOARD_FAB2(SCH_1):PVPP_GHJ
  146  M_H_VREF       VREFCA  @BASEBOARD_FAB2_LIB.BASEBOARD_FAB2(SCH_1):M_H_VREF
  222  M_H_PAR          PAR  @BASEBOARD_FAB2_LIB.BASEBOARD_FAB2(SCH_1):M_H_PAR
   91  M_H_ODT<1>     ODT<1>  @BASEBOARD_FAB2_LIB.BASEBOARD_FAB2(SCH_1):M_H_ODT<1>
   87  M_H_ODT<0>     ODT<0>  @BASEBOARD_FAB2_LIB.BASEBOARD_FAB2(SCH_1):M_H_ODT<0>
   66  M_H_MA<9>         A9  @BASEBOARD_FAB2_LIB.BASEBOARD_FAB2(SCH_1):M_H_MA<9>
   68  M_H_MA<8>         A8  @BASEBOARD_FAB2_LIB.BASEBOARD_FAB2(SCH_1):M_H_MA<8>
  211  M_H_MA<7>         A7  @BASEBOARD_FAB2_LIB.BASEBOARD_FAB2(SCH_1):M_H_MA<7>
   69  M_H_MA<6>         A6  @BASEBOARD_FAB2_LIB.BASEBOARD_FAB2(SCH_1):M_H_MA<6>
  213  M_H_MA<5>         A5  @BASEBOARD_FAB2_LIB.BASEBOARD_FAB2(SCH_1):M_H_MA<5>
  214  M_H_MA<4>         A4  @BASEBOARD_FAB2_LIB.BASEBOARD_FAB2(SCH_1):M_H_MA<4>
   71  M_H_MA<3>         A3  @BASEBOARD_FAB2_LIB.BASEBOARD_FAB2(SCH_1):M_H_MA<3>
  216  M_H_MA<2>         A2  @BASEBOARD_FAB2_LIB.BASEBOARD_FAB2(SCH_1):M_H_MA<2>
   72  M_H_MA<1>         A1  @BASEBOARD_FAB2_LIB.BASEBOARD_FAB2(SCH_1):M_H_MA<1>
  234  M_H_MA<17>       A17  @BASEBOARD_FAB2_LIB.BASEBOARD_FAB2(SCH_1):M_H_MA<17>
   82  M_H_MA<16>     A16_RAS_N  @BASEBOARD_FAB2_LIB.BASEBOARD_FAB2(SCH_1):M_H_MA<16>
   86  M_H_MA<15>     A15_CAS_N  @BASEBOARD_FAB2_LIB.BASEBOARD_FAB2(SCH_1):M_H_MA<15>
  228  M_H_MA<14>     A14_WE_N  @BASEBOARD_FAB2_LIB.BASEBOARD_FAB2(SCH_1):M_H_MA<14>
  232  M_H_MA<13>       A13  @BASEBOARD_FAB2_LIB.BASEBOARD_FAB2(SCH_1):M_H_MA<13>
   65  M_H_MA<12>       A12  @BASEBOARD_FAB2_LIB.BASEBOARD_FAB2(SCH_1):M_H_MA<12>
  210  M_H_MA<11>       A11  @BASEBOARD_FAB2_LIB.BASEBOARD_FAB2(SCH_1):M_H_MA<11>
  225  M_H_MA<10>       A10  @BASEBOARD_FAB2_LIB.BASEBOARD_FAB2(SCH_1):M_H_MA<10>
   79  M_H_MA<0>         A0  @BASEBOARD_FAB2_LIB.BASEBOARD_FAB2(SCH_1):M_H_MA<0>
   54  M_H_ECC<7>     CB<6>  @BASEBOARD_FAB2_LIB.BASEBOARD_FAB2(SCH_1):M_H_ECC<7>
  199  M_H_ECC<6>     CB<7>  @BASEBOARD_FAB2_LIB.BASEBOARD_FAB2(SCH_1):M_H_ECC<6>
   47  M_H_ECC<5>     CB<4>  @BASEBOARD_FAB2_LIB.BASEBOARD_FAB2(SCH_1):M_H_ECC<5>
  192  M_H_ECC<4>     CB<5>  @BASEBOARD_FAB2_LIB.BASEBOARD_FAB2(SCH_1):M_H_ECC<4>
   56  M_H_ECC<3>     CB<2>  @BASEBOARD_FAB2_LIB.BASEBOARD_FAB2(SCH_1):M_H_ECC<3>
  201  M_H_ECC<2>     CB<3>  @BASEBOARD_FAB2_LIB.BASEBOARD_FAB2(SCH_1):M_H_ECC<2>
   49  M_H_ECC<1>     CB<0>  @BASEBOARD_FAB2_LIB.BASEBOARD_FAB2(SCH_1):M_H_ECC<1>
  194  M_H_ECC<0>     CB<1>  @BASEBOARD_FAB2_LIB.BASEBOARD_FAB2(SCH_1):M_H_ECC<0>
   16  M_H_DQ<9>      DQ<8>  @BASEBOARD_FAB2_LIB.BASEBOARD_FAB2(SCH_1):M_H_DQ<9>
  161  M_H_DQ<8>      DQ<9>  @BASEBOARD_FAB2_LIB.BASEBOARD_FAB2(SCH_1):M_H_DQ<8>
   10  M_H_DQ<7>      DQ<6>  @BASEBOARD_FAB2_LIB.BASEBOARD_FAB2(SCH_1):M_H_DQ<7>
  155  M_H_DQ<6>      DQ<7>  @BASEBOARD_FAB2_LIB.BASEBOARD_FAB2(SCH_1):M_H_DQ<6>
  135  M_H_DQ<63>     DQ<62>  @BASEBOARD_FAB2_LIB.BASEBOARD_FAB2(SCH_1):M_H_DQ<63>
  280  M_H_DQ<62>     DQ<63>  @BASEBOARD_FAB2_LIB.BASEBOARD_FAB2(SCH_1):M_H_DQ<62>
  128  M_H_DQ<61>     DQ<60>  @BASEBOARD_FAB2_LIB.BASEBOARD_FAB2(SCH_1):M_H_DQ<61>
  273  M_H_DQ<60>     DQ<61>  @BASEBOARD_FAB2_LIB.BASEBOARD_FAB2(SCH_1):M_H_DQ<60>
    3  M_H_DQ<5>      DQ<4>  @BASEBOARD_FAB2_LIB.BASEBOARD_FAB2(SCH_1):M_H_DQ<5>
  137  M_H_DQ<59>     DQ<58>  @BASEBOARD_FAB2_LIB.BASEBOARD_FAB2(SCH_1):M_H_DQ<59>
  282  M_H_DQ<58>     DQ<59>  @BASEBOARD_FAB2_LIB.BASEBOARD_FAB2(SCH_1):M_H_DQ<58>
  130  M_H_DQ<57>     DQ<56>  @BASEBOARD_FAB2_LIB.BASEBOARD_FAB2(SCH_1):M_H_DQ<57>
  275  M_H_DQ<56>     DQ<57>  @BASEBOARD_FAB2_LIB.BASEBOARD_FAB2(SCH_1):M_H_DQ<56>
  124  M_H_DQ<55>     DQ<54>  @BASEBOARD_FAB2_LIB.BASEBOARD_FAB2(SCH_1):M_H_DQ<55>
  269  M_H_DQ<54>     DQ<55>  @BASEBOARD_FAB2_LIB.BASEBOARD_FAB2(SCH_1):M_H_DQ<54>
  117  M_H_DQ<53>     DQ<52>  @BASEBOARD_FAB2_LIB.BASEBOARD_FAB2(SCH_1):M_H_DQ<53>
  262  M_H_DQ<52>     DQ<53>  @BASEBOARD_FAB2_LIB.BASEBOARD_FAB2(SCH_1):M_H_DQ<52>
  126  M_H_DQ<51>     DQ<50>  @BASEBOARD_FAB2_LIB.BASEBOARD_FAB2(SCH_1):M_H_DQ<51>
  271  M_H_DQ<50>     DQ<51>  @BASEBOARD_FAB2_LIB.BASEBOARD_FAB2(SCH_1):M_H_DQ<50>
  148  M_H_DQ<4>      DQ<5>  @BASEBOARD_FAB2_LIB.BASEBOARD_FAB2(SCH_1):M_H_DQ<4>
  119  M_H_DQ<49>     DQ<48>  @BASEBOARD_FAB2_LIB.BASEBOARD_FAB2(SCH_1):M_H_DQ<49>
  264  M_H_DQ<48>     DQ<49>  @BASEBOARD_FAB2_LIB.BASEBOARD_FAB2(SCH_1):M_H_DQ<48>
  113  M_H_DQ<47>     DQ<46>  @BASEBOARD_FAB2_LIB.BASEBOARD_FAB2(SCH_1):M_H_DQ<47>
  258  M_H_DQ<46>     DQ<47>  @BASEBOARD_FAB2_LIB.BASEBOARD_FAB2(SCH_1):M_H_DQ<46>
  106  M_H_DQ<45>     DQ<44>  @BASEBOARD_FAB2_LIB.BASEBOARD_FAB2(SCH_1):M_H_DQ<45>
  251  M_H_DQ<44>     DQ<45>  @BASEBOARD_FAB2_LIB.BASEBOARD_FAB2(SCH_1):M_H_DQ<44>
  115  M_H_DQ<43>     DQ<42>  @BASEBOARD_FAB2_LIB.BASEBOARD_FAB2(SCH_1):M_H_DQ<43>
  260  M_H_DQ<42>     DQ<43>  @BASEBOARD_FAB2_LIB.BASEBOARD_FAB2(SCH_1):M_H_DQ<42>
  108  M_H_DQ<41>     DQ<40>  @BASEBOARD_FAB2_LIB.BASEBOARD_FAB2(SCH_1):M_H_DQ<41>
  253  M_H_DQ<40>     DQ<41>  @BASEBOARD_FAB2_LIB.BASEBOARD_FAB2(SCH_1):M_H_DQ<40>
   12  M_H_DQ<3>      DQ<2>  @BASEBOARD_FAB2_LIB.BASEBOARD_FAB2(SCH_1):M_H_DQ<3>
  102  M_H_DQ<39>     DQ<38>  @BASEBOARD_FAB2_LIB.BASEBOARD_FAB2(SCH_1):M_H_DQ<39>
  247  M_H_DQ<38>     DQ<39>  @BASEBOARD_FAB2_LIB.BASEBOARD_FAB2(SCH_1):M_H_DQ<38>
   95  M_H_DQ<37>     DQ<36>  @BASEBOARD_FAB2_LIB.BASEBOARD_FAB2(SCH_1):M_H_DQ<37>
  240  M_H_DQ<36>     DQ<37>  @BASEBOARD_FAB2_LIB.BASEBOARD_FAB2(SCH_1):M_H_DQ<36>
  104  M_H_DQ<35>     DQ<34>  @BASEBOARD_FAB2_LIB.BASEBOARD_FAB2(SCH_1):M_H_DQ<35>
  249  M_H_DQ<34>     DQ<35>  @BASEBOARD_FAB2_LIB.BASEBOARD_FAB2(SCH_1):M_H_DQ<34>
   97  M_H_DQ<33>     DQ<32>  @BASEBOARD_FAB2_LIB.BASEBOARD_FAB2(SCH_1):M_H_DQ<33>
  242  M_H_DQ<32>     DQ<33>  @BASEBOARD_FAB2_LIB.BASEBOARD_FAB2(SCH_1):M_H_DQ<32>
   43  M_H_DQ<31>     DQ<30>  @BASEBOARD_FAB2_LIB.BASEBOARD_FAB2(SCH_1):M_H_DQ<31>
  188  M_H_DQ<30>     DQ<31>  @BASEBOARD_FAB2_LIB.BASEBOARD_FAB2(SCH_1):M_H_DQ<30>
  157  M_H_DQ<2>      DQ<3>  @BASEBOARD_FAB2_LIB.BASEBOARD_FAB2(SCH_1):M_H_DQ<2>
   36  M_H_DQ<29>     DQ<28>  @BASEBOARD_FAB2_LIB.BASEBOARD_FAB2(SCH_1):M_H_DQ<29>
  181  M_H_DQ<28>     DQ<29>  @BASEBOARD_FAB2_LIB.BASEBOARD_FAB2(SCH_1):M_H_DQ<28>
   45  M_H_DQ<27>     DQ<26>  @BASEBOARD_FAB2_LIB.BASEBOARD_FAB2(SCH_1):M_H_DQ<27>
  190  M_H_DQ<26>     DQ<27>  @BASEBOARD_FAB2_LIB.BASEBOARD_FAB2(SCH_1):M_H_DQ<26>
   38  M_H_DQ<25>     DQ<24>  @BASEBOARD_FAB2_LIB.BASEBOARD_FAB2(SCH_1):M_H_DQ<25>
  183  M_H_DQ<24>     DQ<25>  @BASEBOARD_FAB2_LIB.BASEBOARD_FAB2(SCH_1):M_H_DQ<24>
   32  M_H_DQ<23>     DQ<22>  @BASEBOARD_FAB2_LIB.BASEBOARD_FAB2(SCH_1):M_H_DQ<23>
  177  M_H_DQ<22>     DQ<23>  @BASEBOARD_FAB2_LIB.BASEBOARD_FAB2(SCH_1):M_H_DQ<22>
   25  M_H_DQ<21>     DQ<20>  @BASEBOARD_FAB2_LIB.BASEBOARD_FAB2(SCH_1):M_H_DQ<21>
  170  M_H_DQ<20>     DQ<21>  @BASEBOARD_FAB2_LIB.BASEBOARD_FAB2(SCH_1):M_H_DQ<20>
    5  M_H_DQ<1>      DQ<0>  @BASEBOARD_FAB2_LIB.BASEBOARD_FAB2(SCH_1):M_H_DQ<1>
   34  M_H_DQ<19>     DQ<18>  @BASEBOARD_FAB2_LIB.BASEBOARD_FAB2(SCH_1):M_H_DQ<19>
  179  M_H_DQ<18>     DQ<19>  @BASEBOARD_FAB2_LIB.BASEBOARD_FAB2(SCH_1):M_H_DQ<18>
   27  M_H_DQ<17>     DQ<16>  @BASEBOARD_FAB2_LIB.BASEBOARD_FAB2(SCH_1):M_H_DQ<17>
  172  M_H_DQ<16>     DQ<17>  @BASEBOARD_FAB2_LIB.BASEBOARD_FAB2(SCH_1):M_H_DQ<16>
   21  M_H_DQ<15>     DQ<14>  @BASEBOARD_FAB2_LIB.BASEBOARD_FAB2(SCH_1):M_H_DQ<15>
  166  M_H_DQ<14>     DQ<15>  @BASEBOARD_FAB2_LIB.BASEBOARD_FAB2(SCH_1):M_H_DQ<14>
   14  M_H_DQ<13>     DQ<12>  @BASEBOARD_FAB2_LIB.BASEBOARD_FAB2(SCH_1):M_H_DQ<13>
  159  M_H_DQ<12>     DQ<13>  @BASEBOARD_FAB2_LIB.BASEBOARD_FAB2(SCH_1):M_H_DQ<12>
   23  M_H_DQ<11>     DQ<10>  @BASEBOARD_FAB2_LIB.BASEBOARD_FAB2(SCH_1):M_H_DQ<11>
  168  M_H_DQ<10>     DQ<11>  @BASEBOARD_FAB2_LIB.BASEBOARD_FAB2(SCH_1):M_H_DQ<10>
  150  M_H_DQ<0>      DQ<1>  @BASEBOARD_FAB2_LIB.BASEBOARD_FAB2(SCH_1):M_H_DQ<0>
  237  M_H_CS_N<3>    S3_N_C<1>  @BASEBOARD_FAB2_LIB.BASEBOARD_FAB2(SCH_1):M_H_CS_N<3>
   93  M_H_CS_N<2>    S2_N_C<0>  @BASEBOARD_FAB2_LIB.BASEBOARD_FAB2(SCH_1):M_H_CS_N<2>
   89  M_H_CS_N<1>     S1_N  @BASEBOARD_FAB2_LIB.BASEBOARD_FAB2(SCH_1):M_H_CS_N<1>
   84  M_H_CS_N<0>     S0_N  @BASEBOARD_FAB2_LIB.BASEBOARD_FAB2(SCH_1):M_H_CS_N<0>
  218  M_H_CLK_DP<1>   CK1P  @BASEBOARD_FAB2_LIB.BASEBOARD_FAB2(SCH_1):M_H_CLK_DP<1>
   74  M_H_CLK_DP<0>   CK0P  @BASEBOARD_FAB2_LIB.BASEBOARD_FAB2(SCH_1):M_H_CLK_DP<0>
  219  M_H_CLK_DN<1>   CK1N  @BASEBOARD_FAB2_LIB.BASEBOARD_FAB2(SCH_1):M_H_CLK_DN<1>
   75  M_H_CLK_DN<0>   CK0N  @BASEBOARD_FAB2_LIB.BASEBOARD_FAB2(SCH_1):M_H_CLK_DN<0>
  203  M_H_CKE<1>     CKE<1>  @BASEBOARD_FAB2_LIB.BASEBOARD_FAB2(SCH_1):M_H_CKE<1>
   60  M_H_CKE<0>     CKE<0>  @BASEBOARD_FAB2_LIB.BASEBOARD_FAB2(SCH_1):M_H_CKE<0>
  235  M_H_C<2>        C<2>  @BASEBOARD_FAB2_LIB.BASEBOARD_FAB2(SCH_1):M_H_C<2>
  207  M_H_BG<1>      BG<1>  @BASEBOARD_FAB2_LIB.BASEBOARD_FAB2(SCH_1):M_H_BG<1>
   63  M_H_BG<0>      BG<0>  @BASEBOARD_FAB2_LIB.BASEBOARD_FAB2(SCH_1):M_H_BG<0>
  224  M_H_BA<1>      BA<1>  @BASEBOARD_FAB2_LIB.BASEBOARD_FAB2(SCH_1):M_H_BA<1>
   81  M_H_BA<0>      BA<0>  @BASEBOARD_FAB2_LIB.BASEBOARD_FAB2(SCH_1):M_H_BA<0>
  208  M_H_ALERT_N    ALERT_N  @BASEBOARD_FAB2_LIB.BASEBOARD_FAB2(SCH_1):M_H_ALERT_N
   62  M_H_ACT_N      ACT_N  @BASEBOARD_FAB2_LIB.BASEBOARD_FAB2(SCH_1):M_H_ACT_N
   58  M_GHJ_RST_N    RESET_N  @BASEBOARD_FAB2_LIB.BASEBOARD_FAB2(SCH_1):M_GHJ_RST_N
  238  GND            SA<2>  @BASEBOARD_FAB2_LIB.BASEBOARD_FAB2(SCH_1):GND
  139  GND            SA<0>  @BASEBOARD_FAB2_LIB.BASEBOARD_FAB2(SCH_1):GND
   78  FM_DIMM_EVENT_COD_N  EVENT_N  @BASEBOARD_FAB2_LIB.BASEBOARD_FAB2(SCH_1):FM_DIMM_EVENT_COD_N
  230  FM_ADR_COMPLETE_GHJ_N  SAVE_N_NC  @BASEBOARD_FAB2_LIB.BASEBOARD_FAB2(SCH_1):FM_ADR_COMPLETE_GHJ_N

SCONN288_H44441004_PIP  I169  J1G3   [SCONN288_H44441004_PIP-SCONN,HA]
   77  PVTT_GHJ       VTT<1>  @BASEBOARD_FAB2_LIB.BASEBOARD_FAB2(SCH_1):PVTT_GHJ
  221  PVTT_GHJ       VTT<0>  @BASEBOARD_FAB2_LIB.BASEBOARD_FAB2(SCH_1):PVTT_GHJ
  142  PVPP_GHJ       VPP<4>  @BASEBOARD_FAB2_LIB.BASEBOARD_FAB2(SCH_1):PVPP_GHJ
  143  PVPP_GHJ       VPP<3>  @BASEBOARD_FAB2_LIB.BASEBOARD_FAB2(SCH_1):PVPP_GHJ
  288  PVPP_GHJ       VPP<2>  @BASEBOARD_FAB2_LIB.BASEBOARD_FAB2(SCH_1):PVPP_GHJ
  286  PVPP_GHJ       VPP<1>  @BASEBOARD_FAB2_LIB.BASEBOARD_FAB2(SCH_1):PVPP_GHJ
  287  PVPP_GHJ       VPP<0>  @BASEBOARD_FAB2_LIB.BASEBOARD_FAB2(SCH_1):PVPP_GHJ
   59  PVDDQ_GHJ      VDD<25>  @BASEBOARD_FAB2_LIB.BASEBOARD_FAB2(SCH_1):PVDDQ_GHJ
   61  PVDDQ_GHJ      VDD<24>  @BASEBOARD_FAB2_LIB.BASEBOARD_FAB2(SCH_1):PVDDQ_GHJ
   64  PVDDQ_GHJ      VDD<23>  @BASEBOARD_FAB2_LIB.BASEBOARD_FAB2(SCH_1):PVDDQ_GHJ
   67  PVDDQ_GHJ      VDD<22>  @BASEBOARD_FAB2_LIB.BASEBOARD_FAB2(SCH_1):PVDDQ_GHJ
   70  PVDDQ_GHJ      VDD<21>  @BASEBOARD_FAB2_LIB.BASEBOARD_FAB2(SCH_1):PVDDQ_GHJ
   73  PVDDQ_GHJ      VDD<20>  @BASEBOARD_FAB2_LIB.BASEBOARD_FAB2(SCH_1):PVDDQ_GHJ
   76  PVDDQ_GHJ      VDD<19>  @BASEBOARD_FAB2_LIB.BASEBOARD_FAB2(SCH_1):PVDDQ_GHJ
   80  PVDDQ_GHJ      VDD<18>  @BASEBOARD_FAB2_LIB.BASEBOARD_FAB2(SCH_1):PVDDQ_GHJ
   83  PVDDQ_GHJ      VDD<17>  @BASEBOARD_FAB2_LIB.BASEBOARD_FAB2(SCH_1):PVDDQ_GHJ
   85  PVDDQ_GHJ      VDD<16>  @BASEBOARD_FAB2_LIB.BASEBOARD_FAB2(SCH_1):PVDDQ_GHJ
   88  PVDDQ_GHJ      VDD<15>  @BASEBOARD_FAB2_LIB.BASEBOARD_FAB2(SCH_1):PVDDQ_GHJ
   90  PVDDQ_GHJ      VDD<14>  @BASEBOARD_FAB2_LIB.BASEBOARD_FAB2(SCH_1):PVDDQ_GHJ
   92  PVDDQ_GHJ      VDD<13>  @BASEBOARD_FAB2_LIB.BASEBOARD_FAB2(SCH_1):PVDDQ_GHJ
  204  PVDDQ_GHJ      VDD<12>  @BASEBOARD_FAB2_LIB.BASEBOARD_FAB2(SCH_1):PVDDQ_GHJ
  206  PVDDQ_GHJ      VDD<11>  @BASEBOARD_FAB2_LIB.BASEBOARD_FAB2(SCH_1):PVDDQ_GHJ
  209  PVDDQ_GHJ      VDD<10>  @BASEBOARD_FAB2_LIB.BASEBOARD_FAB2(SCH_1):PVDDQ_GHJ
  212  PVDDQ_GHJ      VDD<9>  @BASEBOARD_FAB2_LIB.BASEBOARD_FAB2(SCH_1):PVDDQ_GHJ
  215  PVDDQ_GHJ      VDD<8>  @BASEBOARD_FAB2_LIB.BASEBOARD_FAB2(SCH_1):PVDDQ_GHJ
  217  PVDDQ_GHJ      VDD<7>  @BASEBOARD_FAB2_LIB.BASEBOARD_FAB2(SCH_1):PVDDQ_GHJ
  220  PVDDQ_GHJ      VDD<6>  @BASEBOARD_FAB2_LIB.BASEBOARD_FAB2(SCH_1):PVDDQ_GHJ
  223  PVDDQ_GHJ      VDD<5>  @BASEBOARD_FAB2_LIB.BASEBOARD_FAB2(SCH_1):PVDDQ_GHJ
  226  PVDDQ_GHJ      VDD<4>  @BASEBOARD_FAB2_LIB.BASEBOARD_FAB2(SCH_1):PVDDQ_GHJ
  229  PVDDQ_GHJ      VDD<3>  @BASEBOARD_FAB2_LIB.BASEBOARD_FAB2(SCH_1):PVDDQ_GHJ
  231  PVDDQ_GHJ      VDD<2>  @BASEBOARD_FAB2_LIB.BASEBOARD_FAB2(SCH_1):PVDDQ_GHJ
  233  PVDDQ_GHJ      VDD<1>  @BASEBOARD_FAB2_LIB.BASEBOARD_FAB2(SCH_1):PVDDQ_GHJ
  236  PVDDQ_GHJ      VDD<0>  @BASEBOARD_FAB2_LIB.BASEBOARD_FAB2(SCH_1):PVDDQ_GHJ
    1  P12V_NVDIMM_GHJ  12V<1>  @BASEBOARD_FAB2_LIB.BASEBOARD_FAB2(SCH_1):P12V_NVDIMM_GHJ
  145  P12V_NVDIMM_GHJ  12V<0>  @BASEBOARD_FAB2_LIB.BASEBOARD_FAB2(SCH_1):P12V_NVDIMM_GHJ

SCONN288_H44441004_PIP  I185  J1G3   [SCONN288_H44441004_PIP-SCONN,HA]
    2  GND            VSS<93>  @BASEBOARD_FAB2_LIB.BASEBOARD_FAB2(SCH_1):GND
    4  GND            VSS<92>  @BASEBOARD_FAB2_LIB.BASEBOARD_FAB2(SCH_1):GND
    6  GND            VSS<91>  @BASEBOARD_FAB2_LIB.BASEBOARD_FAB2(SCH_1):GND
    9  GND            VSS<90>  @BASEBOARD_FAB2_LIB.BASEBOARD_FAB2(SCH_1):GND
   11  GND            VSS<89>  @BASEBOARD_FAB2_LIB.BASEBOARD_FAB2(SCH_1):GND
   13  GND            VSS<88>  @BASEBOARD_FAB2_LIB.BASEBOARD_FAB2(SCH_1):GND
   15  GND            VSS<87>  @BASEBOARD_FAB2_LIB.BASEBOARD_FAB2(SCH_1):GND
   17  GND            VSS<86>  @BASEBOARD_FAB2_LIB.BASEBOARD_FAB2(SCH_1):GND
   20  GND            VSS<85>  @BASEBOARD_FAB2_LIB.BASEBOARD_FAB2(SCH_1):GND
   22  GND            VSS<84>  @BASEBOARD_FAB2_LIB.BASEBOARD_FAB2(SCH_1):GND
   24  GND            VSS<83>  @BASEBOARD_FAB2_LIB.BASEBOARD_FAB2(SCH_1):GND
   26  GND            VSS<82>  @BASEBOARD_FAB2_LIB.BASEBOARD_FAB2(SCH_1):GND
   28  GND            VSS<81>  @BASEBOARD_FAB2_LIB.BASEBOARD_FAB2(SCH_1):GND
   31  GND            VSS<80>  @BASEBOARD_FAB2_LIB.BASEBOARD_FAB2(SCH_1):GND
   33  GND            VSS<79>  @BASEBOARD_FAB2_LIB.BASEBOARD_FAB2(SCH_1):GND
   35  GND            VSS<78>  @BASEBOARD_FAB2_LIB.BASEBOARD_FAB2(SCH_1):GND
   37  GND            VSS<77>  @BASEBOARD_FAB2_LIB.BASEBOARD_FAB2(SCH_1):GND
   39  GND            VSS<76>  @BASEBOARD_FAB2_LIB.BASEBOARD_FAB2(SCH_1):GND
   42  GND            VSS<75>  @BASEBOARD_FAB2_LIB.BASEBOARD_FAB2(SCH_1):GND
   44  GND            VSS<74>  @BASEBOARD_FAB2_LIB.BASEBOARD_FAB2(SCH_1):GND
   46  GND            VSS<73>  @BASEBOARD_FAB2_LIB.BASEBOARD_FAB2(SCH_1):GND
   48  GND            VSS<72>  @BASEBOARD_FAB2_LIB.BASEBOARD_FAB2(SCH_1):GND
   50  GND            VSS<71>  @BASEBOARD_FAB2_LIB.BASEBOARD_FAB2(SCH_1):GND
   53  GND            VSS<70>  @BASEBOARD_FAB2_LIB.BASEBOARD_FAB2(SCH_1):GND
   55  GND            VSS<69>  @BASEBOARD_FAB2_LIB.BASEBOARD_FAB2(SCH_1):GND
   57  GND            VSS<68>  @BASEBOARD_FAB2_LIB.BASEBOARD_FAB2(SCH_1):GND
   94  GND            VSS<67>  @BASEBOARD_FAB2_LIB.BASEBOARD_FAB2(SCH_1):GND
   96  GND            VSS<66>  @BASEBOARD_FAB2_LIB.BASEBOARD_FAB2(SCH_1):GND
   98  GND            VSS<65>  @BASEBOARD_FAB2_LIB.BASEBOARD_FAB2(SCH_1):GND
  101  GND            VSS<64>  @BASEBOARD_FAB2_LIB.BASEBOARD_FAB2(SCH_1):GND
  103  GND            VSS<63>  @BASEBOARD_FAB2_LIB.BASEBOARD_FAB2(SCH_1):GND
  105  GND            VSS<62>  @BASEBOARD_FAB2_LIB.BASEBOARD_FAB2(SCH_1):GND
  107  GND            VSS<61>  @BASEBOARD_FAB2_LIB.BASEBOARD_FAB2(SCH_1):GND
  109  GND            VSS<60>  @BASEBOARD_FAB2_LIB.BASEBOARD_FAB2(SCH_1):GND
  112  GND            VSS<59>  @BASEBOARD_FAB2_LIB.BASEBOARD_FAB2(SCH_1):GND
  114  GND            VSS<58>  @BASEBOARD_FAB2_LIB.BASEBOARD_FAB2(SCH_1):GND
  116  GND            VSS<57>  @BASEBOARD_FAB2_LIB.BASEBOARD_FAB2(SCH_1):GND
  118  GND            VSS<56>  @BASEBOARD_FAB2_LIB.BASEBOARD_FAB2(SCH_1):GND
  120  GND            VSS<55>  @BASEBOARD_FAB2_LIB.BASEBOARD_FAB2(SCH_1):GND
  123  GND            VSS<54>  @BASEBOARD_FAB2_LIB.BASEBOARD_FAB2(SCH_1):GND
  125  GND            VSS<53>  @BASEBOARD_FAB2_LIB.BASEBOARD_FAB2(SCH_1):GND
  127  GND            VSS<52>  @BASEBOARD_FAB2_LIB.BASEBOARD_FAB2(SCH_1):GND
  129  GND            VSS<51>  @BASEBOARD_FAB2_LIB.BASEBOARD_FAB2(SCH_1):GND
  131  GND            VSS<50>  @BASEBOARD_FAB2_LIB.BASEBOARD_FAB2(SCH_1):GND
  134  GND            VSS<49>  @BASEBOARD_FAB2_LIB.BASEBOARD_FAB2(SCH_1):GND
  136  GND            VSS<48>  @BASEBOARD_FAB2_LIB.BASEBOARD_FAB2(SCH_1):GND
  138  GND            VSS<47>  @BASEBOARD_FAB2_LIB.BASEBOARD_FAB2(SCH_1):GND
  147  GND            VSS<46>  @BASEBOARD_FAB2_LIB.BASEBOARD_FAB2(SCH_1):GND
  149  GND            VSS<45>  @BASEBOARD_FAB2_LIB.BASEBOARD_FAB2(SCH_1):GND
  151  GND            VSS<44>  @BASEBOARD_FAB2_LIB.BASEBOARD_FAB2(SCH_1):GND
  154  GND            VSS<43>  @BASEBOARD_FAB2_LIB.BASEBOARD_FAB2(SCH_1):GND
  156  GND            VSS<42>  @BASEBOARD_FAB2_LIB.BASEBOARD_FAB2(SCH_1):GND
  158  GND            VSS<41>  @BASEBOARD_FAB2_LIB.BASEBOARD_FAB2(SCH_1):GND
  160  GND            VSS<40>  @BASEBOARD_FAB2_LIB.BASEBOARD_FAB2(SCH_1):GND
  162  GND            VSS<39>  @BASEBOARD_FAB2_LIB.BASEBOARD_FAB2(SCH_1):GND
  165  GND            VSS<38>  @BASEBOARD_FAB2_LIB.BASEBOARD_FAB2(SCH_1):GND
  167  GND            VSS<37>  @BASEBOARD_FAB2_LIB.BASEBOARD_FAB2(SCH_1):GND
  169  GND            VSS<36>  @BASEBOARD_FAB2_LIB.BASEBOARD_FAB2(SCH_1):GND
  171  GND            VSS<35>  @BASEBOARD_FAB2_LIB.BASEBOARD_FAB2(SCH_1):GND
  173  GND            VSS<34>  @BASEBOARD_FAB2_LIB.BASEBOARD_FAB2(SCH_1):GND
  176  GND            VSS<33>  @BASEBOARD_FAB2_LIB.BASEBOARD_FAB2(SCH_1):GND
  178  GND            VSS<32>  @BASEBOARD_FAB2_LIB.BASEBOARD_FAB2(SCH_1):GND
  180  GND            VSS<31>  @BASEBOARD_FAB2_LIB.BASEBOARD_FAB2(SCH_1):GND
  182  GND            VSS<30>  @BASEBOARD_FAB2_LIB.BASEBOARD_FAB2(SCH_1):GND
  184  GND            VSS<29>  @BASEBOARD_FAB2_LIB.BASEBOARD_FAB2(SCH_1):GND
  187  GND            VSS<28>  @BASEBOARD_FAB2_LIB.BASEBOARD_FAB2(SCH_1):GND
  189  GND            VSS<27>  @BASEBOARD_FAB2_LIB.BASEBOARD_FAB2(SCH_1):GND
  191  GND            VSS<26>  @BASEBOARD_FAB2_LIB.BASEBOARD_FAB2(SCH_1):GND
  193  GND            VSS<25>  @BASEBOARD_FAB2_LIB.BASEBOARD_FAB2(SCH_1):GND
  195  GND            VSS<24>  @BASEBOARD_FAB2_LIB.BASEBOARD_FAB2(SCH_1):GND
  198  GND            VSS<23>  @BASEBOARD_FAB2_LIB.BASEBOARD_FAB2(SCH_1):GND
  200  GND            VSS<22>  @BASEBOARD_FAB2_LIB.BASEBOARD_FAB2(SCH_1):GND
  202  GND            VSS<21>  @BASEBOARD_FAB2_LIB.BASEBOARD_FAB2(SCH_1):GND
  239  GND            VSS<20>  @BASEBOARD_FAB2_LIB.BASEBOARD_FAB2(SCH_1):GND
  241  GND            VSS<19>  @BASEBOARD_FAB2_LIB.BASEBOARD_FAB2(SCH_1):GND
  243  GND            VSS<18>  @BASEBOARD_FAB2_LIB.BASEBOARD_FAB2(SCH_1):GND
  246  GND            VSS<17>  @BASEBOARD_FAB2_LIB.BASEBOARD_FAB2(SCH_1):GND
  248  GND            VSS<16>  @BASEBOARD_FAB2_LIB.BASEBOARD_FAB2(SCH_1):GND
  250  GND            VSS<15>  @BASEBOARD_FAB2_LIB.BASEBOARD_FAB2(SCH_1):GND
  252  GND            VSS<14>  @BASEBOARD_FAB2_LIB.BASEBOARD_FAB2(SCH_1):GND
  254  GND            VSS<13>  @BASEBOARD_FAB2_LIB.BASEBOARD_FAB2(SCH_1):GND
  257  GND            VSS<12>  @BASEBOARD_FAB2_LIB.BASEBOARD_FAB2(SCH_1):GND
  259  GND            VSS<11>  @BASEBOARD_FAB2_LIB.BASEBOARD_FAB2(SCH_1):GND
  261  GND            VSS<10>  @BASEBOARD_FAB2_LIB.BASEBOARD_FAB2(SCH_1):GND
  263  GND            VSS<9>  @BASEBOARD_FAB2_LIB.BASEBOARD_FAB2(SCH_1):GND
  265  GND            VSS<8>  @BASEBOARD_FAB2_LIB.BASEBOARD_FAB2(SCH_1):GND
  268  GND            VSS<7>  @BASEBOARD_FAB2_LIB.BASEBOARD_FAB2(SCH_1):GND
  270  GND            VSS<6>  @BASEBOARD_FAB2_LIB.BASEBOARD_FAB2(SCH_1):GND
  272  GND            VSS<5>  @BASEBOARD_FAB2_LIB.BASEBOARD_FAB2(SCH_1):GND
  274  GND            VSS<4>  @BASEBOARD_FAB2_LIB.BASEBOARD_FAB2(SCH_1):GND
  276  GND            VSS<3>  @BASEBOARD_FAB2_LIB.BASEBOARD_FAB2(SCH_1):GND
  279  GND            VSS<2>  @BASEBOARD_FAB2_LIB.BASEBOARD_FAB2(SCH_1):GND
  281  GND            VSS<1>  @BASEBOARD_FAB2_LIB.BASEBOARD_FAB2(SCH_1):GND
  283  GND            VSS<0>  @BASEBOARD_FAB2_LIB.BASEBOARD_FAB2(SCH_1):GND

SCONN288_H44441004_PIP  I67  J1G3   [SCONN288_H44441004_PIP-SCONN,HA]
    7  M_J_DQS_DP<9>  DQS9P  @BASEBOARD_FAB2_LIB.BASEBOARD_FAB2(SCH_1):M_J_DQS_DP<9>
  197  M_J_DQS_DP<8>  DQS8P  @BASEBOARD_FAB2_LIB.BASEBOARD_FAB2(SCH_1):M_J_DQS_DP<8>
  278  M_J_DQS_DP<7>  DQS7P  @BASEBOARD_FAB2_LIB.BASEBOARD_FAB2(SCH_1):M_J_DQS_DP<7>
  267  M_J_DQS_DP<6>  DQS6P  @BASEBOARD_FAB2_LIB.BASEBOARD_FAB2(SCH_1):M_J_DQS_DP<6>
  256  M_J_DQS_DP<5>  DQS5P  @BASEBOARD_FAB2_LIB.BASEBOARD_FAB2(SCH_1):M_J_DQS_DP<5>
  245  M_J_DQS_DP<4>  DQS4P  @BASEBOARD_FAB2_LIB.BASEBOARD_FAB2(SCH_1):M_J_DQS_DP<4>
  186  M_J_DQS_DP<3>  DQS3P  @BASEBOARD_FAB2_LIB.BASEBOARD_FAB2(SCH_1):M_J_DQS_DP<3>
  175  M_J_DQS_DP<2>  DQS2P  @BASEBOARD_FAB2_LIB.BASEBOARD_FAB2(SCH_1):M_J_DQS_DP<2>
  164  M_J_DQS_DP<1>  DQS1P  @BASEBOARD_FAB2_LIB.BASEBOARD_FAB2(SCH_1):M_J_DQS_DP<1>
   51  M_J_DQS_DP<17>  DQS17P  @BASEBOARD_FAB2_LIB.BASEBOARD_FAB2(SCH_1):M_J_DQS_DP<17>
  132  M_J_DQS_DP<16>  DQS16P  @BASEBOARD_FAB2_LIB.BASEBOARD_FAB2(SCH_1):M_J_DQS_DP<16>
  121  M_J_DQS_DP<15>  DQS15P  @BASEBOARD_FAB2_LIB.BASEBOARD_FAB2(SCH_1):M_J_DQS_DP<15>
  110  M_J_DQS_DP<14>  DQS14P  @BASEBOARD_FAB2_LIB.BASEBOARD_FAB2(SCH_1):M_J_DQS_DP<14>
   99  M_J_DQS_DP<13>  DQS13P  @BASEBOARD_FAB2_LIB.BASEBOARD_FAB2(SCH_1):M_J_DQS_DP<13>
   40  M_J_DQS_DP<12>  DQS12P  @BASEBOARD_FAB2_LIB.BASEBOARD_FAB2(SCH_1):M_J_DQS_DP<12>
   29  M_J_DQS_DP<11>  DQS11P  @BASEBOARD_FAB2_LIB.BASEBOARD_FAB2(SCH_1):M_J_DQS_DP<11>
   18  M_J_DQS_DP<10>  DQS10P  @BASEBOARD_FAB2_LIB.BASEBOARD_FAB2(SCH_1):M_J_DQS_DP<10>
  153  M_J_DQS_DP<0>  DQS0P  @BASEBOARD_FAB2_LIB.BASEBOARD_FAB2(SCH_1):M_J_DQS_DP<0>
    8  M_J_DQS_DN<9>  DQS9N  @BASEBOARD_FAB2_LIB.BASEBOARD_FAB2(SCH_1):M_J_DQS_DN<9>
  196  M_J_DQS_DN<8>  DQS8N  @BASEBOARD_FAB2_LIB.BASEBOARD_FAB2(SCH_1):M_J_DQS_DN<8>
  277  M_J_DQS_DN<7>  DQS7N  @BASEBOARD_FAB2_LIB.BASEBOARD_FAB2(SCH_1):M_J_DQS_DN<7>
  266  M_J_DQS_DN<6>  DQS6N  @BASEBOARD_FAB2_LIB.BASEBOARD_FAB2(SCH_1):M_J_DQS_DN<6>
  255  M_J_DQS_DN<5>  DQS5N  @BASEBOARD_FAB2_LIB.BASEBOARD_FAB2(SCH_1):M_J_DQS_DN<5>
  244  M_J_DQS_DN<4>  DQS4N  @BASEBOARD_FAB2_LIB.BASEBOARD_FAB2(SCH_1):M_J_DQS_DN<4>
  185  M_J_DQS_DN<3>  DQS3N  @BASEBOARD_FAB2_LIB.BASEBOARD_FAB2(SCH_1):M_J_DQS_DN<3>
  174  M_J_DQS_DN<2>  DQS2N  @BASEBOARD_FAB2_LIB.BASEBOARD_FAB2(SCH_1):M_J_DQS_DN<2>
  163  M_J_DQS_DN<1>  DQS1N  @BASEBOARD_FAB2_LIB.BASEBOARD_FAB2(SCH_1):M_J_DQS_DN<1>
   52  M_J_DQS_DN<17>  DQS17N  @BASEBOARD_FAB2_LIB.BASEBOARD_FAB2(SCH_1):M_J_DQS_DN<17>
  133  M_J_DQS_DN<16>  DQS16N  @BASEBOARD_FAB2_LIB.BASEBOARD_FAB2(SCH_1):M_J_DQS_DN<16>
  122  M_J_DQS_DN<15>  DQS15N  @BASEBOARD_FAB2_LIB.BASEBOARD_FAB2(SCH_1):M_J_DQS_DN<15>
  111  M_J_DQS_DN<14>  DQS14N  @BASEBOARD_FAB2_LIB.BASEBOARD_FAB2(SCH_1):M_J_DQS_DN<14>
  100  M_J_DQS_DN<13>  DQS13N  @BASEBOARD_FAB2_LIB.BASEBOARD_FAB2(SCH_1):M_J_DQS_DN<13>
   41  M_J_DQS_DN<12>  DQS12N  @BASEBOARD_FAB2_LIB.BASEBOARD_FAB2(SCH_1):M_J_DQS_DN<12>
   30  M_J_DQS_DN<11>  DQS11N  @BASEBOARD_FAB2_LIB.BASEBOARD_FAB2(SCH_1):M_J_DQS_DN<11>
   19  M_J_DQS_DN<10>  DQS10N  @BASEBOARD_FAB2_LIB.BASEBOARD_FAB2(SCH_1):M_J_DQS_DN<10>
  152  M_J_DQS_DN<0>  DQS0N  @BASEBOARD_FAB2_LIB.BASEBOARD_FAB2(SCH_1):M_J_DQS_DN<0>

SCONN288_H44441004_PIP  I186  J1G3   [SCONN288_H44441004_PIP-SCONN,HA]
  144  TP_CH_J_DIMM_J0_RFU_2  RFU<2>  @BASEBOARD_FAB2_LIB.BASEBOARD_FAB2(SCH_1):TP_CH_J_DIMM_J0_RFU_2
  227  TP_CH_J_DIMM_J0_RFU_1  RFU<1>  @BASEBOARD_FAB2_LIB.BASEBOARD_FAB2(SCH_1):TP_CH_J_DIMM_J0_RFU_1
  205  TP_CH_J_DIMM_J0_RFU_0  RFU<0>  @BASEBOARD_FAB2_LIB.BASEBOARD_FAB2(SCH_1):TP_CH_J_DIMM_J0_RFU_0
  285  SMB_DDR_GHJ_VPP_SDA    SDA  @BASEBOARD_FAB2_LIB.BASEBOARD_FAB2(SCH_1):SMB_DDR_GHJ_VPP_SDA
  141  SMB_DDR_GHJ_VPP_SCL    SCL  @BASEBOARD_FAB2_LIB.BASEBOARD_FAB2(SCH_1):SMB_DDR_GHJ_VPP_SCL
  284  PVPP_GHJ       VDDSPD  @BASEBOARD_FAB2_LIB.BASEBOARD_FAB2(SCH_1):PVPP_GHJ
  238  PVPP_GHJ       SA<2>  @BASEBOARD_FAB2_LIB.BASEBOARD_FAB2(SCH_1):PVPP_GHJ
  146  M_J_VREF       VREFCA  @BASEBOARD_FAB2_LIB.BASEBOARD_FAB2(SCH_1):M_J_VREF
  222  M_J_PAR          PAR  @BASEBOARD_FAB2_LIB.BASEBOARD_FAB2(SCH_1):M_J_PAR
   91  M_J_ODT<1>     ODT<1>  @BASEBOARD_FAB2_LIB.BASEBOARD_FAB2(SCH_1):M_J_ODT<1>
   87  M_J_ODT<0>     ODT<0>  @BASEBOARD_FAB2_LIB.BASEBOARD_FAB2(SCH_1):M_J_ODT<0>
   66  M_J_MA<9>         A9  @BASEBOARD_FAB2_LIB.BASEBOARD_FAB2(SCH_1):M_J_MA<9>
   68  M_J_MA<8>         A8  @BASEBOARD_FAB2_LIB.BASEBOARD_FAB2(SCH_1):M_J_MA<8>
  211  M_J_MA<7>         A7  @BASEBOARD_FAB2_LIB.BASEBOARD_FAB2(SCH_1):M_J_MA<7>
   69  M_J_MA<6>         A6  @BASEBOARD_FAB2_LIB.BASEBOARD_FAB2(SCH_1):M_J_MA<6>
  213  M_J_MA<5>         A5  @BASEBOARD_FAB2_LIB.BASEBOARD_FAB2(SCH_1):M_J_MA<5>
  214  M_J_MA<4>         A4  @BASEBOARD_FAB2_LIB.BASEBOARD_FAB2(SCH_1):M_J_MA<4>
   71  M_J_MA<3>         A3  @BASEBOARD_FAB2_LIB.BASEBOARD_FAB2(SCH_1):M_J_MA<3>
  216  M_J_MA<2>         A2  @BASEBOARD_FAB2_LIB.BASEBOARD_FAB2(SCH_1):M_J_MA<2>
   72  M_J_MA<1>         A1  @BASEBOARD_FAB2_LIB.BASEBOARD_FAB2(SCH_1):M_J_MA<1>
  234  M_J_MA<17>       A17  @BASEBOARD_FAB2_LIB.BASEBOARD_FAB2(SCH_1):M_J_MA<17>
   82  M_J_MA<16>     A16_RAS_N  @BASEBOARD_FAB2_LIB.BASEBOARD_FAB2(SCH_1):M_J_MA<16>
   86  M_J_MA<15>     A15_CAS_N  @BASEBOARD_FAB2_LIB.BASEBOARD_FAB2(SCH_1):M_J_MA<15>
  228  M_J_MA<14>     A14_WE_N  @BASEBOARD_FAB2_LIB.BASEBOARD_FAB2(SCH_1):M_J_MA<14>
  232  M_J_MA<13>       A13  @BASEBOARD_FAB2_LIB.BASEBOARD_FAB2(SCH_1):M_J_MA<13>
   65  M_J_MA<12>       A12  @BASEBOARD_FAB2_LIB.BASEBOARD_FAB2(SCH_1):M_J_MA<12>
  210  M_J_MA<11>       A11  @BASEBOARD_FAB2_LIB.BASEBOARD_FAB2(SCH_1):M_J_MA<11>
  225  M_J_MA<10>       A10  @BASEBOARD_FAB2_LIB.BASEBOARD_FAB2(SCH_1):M_J_MA<10>
   79  M_J_MA<0>         A0  @BASEBOARD_FAB2_LIB.BASEBOARD_FAB2(SCH_1):M_J_MA<0>
   54  M_J_ECC<7>     CB<6>  @BASEBOARD_FAB2_LIB.BASEBOARD_FAB2(SCH_1):M_J_ECC<7>
  199  M_J_ECC<6>     CB<7>  @BASEBOARD_FAB2_LIB.BASEBOARD_FAB2(SCH_1):M_J_ECC<6>
   47  M_J_ECC<5>     CB<4>  @BASEBOARD_FAB2_LIB.BASEBOARD_FAB2(SCH_1):M_J_ECC<5>
  192  M_J_ECC<4>     CB<5>  @BASEBOARD_FAB2_LIB.BASEBOARD_FAB2(SCH_1):M_J_ECC<4>
   56  M_J_ECC<3>     CB<2>  @BASEBOARD_FAB2_LIB.BASEBOARD_FAB2(SCH_1):M_J_ECC<3>
  201  M_J_ECC<2>     CB<3>  @BASEBOARD_FAB2_LIB.BASEBOARD_FAB2(SCH_1):M_J_ECC<2>
   49  M_J_ECC<1>     CB<0>  @BASEBOARD_FAB2_LIB.BASEBOARD_FAB2(SCH_1):M_J_ECC<1>
  194  M_J_ECC<0>     CB<1>  @BASEBOARD_FAB2_LIB.BASEBOARD_FAB2(SCH_1):M_J_ECC<0>
   16  M_J_DQ<9>      DQ<8>  @BASEBOARD_FAB2_LIB.BASEBOARD_FAB2(SCH_1):M_J_DQ<9>
  161  M_J_DQ<8>      DQ<9>  @BASEBOARD_FAB2_LIB.BASEBOARD_FAB2(SCH_1):M_J_DQ<8>
   10  M_J_DQ<7>      DQ<6>  @BASEBOARD_FAB2_LIB.BASEBOARD_FAB2(SCH_1):M_J_DQ<7>
  155  M_J_DQ<6>      DQ<7>  @BASEBOARD_FAB2_LIB.BASEBOARD_FAB2(SCH_1):M_J_DQ<6>
  135  M_J_DQ<63>     DQ<62>  @BASEBOARD_FAB2_LIB.BASEBOARD_FAB2(SCH_1):M_J_DQ<63>
  280  M_J_DQ<62>     DQ<63>  @BASEBOARD_FAB2_LIB.BASEBOARD_FAB2(SCH_1):M_J_DQ<62>
  128  M_J_DQ<61>     DQ<60>  @BASEBOARD_FAB2_LIB.BASEBOARD_FAB2(SCH_1):M_J_DQ<61>
  273  M_J_DQ<60>     DQ<61>  @BASEBOARD_FAB2_LIB.BASEBOARD_FAB2(SCH_1):M_J_DQ<60>
    3  M_J_DQ<5>      DQ<4>  @BASEBOARD_FAB2_LIB.BASEBOARD_FAB2(SCH_1):M_J_DQ<5>
  137  M_J_DQ<59>     DQ<58>  @BASEBOARD_FAB2_LIB.BASEBOARD_FAB2(SCH_1):M_J_DQ<59>
  282  M_J_DQ<58>     DQ<59>  @BASEBOARD_FAB2_LIB.BASEBOARD_FAB2(SCH_1):M_J_DQ<58>
  130  M_J_DQ<57>     DQ<56>  @BASEBOARD_FAB2_LIB.BASEBOARD_FAB2(SCH_1):M_J_DQ<57>
  275  M_J_DQ<56>     DQ<57>  @BASEBOARD_FAB2_LIB.BASEBOARD_FAB2(SCH_1):M_J_DQ<56>
  124  M_J_DQ<55>     DQ<54>  @BASEBOARD_FAB2_LIB.BASEBOARD_FAB2(SCH_1):M_J_DQ<55>
  269  M_J_DQ<54>     DQ<55>  @BASEBOARD_FAB2_LIB.BASEBOARD_FAB2(SCH_1):M_J_DQ<54>
  117  M_J_DQ<53>     DQ<52>  @BASEBOARD_FAB2_LIB.BASEBOARD_FAB2(SCH_1):M_J_DQ<53>
  262  M_J_DQ<52>     DQ<53>  @BASEBOARD_FAB2_LIB.BASEBOARD_FAB2(SCH_1):M_J_DQ<52>
  126  M_J_DQ<51>     DQ<50>  @BASEBOARD_FAB2_LIB.BASEBOARD_FAB2(SCH_1):M_J_DQ<51>
  271  M_J_DQ<50>     DQ<51>  @BASEBOARD_FAB2_LIB.BASEBOARD_FAB2(SCH_1):M_J_DQ<50>
  148  M_J_DQ<4>      DQ<5>  @BASEBOARD_FAB2_LIB.BASEBOARD_FAB2(SCH_1):M_J_DQ<4>
  119  M_J_DQ<49>     DQ<48>  @BASEBOARD_FAB2_LIB.BASEBOARD_FAB2(SCH_1):M_J_DQ<49>
  264  M_J_DQ<48>     DQ<49>  @BASEBOARD_FAB2_LIB.BASEBOARD_FAB2(SCH_1):M_J_DQ<48>
  113  M_J_DQ<47>     DQ<46>  @BASEBOARD_FAB2_LIB.BASEBOARD_FAB2(SCH_1):M_J_DQ<47>
  258  M_J_DQ<46>     DQ<47>  @BASEBOARD_FAB2_LIB.BASEBOARD_FAB2(SCH_1):M_J_DQ<46>
  106  M_J_DQ<45>     DQ<44>  @BASEBOARD_FAB2_LIB.BASEBOARD_FAB2(SCH_1):M_J_DQ<45>
  251  M_J_DQ<44>     DQ<45>  @BASEBOARD_FAB2_LIB.BASEBOARD_FAB2(SCH_1):M_J_DQ<44>
  115  M_J_DQ<43>     DQ<42>  @BASEBOARD_FAB2_LIB.BASEBOARD_FAB2(SCH_1):M_J_DQ<43>
  260  M_J_DQ<42>     DQ<43>  @BASEBOARD_FAB2_LIB.BASEBOARD_FAB2(SCH_1):M_J_DQ<42>
  108  M_J_DQ<41>     DQ<40>  @BASEBOARD_FAB2_LIB.BASEBOARD_FAB2(SCH_1):M_J_DQ<41>
  253  M_J_DQ<40>     DQ<41>  @BASEBOARD_FAB2_LIB.BASEBOARD_FAB2(SCH_1):M_J_DQ<40>
   12  M_J_DQ<3>      DQ<2>  @BASEBOARD_FAB2_LIB.BASEBOARD_FAB2(SCH_1):M_J_DQ<3>
  102  M_J_DQ<39>     DQ<38>  @BASEBOARD_FAB2_LIB.BASEBOARD_FAB2(SCH_1):M_J_DQ<39>
  247  M_J_DQ<38>     DQ<39>  @BASEBOARD_FAB2_LIB.BASEBOARD_FAB2(SCH_1):M_J_DQ<38>
   95  M_J_DQ<37>     DQ<36>  @BASEBOARD_FAB2_LIB.BASEBOARD_FAB2(SCH_1):M_J_DQ<37>
  240  M_J_DQ<36>     DQ<37>  @BASEBOARD_FAB2_LIB.BASEBOARD_FAB2(SCH_1):M_J_DQ<36>
  104  M_J_DQ<35>     DQ<34>  @BASEBOARD_FAB2_LIB.BASEBOARD_FAB2(SCH_1):M_J_DQ<35>
  249  M_J_DQ<34>     DQ<35>  @BASEBOARD_FAB2_LIB.BASEBOARD_FAB2(SCH_1):M_J_DQ<34>
   97  M_J_DQ<33>     DQ<32>  @BASEBOARD_FAB2_LIB.BASEBOARD_FAB2(SCH_1):M_J_DQ<33>
  242  M_J_DQ<32>     DQ<33>  @BASEBOARD_FAB2_LIB.BASEBOARD_FAB2(SCH_1):M_J_DQ<32>
   43  M_J_DQ<31>     DQ<30>  @BASEBOARD_FAB2_LIB.BASEBOARD_FAB2(SCH_1):M_J_DQ<31>
  188  M_J_DQ<30>     DQ<31>  @BASEBOARD_FAB2_LIB.BASEBOARD_FAB2(SCH_1):M_J_DQ<30>
  157  M_J_DQ<2>      DQ<3>  @BASEBOARD_FAB2_LIB.BASEBOARD_FAB2(SCH_1):M_J_DQ<2>
   36  M_J_DQ<29>     DQ<28>  @BASEBOARD_FAB2_LIB.BASEBOARD_FAB2(SCH_1):M_J_DQ<29>
  181  M_J_DQ<28>     DQ<29>  @BASEBOARD_FAB2_LIB.BASEBOARD_FAB2(SCH_1):M_J_DQ<28>
   45  M_J_DQ<27>     DQ<26>  @BASEBOARD_FAB2_LIB.BASEBOARD_FAB2(SCH_1):M_J_DQ<27>
  190  M_J_DQ<26>     DQ<27>  @BASEBOARD_FAB2_LIB.BASEBOARD_FAB2(SCH_1):M_J_DQ<26>
   38  M_J_DQ<25>     DQ<24>  @BASEBOARD_FAB2_LIB.BASEBOARD_FAB2(SCH_1):M_J_DQ<25>
  183  M_J_DQ<24>     DQ<25>  @BASEBOARD_FAB2_LIB.BASEBOARD_FAB2(SCH_1):M_J_DQ<24>
   32  M_J_DQ<23>     DQ<22>  @BASEBOARD_FAB2_LIB.BASEBOARD_FAB2(SCH_1):M_J_DQ<23>
  177  M_J_DQ<22>     DQ<23>  @BASEBOARD_FAB2_LIB.BASEBOARD_FAB2(SCH_1):M_J_DQ<22>
   25  M_J_DQ<21>     DQ<20>  @BASEBOARD_FAB2_LIB.BASEBOARD_FAB2(SCH_1):M_J_DQ<21>
  170  M_J_DQ<20>     DQ<21>  @BASEBOARD_FAB2_LIB.BASEBOARD_FAB2(SCH_1):M_J_DQ<20>
    5  M_J_DQ<1>      DQ<0>  @BASEBOARD_FAB2_LIB.BASEBOARD_FAB2(SCH_1):M_J_DQ<1>
   34  M_J_DQ<19>     DQ<18>  @BASEBOARD_FAB2_LIB.BASEBOARD_FAB2(SCH_1):M_J_DQ<19>
  179  M_J_DQ<18>     DQ<19>  @BASEBOARD_FAB2_LIB.BASEBOARD_FAB2(SCH_1):M_J_DQ<18>
   27  M_J_DQ<17>     DQ<16>  @BASEBOARD_FAB2_LIB.BASEBOARD_FAB2(SCH_1):M_J_DQ<17>
  172  M_J_DQ<16>     DQ<17>  @BASEBOARD_FAB2_LIB.BASEBOARD_FAB2(SCH_1):M_J_DQ<16>
   21  M_J_DQ<15>     DQ<14>  @BASEBOARD_FAB2_LIB.BASEBOARD_FAB2(SCH_1):M_J_DQ<15>
  166  M_J_DQ<14>     DQ<15>  @BASEBOARD_FAB2_LIB.BASEBOARD_FAB2(SCH_1):M_J_DQ<14>
   14  M_J_DQ<13>     DQ<12>  @BASEBOARD_FAB2_LIB.BASEBOARD_FAB2(SCH_1):M_J_DQ<13>
  159  M_J_DQ<12>     DQ<13>  @BASEBOARD_FAB2_LIB.BASEBOARD_FAB2(SCH_1):M_J_DQ<12>
   23  M_J_DQ<11>     DQ<10>  @BASEBOARD_FAB2_LIB.BASEBOARD_FAB2(SCH_1):M_J_DQ<11>
  168  M_J_DQ<10>     DQ<11>  @BASEBOARD_FAB2_LIB.BASEBOARD_FAB2(SCH_1):M_J_DQ<10>
  150  M_J_DQ<0>      DQ<1>  @BASEBOARD_FAB2_LIB.BASEBOARD_FAB2(SCH_1):M_J_DQ<0>
  237  M_J_CS_N<3>    S3_N_C<1>  @BASEBOARD_FAB2_LIB.BASEBOARD_FAB2(SCH_1):M_J_CS_N<3>
   93  M_J_CS_N<2>    S2_N_C<0>  @BASEBOARD_FAB2_LIB.BASEBOARD_FAB2(SCH_1):M_J_CS_N<2>
   89  M_J_CS_N<1>     S1_N  @BASEBOARD_FAB2_LIB.BASEBOARD_FAB2(SCH_1):M_J_CS_N<1>
   84  M_J_CS_N<0>     S0_N  @BASEBOARD_FAB2_LIB.BASEBOARD_FAB2(SCH_1):M_J_CS_N<0>
  218  M_J_CLK_DP<1>   CK1P  @BASEBOARD_FAB2_LIB.BASEBOARD_FAB2(SCH_1):M_J_CLK_DP<1>
   74  M_J_CLK_DP<0>   CK0P  @BASEBOARD_FAB2_LIB.BASEBOARD_FAB2(SCH_1):M_J_CLK_DP<0>
  219  M_J_CLK_DN<1>   CK1N  @BASEBOARD_FAB2_LIB.BASEBOARD_FAB2(SCH_1):M_J_CLK_DN<1>
   75  M_J_CLK_DN<0>   CK0N  @BASEBOARD_FAB2_LIB.BASEBOARD_FAB2(SCH_1):M_J_CLK_DN<0>
  203  M_J_CKE<1>     CKE<1>  @BASEBOARD_FAB2_LIB.BASEBOARD_FAB2(SCH_1):M_J_CKE<1>
   60  M_J_CKE<0>     CKE<0>  @BASEBOARD_FAB2_LIB.BASEBOARD_FAB2(SCH_1):M_J_CKE<0>
  235  M_J_C<2>        C<2>  @BASEBOARD_FAB2_LIB.BASEBOARD_FAB2(SCH_1):M_J_C<2>
  207  M_J_BG<1>      BG<1>  @BASEBOARD_FAB2_LIB.BASEBOARD_FAB2(SCH_1):M_J_BG<1>
   63  M_J_BG<0>      BG<0>  @BASEBOARD_FAB2_LIB.BASEBOARD_FAB2(SCH_1):M_J_BG<0>
  224  M_J_BA<1>      BA<1>  @BASEBOARD_FAB2_LIB.BASEBOARD_FAB2(SCH_1):M_J_BA<1>
   81  M_J_BA<0>      BA<0>  @BASEBOARD_FAB2_LIB.BASEBOARD_FAB2(SCH_1):M_J_BA<0>
  208  M_J_ALERT_N    ALERT_N  @BASEBOARD_FAB2_LIB.BASEBOARD_FAB2(SCH_1):M_J_ALERT_N
   62  M_J_ACT_N      ACT_N  @BASEBOARD_FAB2_LIB.BASEBOARD_FAB2(SCH_1):M_J_ACT_N
   58  M_GHJ_RST_N    RESET_N  @BASEBOARD_FAB2_LIB.BASEBOARD_FAB2(SCH_1):M_GHJ_RST_N
  140  GND            SA<1>  @BASEBOARD_FAB2_LIB.BASEBOARD_FAB2(SCH_1):GND
  139  GND            SA<0>  @BASEBOARD_FAB2_LIB.BASEBOARD_FAB2(SCH_1):GND
   78  FM_DIMM_EVENT_COD_N  EVENT_N  @BASEBOARD_FAB2_LIB.BASEBOARD_FAB2(SCH_1):FM_DIMM_EVENT_COD_N
  230  FM_ADR_COMPLETE_GHJ_N  SAVE_N_NC  @BASEBOARD_FAB2_LIB.BASEBOARD_FAB2(SCH_1):FM_ADR_COMPLETE_GHJ_N

CONN4_H73295001_PIP  I53  J2L1   [CONN4_H73295001_PIP-CONN,H7329A]
    1  P5V_HDD_SATA     IO1  @BASEBOARD_FAB2_LIB.BASEBOARD_FAB2(SCH_1):P5V_HDD_SATA
    4  P12V_HDD_SATA    IO4  @BASEBOARD_FAB2_LIB.BASEBOARD_FAB2(SCH_1):P12V_HDD_SATA
    3  GND              IO3  @BASEBOARD_FAB2_LIB.BASEBOARD_FAB2(SCH_1):GND
    2  GND              IO2  @BASEBOARD_FAB2_LIB.BASEBOARD_FAB2(SCH_1):GND

CONN7_E82125014_PIP_TH  I52  J2M1   [CONN7_E82125014_PIP_TH-CONN,E8A]
    2  SATA6G_S1_TX_C_DP  SATA_TXP  @BASEBOARD_FAB2_LIB.BASEBOARD_FAB2(SCH_1):SATA6G_S1_TX_C_DP
    3  SATA6G_S1_TX_C_DN  SATA_TXN  @BASEBOARD_FAB2_LIB.BASEBOARD_FAB2(SCH_1):SATA6G_S1_TX_C_DN
    6  SATA6G_S1_RX_C_DP  SATA_RXP  @BASEBOARD_FAB2_LIB.BASEBOARD_FAB2(SCH_1):SATA6G_S1_RX_C_DP
    5  SATA6G_S1_RX_C_DN  SATA_RXN  @BASEBOARD_FAB2_LIB.BASEBOARD_FAB2(SCH_1):SATA6G_S1_RX_C_DN
  MH2  GND              MH2  @BASEBOARD_FAB2_LIB.BASEBOARD_FAB2(SCH_1):GND
  MH1  GND              MH1  @BASEBOARD_FAB2_LIB.BASEBOARD_FAB2(SCH_1):GND
    1  GND            GND<2>  @BASEBOARD_FAB2_LIB.BASEBOARD_FAB2(SCH_1):GND
    4  GND            GND<1>  @BASEBOARD_FAB2_LIB.BASEBOARD_FAB2(SCH_1):GND
    7  GND            GND<0>  @BASEBOARD_FAB2_LIB.BASEBOARD_FAB2(SCH_1):GND

SCONN288_H44441004_PIP  I171  J4A1   [SCONN288_H44441004_PIP-SCONN,HA]
   77  PVTT_DEF       VTT<1>  @BASEBOARD_FAB2_LIB.BASEBOARD_FAB2(SCH_1):PVTT_DEF
  221  PVTT_DEF       VTT<0>  @BASEBOARD_FAB2_LIB.BASEBOARD_FAB2(SCH_1):PVTT_DEF
  142  PVPP_DEF       VPP<4>  @BASEBOARD_FAB2_LIB.BASEBOARD_FAB2(SCH_1):PVPP_DEF
  143  PVPP_DEF       VPP<3>  @BASEBOARD_FAB2_LIB.BASEBOARD_FAB2(SCH_1):PVPP_DEF
  288  PVPP_DEF       VPP<2>  @BASEBOARD_FAB2_LIB.BASEBOARD_FAB2(SCH_1):PVPP_DEF
  286  PVPP_DEF       VPP<1>  @BASEBOARD_FAB2_LIB.BASEBOARD_FAB2(SCH_1):PVPP_DEF
  287  PVPP_DEF       VPP<0>  @BASEBOARD_FAB2_LIB.BASEBOARD_FAB2(SCH_1):PVPP_DEF
   59  PVDDQ_DEF      VDD<25>  @BASEBOARD_FAB2_LIB.BASEBOARD_FAB2(SCH_1):PVDDQ_DEF
   61  PVDDQ_DEF      VDD<24>  @BASEBOARD_FAB2_LIB.BASEBOARD_FAB2(SCH_1):PVDDQ_DEF
   64  PVDDQ_DEF      VDD<23>  @BASEBOARD_FAB2_LIB.BASEBOARD_FAB2(SCH_1):PVDDQ_DEF
   67  PVDDQ_DEF      VDD<22>  @BASEBOARD_FAB2_LIB.BASEBOARD_FAB2(SCH_1):PVDDQ_DEF
   70  PVDDQ_DEF      VDD<21>  @BASEBOARD_FAB2_LIB.BASEBOARD_FAB2(SCH_1):PVDDQ_DEF
   73  PVDDQ_DEF      VDD<20>  @BASEBOARD_FAB2_LIB.BASEBOARD_FAB2(SCH_1):PVDDQ_DEF
   76  PVDDQ_DEF      VDD<19>  @BASEBOARD_FAB2_LIB.BASEBOARD_FAB2(SCH_1):PVDDQ_DEF
   80  PVDDQ_DEF      VDD<18>  @BASEBOARD_FAB2_LIB.BASEBOARD_FAB2(SCH_1):PVDDQ_DEF
   83  PVDDQ_DEF      VDD<17>  @BASEBOARD_FAB2_LIB.BASEBOARD_FAB2(SCH_1):PVDDQ_DEF
   85  PVDDQ_DEF      VDD<16>  @BASEBOARD_FAB2_LIB.BASEBOARD_FAB2(SCH_1):PVDDQ_DEF
   88  PVDDQ_DEF      VDD<15>  @BASEBOARD_FAB2_LIB.BASEBOARD_FAB2(SCH_1):PVDDQ_DEF
   90  PVDDQ_DEF      VDD<14>  @BASEBOARD_FAB2_LIB.BASEBOARD_FAB2(SCH_1):PVDDQ_DEF
   92  PVDDQ_DEF      VDD<13>  @BASEBOARD_FAB2_LIB.BASEBOARD_FAB2(SCH_1):PVDDQ_DEF
  204  PVDDQ_DEF      VDD<12>  @BASEBOARD_FAB2_LIB.BASEBOARD_FAB2(SCH_1):PVDDQ_DEF
  206  PVDDQ_DEF      VDD<11>  @BASEBOARD_FAB2_LIB.BASEBOARD_FAB2(SCH_1):PVDDQ_DEF
  209  PVDDQ_DEF      VDD<10>  @BASEBOARD_FAB2_LIB.BASEBOARD_FAB2(SCH_1):PVDDQ_DEF
  212  PVDDQ_DEF      VDD<9>  @BASEBOARD_FAB2_LIB.BASEBOARD_FAB2(SCH_1):PVDDQ_DEF
  215  PVDDQ_DEF      VDD<8>  @BASEBOARD_FAB2_LIB.BASEBOARD_FAB2(SCH_1):PVDDQ_DEF
  217  PVDDQ_DEF      VDD<7>  @BASEBOARD_FAB2_LIB.BASEBOARD_FAB2(SCH_1):PVDDQ_DEF
  220  PVDDQ_DEF      VDD<6>  @BASEBOARD_FAB2_LIB.BASEBOARD_FAB2(SCH_1):PVDDQ_DEF
  223  PVDDQ_DEF      VDD<5>  @BASEBOARD_FAB2_LIB.BASEBOARD_FAB2(SCH_1):PVDDQ_DEF
  226  PVDDQ_DEF      VDD<4>  @BASEBOARD_FAB2_LIB.BASEBOARD_FAB2(SCH_1):PVDDQ_DEF
  229  PVDDQ_DEF      VDD<3>  @BASEBOARD_FAB2_LIB.BASEBOARD_FAB2(SCH_1):PVDDQ_DEF
  231  PVDDQ_DEF      VDD<2>  @BASEBOARD_FAB2_LIB.BASEBOARD_FAB2(SCH_1):PVDDQ_DEF
  233  PVDDQ_DEF      VDD<1>  @BASEBOARD_FAB2_LIB.BASEBOARD_FAB2(SCH_1):PVDDQ_DEF
  236  PVDDQ_DEF      VDD<0>  @BASEBOARD_FAB2_LIB.BASEBOARD_FAB2(SCH_1):PVDDQ_DEF
    1  P12V_NVDIMM_DEF  12V<1>  @BASEBOARD_FAB2_LIB.BASEBOARD_FAB2(SCH_1):P12V_NVDIMM_DEF
  145  P12V_NVDIMM_DEF  12V<0>  @BASEBOARD_FAB2_LIB.BASEBOARD_FAB2(SCH_1):P12V_NVDIMM_DEF

SCONN288_H44441004_PIP  I43  J4A1   [SCONN288_H44441004_PIP-SCONN,HA]
    2  GND            VSS<93>  @BASEBOARD_FAB2_LIB.BASEBOARD_FAB2(SCH_1):GND
    4  GND            VSS<92>  @BASEBOARD_FAB2_LIB.BASEBOARD_FAB2(SCH_1):GND
    6  GND            VSS<91>  @BASEBOARD_FAB2_LIB.BASEBOARD_FAB2(SCH_1):GND
    9  GND            VSS<90>  @BASEBOARD_FAB2_LIB.BASEBOARD_FAB2(SCH_1):GND
   11  GND            VSS<89>  @BASEBOARD_FAB2_LIB.BASEBOARD_FAB2(SCH_1):GND
   13  GND            VSS<88>  @BASEBOARD_FAB2_LIB.BASEBOARD_FAB2(SCH_1):GND
   15  GND            VSS<87>  @BASEBOARD_FAB2_LIB.BASEBOARD_FAB2(SCH_1):GND
   17  GND            VSS<86>  @BASEBOARD_FAB2_LIB.BASEBOARD_FAB2(SCH_1):GND
   20  GND            VSS<85>  @BASEBOARD_FAB2_LIB.BASEBOARD_FAB2(SCH_1):GND
   22  GND            VSS<84>  @BASEBOARD_FAB2_LIB.BASEBOARD_FAB2(SCH_1):GND
   24  GND            VSS<83>  @BASEBOARD_FAB2_LIB.BASEBOARD_FAB2(SCH_1):GND
   26  GND            VSS<82>  @BASEBOARD_FAB2_LIB.BASEBOARD_FAB2(SCH_1):GND
   28  GND            VSS<81>  @BASEBOARD_FAB2_LIB.BASEBOARD_FAB2(SCH_1):GND
   31  GND            VSS<80>  @BASEBOARD_FAB2_LIB.BASEBOARD_FAB2(SCH_1):GND
   33  GND            VSS<79>  @BASEBOARD_FAB2_LIB.BASEBOARD_FAB2(SCH_1):GND
   35  GND            VSS<78>  @BASEBOARD_FAB2_LIB.BASEBOARD_FAB2(SCH_1):GND
   37  GND            VSS<77>  @BASEBOARD_FAB2_LIB.BASEBOARD_FAB2(SCH_1):GND
   39  GND            VSS<76>  @BASEBOARD_FAB2_LIB.BASEBOARD_FAB2(SCH_1):GND
   42  GND            VSS<75>  @BASEBOARD_FAB2_LIB.BASEBOARD_FAB2(SCH_1):GND
   44  GND            VSS<74>  @BASEBOARD_FAB2_LIB.BASEBOARD_FAB2(SCH_1):GND
   46  GND            VSS<73>  @BASEBOARD_FAB2_LIB.BASEBOARD_FAB2(SCH_1):GND
   48  GND            VSS<72>  @BASEBOARD_FAB2_LIB.BASEBOARD_FAB2(SCH_1):GND
   50  GND            VSS<71>  @BASEBOARD_FAB2_LIB.BASEBOARD_FAB2(SCH_1):GND
   53  GND            VSS<70>  @BASEBOARD_FAB2_LIB.BASEBOARD_FAB2(SCH_1):GND
   55  GND            VSS<69>  @BASEBOARD_FAB2_LIB.BASEBOARD_FAB2(SCH_1):GND
   57  GND            VSS<68>  @BASEBOARD_FAB2_LIB.BASEBOARD_FAB2(SCH_1):GND
   94  GND            VSS<67>  @BASEBOARD_FAB2_LIB.BASEBOARD_FAB2(SCH_1):GND
   96  GND            VSS<66>  @BASEBOARD_FAB2_LIB.BASEBOARD_FAB2(SCH_1):GND
   98  GND            VSS<65>  @BASEBOARD_FAB2_LIB.BASEBOARD_FAB2(SCH_1):GND
  101  GND            VSS<64>  @BASEBOARD_FAB2_LIB.BASEBOARD_FAB2(SCH_1):GND
  103  GND            VSS<63>  @BASEBOARD_FAB2_LIB.BASEBOARD_FAB2(SCH_1):GND
  105  GND            VSS<62>  @BASEBOARD_FAB2_LIB.BASEBOARD_FAB2(SCH_1):GND
  107  GND            VSS<61>  @BASEBOARD_FAB2_LIB.BASEBOARD_FAB2(SCH_1):GND
  109  GND            VSS<60>  @BASEBOARD_FAB2_LIB.BASEBOARD_FAB2(SCH_1):GND
  112  GND            VSS<59>  @BASEBOARD_FAB2_LIB.BASEBOARD_FAB2(SCH_1):GND
  114  GND            VSS<58>  @BASEBOARD_FAB2_LIB.BASEBOARD_FAB2(SCH_1):GND
  116  GND            VSS<57>  @BASEBOARD_FAB2_LIB.BASEBOARD_FAB2(SCH_1):GND
  118  GND            VSS<56>  @BASEBOARD_FAB2_LIB.BASEBOARD_FAB2(SCH_1):GND
  120  GND            VSS<55>  @BASEBOARD_FAB2_LIB.BASEBOARD_FAB2(SCH_1):GND
  123  GND            VSS<54>  @BASEBOARD_FAB2_LIB.BASEBOARD_FAB2(SCH_1):GND
  125  GND            VSS<53>  @BASEBOARD_FAB2_LIB.BASEBOARD_FAB2(SCH_1):GND
  127  GND            VSS<52>  @BASEBOARD_FAB2_LIB.BASEBOARD_FAB2(SCH_1):GND
  129  GND            VSS<51>  @BASEBOARD_FAB2_LIB.BASEBOARD_FAB2(SCH_1):GND
  131  GND            VSS<50>  @BASEBOARD_FAB2_LIB.BASEBOARD_FAB2(SCH_1):GND
  134  GND            VSS<49>  @BASEBOARD_FAB2_LIB.BASEBOARD_FAB2(SCH_1):GND
  136  GND            VSS<48>  @BASEBOARD_FAB2_LIB.BASEBOARD_FAB2(SCH_1):GND
  138  GND            VSS<47>  @BASEBOARD_FAB2_LIB.BASEBOARD_FAB2(SCH_1):GND
  147  GND            VSS<46>  @BASEBOARD_FAB2_LIB.BASEBOARD_FAB2(SCH_1):GND
  149  GND            VSS<45>  @BASEBOARD_FAB2_LIB.BASEBOARD_FAB2(SCH_1):GND
  151  GND            VSS<44>  @BASEBOARD_FAB2_LIB.BASEBOARD_FAB2(SCH_1):GND
  154  GND            VSS<43>  @BASEBOARD_FAB2_LIB.BASEBOARD_FAB2(SCH_1):GND
  156  GND            VSS<42>  @BASEBOARD_FAB2_LIB.BASEBOARD_FAB2(SCH_1):GND
  158  GND            VSS<41>  @BASEBOARD_FAB2_LIB.BASEBOARD_FAB2(SCH_1):GND
  160  GND            VSS<40>  @BASEBOARD_FAB2_LIB.BASEBOARD_FAB2(SCH_1):GND
  162  GND            VSS<39>  @BASEBOARD_FAB2_LIB.BASEBOARD_FAB2(SCH_1):GND
  165  GND            VSS<38>  @BASEBOARD_FAB2_LIB.BASEBOARD_FAB2(SCH_1):GND
  167  GND            VSS<37>  @BASEBOARD_FAB2_LIB.BASEBOARD_FAB2(SCH_1):GND
  169  GND            VSS<36>  @BASEBOARD_FAB2_LIB.BASEBOARD_FAB2(SCH_1):GND
  171  GND            VSS<35>  @BASEBOARD_FAB2_LIB.BASEBOARD_FAB2(SCH_1):GND
  173  GND            VSS<34>  @BASEBOARD_FAB2_LIB.BASEBOARD_FAB2(SCH_1):GND
  176  GND            VSS<33>  @BASEBOARD_FAB2_LIB.BASEBOARD_FAB2(SCH_1):GND
  178  GND            VSS<32>  @BASEBOARD_FAB2_LIB.BASEBOARD_FAB2(SCH_1):GND
  180  GND            VSS<31>  @BASEBOARD_FAB2_LIB.BASEBOARD_FAB2(SCH_1):GND
  182  GND            VSS<30>  @BASEBOARD_FAB2_LIB.BASEBOARD_FAB2(SCH_1):GND
  184  GND            VSS<29>  @BASEBOARD_FAB2_LIB.BASEBOARD_FAB2(SCH_1):GND
  187  GND            VSS<28>  @BASEBOARD_FAB2_LIB.BASEBOARD_FAB2(SCH_1):GND
  189  GND            VSS<27>  @BASEBOARD_FAB2_LIB.BASEBOARD_FAB2(SCH_1):GND
  191  GND            VSS<26>  @BASEBOARD_FAB2_LIB.BASEBOARD_FAB2(SCH_1):GND
  193  GND            VSS<25>  @BASEBOARD_FAB2_LIB.BASEBOARD_FAB2(SCH_1):GND
  195  GND            VSS<24>  @BASEBOARD_FAB2_LIB.BASEBOARD_FAB2(SCH_1):GND
  198  GND            VSS<23>  @BASEBOARD_FAB2_LIB.BASEBOARD_FAB2(SCH_1):GND
  200  GND            VSS<22>  @BASEBOARD_FAB2_LIB.BASEBOARD_FAB2(SCH_1):GND
  202  GND            VSS<21>  @BASEBOARD_FAB2_LIB.BASEBOARD_FAB2(SCH_1):GND
  239  GND            VSS<20>  @BASEBOARD_FAB2_LIB.BASEBOARD_FAB2(SCH_1):GND
  241  GND            VSS<19>  @BASEBOARD_FAB2_LIB.BASEBOARD_FAB2(SCH_1):GND
  243  GND            VSS<18>  @BASEBOARD_FAB2_LIB.BASEBOARD_FAB2(SCH_1):GND
  246  GND            VSS<17>  @BASEBOARD_FAB2_LIB.BASEBOARD_FAB2(SCH_1):GND
  248  GND            VSS<16>  @BASEBOARD_FAB2_LIB.BASEBOARD_FAB2(SCH_1):GND
  250  GND            VSS<15>  @BASEBOARD_FAB2_LIB.BASEBOARD_FAB2(SCH_1):GND
  252  GND            VSS<14>  @BASEBOARD_FAB2_LIB.BASEBOARD_FAB2(SCH_1):GND
  254  GND            VSS<13>  @BASEBOARD_FAB2_LIB.BASEBOARD_FAB2(SCH_1):GND
  257  GND            VSS<12>  @BASEBOARD_FAB2_LIB.BASEBOARD_FAB2(SCH_1):GND
  259  GND            VSS<11>  @BASEBOARD_FAB2_LIB.BASEBOARD_FAB2(SCH_1):GND
  261  GND            VSS<10>  @BASEBOARD_FAB2_LIB.BASEBOARD_FAB2(SCH_1):GND
  263  GND            VSS<9>  @BASEBOARD_FAB2_LIB.BASEBOARD_FAB2(SCH_1):GND
  265  GND            VSS<8>  @BASEBOARD_FAB2_LIB.BASEBOARD_FAB2(SCH_1):GND
  268  GND            VSS<7>  @BASEBOARD_FAB2_LIB.BASEBOARD_FAB2(SCH_1):GND
  270  GND            VSS<6>  @BASEBOARD_FAB2_LIB.BASEBOARD_FAB2(SCH_1):GND
  272  GND            VSS<5>  @BASEBOARD_FAB2_LIB.BASEBOARD_FAB2(SCH_1):GND
  274  GND            VSS<4>  @BASEBOARD_FAB2_LIB.BASEBOARD_FAB2(SCH_1):GND
  276  GND            VSS<3>  @BASEBOARD_FAB2_LIB.BASEBOARD_FAB2(SCH_1):GND
  279  GND            VSS<2>  @BASEBOARD_FAB2_LIB.BASEBOARD_FAB2(SCH_1):GND
  281  GND            VSS<1>  @BASEBOARD_FAB2_LIB.BASEBOARD_FAB2(SCH_1):GND
  283  GND            VSS<0>  @BASEBOARD_FAB2_LIB.BASEBOARD_FAB2(SCH_1):GND

SCONN288_H44441004_PIP  I66  J4A1   [SCONN288_H44441004_PIP-SCONN,HA]
    7  M_F_DQS_DP<9>  DQS9P  @BASEBOARD_FAB2_LIB.BASEBOARD_FAB2(SCH_1):M_F_DQS_DP<9>
  197  M_F_DQS_DP<8>  DQS8P  @BASEBOARD_FAB2_LIB.BASEBOARD_FAB2(SCH_1):M_F_DQS_DP<8>
  278  M_F_DQS_DP<7>  DQS7P  @BASEBOARD_FAB2_LIB.BASEBOARD_FAB2(SCH_1):M_F_DQS_DP<7>
  267  M_F_DQS_DP<6>  DQS6P  @BASEBOARD_FAB2_LIB.BASEBOARD_FAB2(SCH_1):M_F_DQS_DP<6>
  256  M_F_DQS_DP<5>  DQS5P  @BASEBOARD_FAB2_LIB.BASEBOARD_FAB2(SCH_1):M_F_DQS_DP<5>
  245  M_F_DQS_DP<4>  DQS4P  @BASEBOARD_FAB2_LIB.BASEBOARD_FAB2(SCH_1):M_F_DQS_DP<4>
  186  M_F_DQS_DP<3>  DQS3P  @BASEBOARD_FAB2_LIB.BASEBOARD_FAB2(SCH_1):M_F_DQS_DP<3>
  175  M_F_DQS_DP<2>  DQS2P  @BASEBOARD_FAB2_LIB.BASEBOARD_FAB2(SCH_1):M_F_DQS_DP<2>
  164  M_F_DQS_DP<1>  DQS1P  @BASEBOARD_FAB2_LIB.BASEBOARD_FAB2(SCH_1):M_F_DQS_DP<1>
   51  M_F_DQS_DP<17>  DQS17P  @BASEBOARD_FAB2_LIB.BASEBOARD_FAB2(SCH_1):M_F_DQS_DP<17>
  132  M_F_DQS_DP<16>  DQS16P  @BASEBOARD_FAB2_LIB.BASEBOARD_FAB2(SCH_1):M_F_DQS_DP<16>
  121  M_F_DQS_DP<15>  DQS15P  @BASEBOARD_FAB2_LIB.BASEBOARD_FAB2(SCH_1):M_F_DQS_DP<15>
  110  M_F_DQS_DP<14>  DQS14P  @BASEBOARD_FAB2_LIB.BASEBOARD_FAB2(SCH_1):M_F_DQS_DP<14>
   99  M_F_DQS_DP<13>  DQS13P  @BASEBOARD_FAB2_LIB.BASEBOARD_FAB2(SCH_1):M_F_DQS_DP<13>
   40  M_F_DQS_DP<12>  DQS12P  @BASEBOARD_FAB2_LIB.BASEBOARD_FAB2(SCH_1):M_F_DQS_DP<12>
   29  M_F_DQS_DP<11>  DQS11P  @BASEBOARD_FAB2_LIB.BASEBOARD_FAB2(SCH_1):M_F_DQS_DP<11>
   18  M_F_DQS_DP<10>  DQS10P  @BASEBOARD_FAB2_LIB.BASEBOARD_FAB2(SCH_1):M_F_DQS_DP<10>
  153  M_F_DQS_DP<0>  DQS0P  @BASEBOARD_FAB2_LIB.BASEBOARD_FAB2(SCH_1):M_F_DQS_DP<0>
    8  M_F_DQS_DN<9>  DQS9N  @BASEBOARD_FAB2_LIB.BASEBOARD_FAB2(SCH_1):M_F_DQS_DN<9>
  196  M_F_DQS_DN<8>  DQS8N  @BASEBOARD_FAB2_LIB.BASEBOARD_FAB2(SCH_1):M_F_DQS_DN<8>
  277  M_F_DQS_DN<7>  DQS7N  @BASEBOARD_FAB2_LIB.BASEBOARD_FAB2(SCH_1):M_F_DQS_DN<7>
  266  M_F_DQS_DN<6>  DQS6N  @BASEBOARD_FAB2_LIB.BASEBOARD_FAB2(SCH_1):M_F_DQS_DN<6>
  255  M_F_DQS_DN<5>  DQS5N  @BASEBOARD_FAB2_LIB.BASEBOARD_FAB2(SCH_1):M_F_DQS_DN<5>
  244  M_F_DQS_DN<4>  DQS4N  @BASEBOARD_FAB2_LIB.BASEBOARD_FAB2(SCH_1):M_F_DQS_DN<4>
  185  M_F_DQS_DN<3>  DQS3N  @BASEBOARD_FAB2_LIB.BASEBOARD_FAB2(SCH_1):M_F_DQS_DN<3>
  174  M_F_DQS_DN<2>  DQS2N  @BASEBOARD_FAB2_LIB.BASEBOARD_FAB2(SCH_1):M_F_DQS_DN<2>
  163  M_F_DQS_DN<1>  DQS1N  @BASEBOARD_FAB2_LIB.BASEBOARD_FAB2(SCH_1):M_F_DQS_DN<1>
   52  M_F_DQS_DN<17>  DQS17N  @BASEBOARD_FAB2_LIB.BASEBOARD_FAB2(SCH_1):M_F_DQS_DN<17>
  133  M_F_DQS_DN<16>  DQS16N  @BASEBOARD_FAB2_LIB.BASEBOARD_FAB2(SCH_1):M_F_DQS_DN<16>
  122  M_F_DQS_DN<15>  DQS15N  @BASEBOARD_FAB2_LIB.BASEBOARD_FAB2(SCH_1):M_F_DQS_DN<15>
  111  M_F_DQS_DN<14>  DQS14N  @BASEBOARD_FAB2_LIB.BASEBOARD_FAB2(SCH_1):M_F_DQS_DN<14>
  100  M_F_DQS_DN<13>  DQS13N  @BASEBOARD_FAB2_LIB.BASEBOARD_FAB2(SCH_1):M_F_DQS_DN<13>
   41  M_F_DQS_DN<12>  DQS12N  @BASEBOARD_FAB2_LIB.BASEBOARD_FAB2(SCH_1):M_F_DQS_DN<12>
   30  M_F_DQS_DN<11>  DQS11N  @BASEBOARD_FAB2_LIB.BASEBOARD_FAB2(SCH_1):M_F_DQS_DN<11>
   19  M_F_DQS_DN<10>  DQS10N  @BASEBOARD_FAB2_LIB.BASEBOARD_FAB2(SCH_1):M_F_DQS_DN<10>
  152  M_F_DQS_DN<0>  DQS0N  @BASEBOARD_FAB2_LIB.BASEBOARD_FAB2(SCH_1):M_F_DQS_DN<0>

SCONN288_H44441004_PIP  I111  J4A1   [SCONN288_H44441004_PIP-SCONN,HA]
  144  TP_CH_F_DIMM_F0_RFU_2  RFU<2>  @BASEBOARD_FAB2_LIB.BASEBOARD_FAB2(SCH_1):TP_CH_F_DIMM_F0_RFU_2
  227  TP_CH_F_DIMM_F0_RFU_1  RFU<1>  @BASEBOARD_FAB2_LIB.BASEBOARD_FAB2(SCH_1):TP_CH_F_DIMM_F0_RFU_1
  205  TP_CH_F_DIMM_F0_RFU_0  RFU<0>  @BASEBOARD_FAB2_LIB.BASEBOARD_FAB2(SCH_1):TP_CH_F_DIMM_F0_RFU_0
  285  SMB_DDR_DEF_VPP_SDA    SDA  @BASEBOARD_FAB2_LIB.BASEBOARD_FAB2(SCH_1):SMB_DDR_DEF_VPP_SDA
  141  SMB_DDR_DEF_VPP_SCL    SCL  @BASEBOARD_FAB2_LIB.BASEBOARD_FAB2(SCH_1):SMB_DDR_DEF_VPP_SCL
  284  PVPP_DEF       VDDSPD  @BASEBOARD_FAB2_LIB.BASEBOARD_FAB2(SCH_1):PVPP_DEF
  238  PVPP_DEF       SA<2>  @BASEBOARD_FAB2_LIB.BASEBOARD_FAB2(SCH_1):PVPP_DEF
  146  M_F_VREF       VREFCA  @BASEBOARD_FAB2_LIB.BASEBOARD_FAB2(SCH_1):M_F_VREF
  222  M_F_PAR          PAR  @BASEBOARD_FAB2_LIB.BASEBOARD_FAB2(SCH_1):M_F_PAR
   91  M_F_ODT<1>     ODT<1>  @BASEBOARD_FAB2_LIB.BASEBOARD_FAB2(SCH_1):M_F_ODT<1>
   87  M_F_ODT<0>     ODT<0>  @BASEBOARD_FAB2_LIB.BASEBOARD_FAB2(SCH_1):M_F_ODT<0>
   66  M_F_MA<9>         A9  @BASEBOARD_FAB2_LIB.BASEBOARD_FAB2(SCH_1):M_F_MA<9>
   68  M_F_MA<8>         A8  @BASEBOARD_FAB2_LIB.BASEBOARD_FAB2(SCH_1):M_F_MA<8>
  211  M_F_MA<7>         A7  @BASEBOARD_FAB2_LIB.BASEBOARD_FAB2(SCH_1):M_F_MA<7>
   69  M_F_MA<6>         A6  @BASEBOARD_FAB2_LIB.BASEBOARD_FAB2(SCH_1):M_F_MA<6>
  213  M_F_MA<5>         A5  @BASEBOARD_FAB2_LIB.BASEBOARD_FAB2(SCH_1):M_F_MA<5>
  214  M_F_MA<4>         A4  @BASEBOARD_FAB2_LIB.BASEBOARD_FAB2(SCH_1):M_F_MA<4>
   71  M_F_MA<3>         A3  @BASEBOARD_FAB2_LIB.BASEBOARD_FAB2(SCH_1):M_F_MA<3>
  216  M_F_MA<2>         A2  @BASEBOARD_FAB2_LIB.BASEBOARD_FAB2(SCH_1):M_F_MA<2>
   72  M_F_MA<1>         A1  @BASEBOARD_FAB2_LIB.BASEBOARD_FAB2(SCH_1):M_F_MA<1>
  234  M_F_MA<17>       A17  @BASEBOARD_FAB2_LIB.BASEBOARD_FAB2(SCH_1):M_F_MA<17>
   82  M_F_MA<16>     A16_RAS_N  @BASEBOARD_FAB2_LIB.BASEBOARD_FAB2(SCH_1):M_F_MA<16>
   86  M_F_MA<15>     A15_CAS_N  @BASEBOARD_FAB2_LIB.BASEBOARD_FAB2(SCH_1):M_F_MA<15>
  228  M_F_MA<14>     A14_WE_N  @BASEBOARD_FAB2_LIB.BASEBOARD_FAB2(SCH_1):M_F_MA<14>
  232  M_F_MA<13>       A13  @BASEBOARD_FAB2_LIB.BASEBOARD_FAB2(SCH_1):M_F_MA<13>
   65  M_F_MA<12>       A12  @BASEBOARD_FAB2_LIB.BASEBOARD_FAB2(SCH_1):M_F_MA<12>
  210  M_F_MA<11>       A11  @BASEBOARD_FAB2_LIB.BASEBOARD_FAB2(SCH_1):M_F_MA<11>
  225  M_F_MA<10>       A10  @BASEBOARD_FAB2_LIB.BASEBOARD_FAB2(SCH_1):M_F_MA<10>
   79  M_F_MA<0>         A0  @BASEBOARD_FAB2_LIB.BASEBOARD_FAB2(SCH_1):M_F_MA<0>
   54  M_F_ECC<7>     CB<6>  @BASEBOARD_FAB2_LIB.BASEBOARD_FAB2(SCH_1):M_F_ECC<7>
  199  M_F_ECC<6>     CB<7>  @BASEBOARD_FAB2_LIB.BASEBOARD_FAB2(SCH_1):M_F_ECC<6>
   47  M_F_ECC<5>     CB<4>  @BASEBOARD_FAB2_LIB.BASEBOARD_FAB2(SCH_1):M_F_ECC<5>
  192  M_F_ECC<4>     CB<5>  @BASEBOARD_FAB2_LIB.BASEBOARD_FAB2(SCH_1):M_F_ECC<4>
   56  M_F_ECC<3>     CB<2>  @BASEBOARD_FAB2_LIB.BASEBOARD_FAB2(SCH_1):M_F_ECC<3>
  201  M_F_ECC<2>     CB<3>  @BASEBOARD_FAB2_LIB.BASEBOARD_FAB2(SCH_1):M_F_ECC<2>
   49  M_F_ECC<1>     CB<0>  @BASEBOARD_FAB2_LIB.BASEBOARD_FAB2(SCH_1):M_F_ECC<1>
  194  M_F_ECC<0>     CB<1>  @BASEBOARD_FAB2_LIB.BASEBOARD_FAB2(SCH_1):M_F_ECC<0>
   16  M_F_DQ<9>      DQ<8>  @BASEBOARD_FAB2_LIB.BASEBOARD_FAB2(SCH_1):M_F_DQ<9>
  161  M_F_DQ<8>      DQ<9>  @BASEBOARD_FAB2_LIB.BASEBOARD_FAB2(SCH_1):M_F_DQ<8>
   10  M_F_DQ<7>      DQ<6>  @BASEBOARD_FAB2_LIB.BASEBOARD_FAB2(SCH_1):M_F_DQ<7>
  155  M_F_DQ<6>      DQ<7>  @BASEBOARD_FAB2_LIB.BASEBOARD_FAB2(SCH_1):M_F_DQ<6>
  135  M_F_DQ<63>     DQ<62>  @BASEBOARD_FAB2_LIB.BASEBOARD_FAB2(SCH_1):M_F_DQ<63>
  280  M_F_DQ<62>     DQ<63>  @BASEBOARD_FAB2_LIB.BASEBOARD_FAB2(SCH_1):M_F_DQ<62>
  128  M_F_DQ<61>     DQ<60>  @BASEBOARD_FAB2_LIB.BASEBOARD_FAB2(SCH_1):M_F_DQ<61>
  273  M_F_DQ<60>     DQ<61>  @BASEBOARD_FAB2_LIB.BASEBOARD_FAB2(SCH_1):M_F_DQ<60>
    3  M_F_DQ<5>      DQ<4>  @BASEBOARD_FAB2_LIB.BASEBOARD_FAB2(SCH_1):M_F_DQ<5>
  137  M_F_DQ<59>     DQ<58>  @BASEBOARD_FAB2_LIB.BASEBOARD_FAB2(SCH_1):M_F_DQ<59>
  282  M_F_DQ<58>     DQ<59>  @BASEBOARD_FAB2_LIB.BASEBOARD_FAB2(SCH_1):M_F_DQ<58>
  130  M_F_DQ<57>     DQ<56>  @BASEBOARD_FAB2_LIB.BASEBOARD_FAB2(SCH_1):M_F_DQ<57>
  275  M_F_DQ<56>     DQ<57>  @BASEBOARD_FAB2_LIB.BASEBOARD_FAB2(SCH_1):M_F_DQ<56>
  124  M_F_DQ<55>     DQ<54>  @BASEBOARD_FAB2_LIB.BASEBOARD_FAB2(SCH_1):M_F_DQ<55>
  269  M_F_DQ<54>     DQ<55>  @BASEBOARD_FAB2_LIB.BASEBOARD_FAB2(SCH_1):M_F_DQ<54>
  117  M_F_DQ<53>     DQ<52>  @BASEBOARD_FAB2_LIB.BASEBOARD_FAB2(SCH_1):M_F_DQ<53>
  262  M_F_DQ<52>     DQ<53>  @BASEBOARD_FAB2_LIB.BASEBOARD_FAB2(SCH_1):M_F_DQ<52>
  126  M_F_DQ<51>     DQ<50>  @BASEBOARD_FAB2_LIB.BASEBOARD_FAB2(SCH_1):M_F_DQ<51>
  271  M_F_DQ<50>     DQ<51>  @BASEBOARD_FAB2_LIB.BASEBOARD_FAB2(SCH_1):M_F_DQ<50>
  148  M_F_DQ<4>      DQ<5>  @BASEBOARD_FAB2_LIB.BASEBOARD_FAB2(SCH_1):M_F_DQ<4>
  119  M_F_DQ<49>     DQ<48>  @BASEBOARD_FAB2_LIB.BASEBOARD_FAB2(SCH_1):M_F_DQ<49>
  264  M_F_DQ<48>     DQ<49>  @BASEBOARD_FAB2_LIB.BASEBOARD_FAB2(SCH_1):M_F_DQ<48>
  113  M_F_DQ<47>     DQ<46>  @BASEBOARD_FAB2_LIB.BASEBOARD_FAB2(SCH_1):M_F_DQ<47>
  258  M_F_DQ<46>     DQ<47>  @BASEBOARD_FAB2_LIB.BASEBOARD_FAB2(SCH_1):M_F_DQ<46>
  106  M_F_DQ<45>     DQ<44>  @BASEBOARD_FAB2_LIB.BASEBOARD_FAB2(SCH_1):M_F_DQ<45>
  251  M_F_DQ<44>     DQ<45>  @BASEBOARD_FAB2_LIB.BASEBOARD_FAB2(SCH_1):M_F_DQ<44>
  115  M_F_DQ<43>     DQ<42>  @BASEBOARD_FAB2_LIB.BASEBOARD_FAB2(SCH_1):M_F_DQ<43>
  260  M_F_DQ<42>     DQ<43>  @BASEBOARD_FAB2_LIB.BASEBOARD_FAB2(SCH_1):M_F_DQ<42>
  108  M_F_DQ<41>     DQ<40>  @BASEBOARD_FAB2_LIB.BASEBOARD_FAB2(SCH_1):M_F_DQ<41>
  253  M_F_DQ<40>     DQ<41>  @BASEBOARD_FAB2_LIB.BASEBOARD_FAB2(SCH_1):M_F_DQ<40>
   12  M_F_DQ<3>      DQ<2>  @BASEBOARD_FAB2_LIB.BASEBOARD_FAB2(SCH_1):M_F_DQ<3>
  102  M_F_DQ<39>     DQ<38>  @BASEBOARD_FAB2_LIB.BASEBOARD_FAB2(SCH_1):M_F_DQ<39>
  247  M_F_DQ<38>     DQ<39>  @BASEBOARD_FAB2_LIB.BASEBOARD_FAB2(SCH_1):M_F_DQ<38>
   95  M_F_DQ<37>     DQ<36>  @BASEBOARD_FAB2_LIB.BASEBOARD_FAB2(SCH_1):M_F_DQ<37>
  240  M_F_DQ<36>     DQ<37>  @BASEBOARD_FAB2_LIB.BASEBOARD_FAB2(SCH_1):M_F_DQ<36>
  104  M_F_DQ<35>     DQ<34>  @BASEBOARD_FAB2_LIB.BASEBOARD_FAB2(SCH_1):M_F_DQ<35>
  249  M_F_DQ<34>     DQ<35>  @BASEBOARD_FAB2_LIB.BASEBOARD_FAB2(SCH_1):M_F_DQ<34>
   97  M_F_DQ<33>     DQ<32>  @BASEBOARD_FAB2_LIB.BASEBOARD_FAB2(SCH_1):M_F_DQ<33>
  242  M_F_DQ<32>     DQ<33>  @BASEBOARD_FAB2_LIB.BASEBOARD_FAB2(SCH_1):M_F_DQ<32>
   43  M_F_DQ<31>     DQ<30>  @BASEBOARD_FAB2_LIB.BASEBOARD_FAB2(SCH_1):M_F_DQ<31>
  188  M_F_DQ<30>     DQ<31>  @BASEBOARD_FAB2_LIB.BASEBOARD_FAB2(SCH_1):M_F_DQ<30>
  157  M_F_DQ<2>      DQ<3>  @BASEBOARD_FAB2_LIB.BASEBOARD_FAB2(SCH_1):M_F_DQ<2>
   36  M_F_DQ<29>     DQ<28>  @BASEBOARD_FAB2_LIB.BASEBOARD_FAB2(SCH_1):M_F_DQ<29>
  181  M_F_DQ<28>     DQ<29>  @BASEBOARD_FAB2_LIB.BASEBOARD_FAB2(SCH_1):M_F_DQ<28>
   45  M_F_DQ<27>     DQ<26>  @BASEBOARD_FAB2_LIB.BASEBOARD_FAB2(SCH_1):M_F_DQ<27>
  190  M_F_DQ<26>     DQ<27>  @BASEBOARD_FAB2_LIB.BASEBOARD_FAB2(SCH_1):M_F_DQ<26>
   38  M_F_DQ<25>     DQ<24>  @BASEBOARD_FAB2_LIB.BASEBOARD_FAB2(SCH_1):M_F_DQ<25>
  183  M_F_DQ<24>     DQ<25>  @BASEBOARD_FAB2_LIB.BASEBOARD_FAB2(SCH_1):M_F_DQ<24>
   32  M_F_DQ<23>     DQ<22>  @BASEBOARD_FAB2_LIB.BASEBOARD_FAB2(SCH_1):M_F_DQ<23>
  177  M_F_DQ<22>     DQ<23>  @BASEBOARD_FAB2_LIB.BASEBOARD_FAB2(SCH_1):M_F_DQ<22>
   25  M_F_DQ<21>     DQ<20>  @BASEBOARD_FAB2_LIB.BASEBOARD_FAB2(SCH_1):M_F_DQ<21>
  170  M_F_DQ<20>     DQ<21>  @BASEBOARD_FAB2_LIB.BASEBOARD_FAB2(SCH_1):M_F_DQ<20>
    5  M_F_DQ<1>      DQ<0>  @BASEBOARD_FAB2_LIB.BASEBOARD_FAB2(SCH_1):M_F_DQ<1>
   34  M_F_DQ<19>     DQ<18>  @BASEBOARD_FAB2_LIB.BASEBOARD_FAB2(SCH_1):M_F_DQ<19>
  179  M_F_DQ<18>     DQ<19>  @BASEBOARD_FAB2_LIB.BASEBOARD_FAB2(SCH_1):M_F_DQ<18>
   27  M_F_DQ<17>     DQ<16>  @BASEBOARD_FAB2_LIB.BASEBOARD_FAB2(SCH_1):M_F_DQ<17>
  172  M_F_DQ<16>     DQ<17>  @BASEBOARD_FAB2_LIB.BASEBOARD_FAB2(SCH_1):M_F_DQ<16>
   21  M_F_DQ<15>     DQ<14>  @BASEBOARD_FAB2_LIB.BASEBOARD_FAB2(SCH_1):M_F_DQ<15>
  166  M_F_DQ<14>     DQ<15>  @BASEBOARD_FAB2_LIB.BASEBOARD_FAB2(SCH_1):M_F_DQ<14>
   14  M_F_DQ<13>     DQ<12>  @BASEBOARD_FAB2_LIB.BASEBOARD_FAB2(SCH_1):M_F_DQ<13>
  159  M_F_DQ<12>     DQ<13>  @BASEBOARD_FAB2_LIB.BASEBOARD_FAB2(SCH_1):M_F_DQ<12>
   23  M_F_DQ<11>     DQ<10>  @BASEBOARD_FAB2_LIB.BASEBOARD_FAB2(SCH_1):M_F_DQ<11>
  168  M_F_DQ<10>     DQ<11>  @BASEBOARD_FAB2_LIB.BASEBOARD_FAB2(SCH_1):M_F_DQ<10>
  150  M_F_DQ<0>      DQ<1>  @BASEBOARD_FAB2_LIB.BASEBOARD_FAB2(SCH_1):M_F_DQ<0>
  237  M_F_CS_N<3>    S3_N_C<1>  @BASEBOARD_FAB2_LIB.BASEBOARD_FAB2(SCH_1):M_F_CS_N<3>
   93  M_F_CS_N<2>    S2_N_C<0>  @BASEBOARD_FAB2_LIB.BASEBOARD_FAB2(SCH_1):M_F_CS_N<2>
   89  M_F_CS_N<1>     S1_N  @BASEBOARD_FAB2_LIB.BASEBOARD_FAB2(SCH_1):M_F_CS_N<1>
   84  M_F_CS_N<0>     S0_N  @BASEBOARD_FAB2_LIB.BASEBOARD_FAB2(SCH_1):M_F_CS_N<0>
  218  M_F_CLK_DP<1>   CK1P  @BASEBOARD_FAB2_LIB.BASEBOARD_FAB2(SCH_1):M_F_CLK_DP<1>
   74  M_F_CLK_DP<0>   CK0P  @BASEBOARD_FAB2_LIB.BASEBOARD_FAB2(SCH_1):M_F_CLK_DP<0>
  219  M_F_CLK_DN<1>   CK1N  @BASEBOARD_FAB2_LIB.BASEBOARD_FAB2(SCH_1):M_F_CLK_DN<1>
   75  M_F_CLK_DN<0>   CK0N  @BASEBOARD_FAB2_LIB.BASEBOARD_FAB2(SCH_1):M_F_CLK_DN<0>
  203  M_F_CKE<1>     CKE<1>  @BASEBOARD_FAB2_LIB.BASEBOARD_FAB2(SCH_1):M_F_CKE<1>
   60  M_F_CKE<0>     CKE<0>  @BASEBOARD_FAB2_LIB.BASEBOARD_FAB2(SCH_1):M_F_CKE<0>
  235  M_F_C<2>        C<2>  @BASEBOARD_FAB2_LIB.BASEBOARD_FAB2(SCH_1):M_F_C<2>
  207  M_F_BG<1>      BG<1>  @BASEBOARD_FAB2_LIB.BASEBOARD_FAB2(SCH_1):M_F_BG<1>
   63  M_F_BG<0>      BG<0>  @BASEBOARD_FAB2_LIB.BASEBOARD_FAB2(SCH_1):M_F_BG<0>
  224  M_F_BA<1>      BA<1>  @BASEBOARD_FAB2_LIB.BASEBOARD_FAB2(SCH_1):M_F_BA<1>
   81  M_F_BA<0>      BA<0>  @BASEBOARD_FAB2_LIB.BASEBOARD_FAB2(SCH_1):M_F_BA<0>
  208  M_F_ALERT_N    ALERT_N  @BASEBOARD_FAB2_LIB.BASEBOARD_FAB2(SCH_1):M_F_ALERT_N
   62  M_F_ACT_N      ACT_N  @BASEBOARD_FAB2_LIB.BASEBOARD_FAB2(SCH_1):M_F_ACT_N
   58  M_DEF_RST_N    RESET_N  @BASEBOARD_FAB2_LIB.BASEBOARD_FAB2(SCH_1):M_DEF_RST_N
  140  GND            SA<1>  @BASEBOARD_FAB2_LIB.BASEBOARD_FAB2(SCH_1):GND
  139  GND            SA<0>  @BASEBOARD_FAB2_LIB.BASEBOARD_FAB2(SCH_1):GND
   78  FM_DIMM_EVENT_COD_N  EVENT_N  @BASEBOARD_FAB2_LIB.BASEBOARD_FAB2(SCH_1):FM_DIMM_EVENT_COD_N
  230  FM_ADR_COMPLETE_DEF_N  SAVE_N_NC  @BASEBOARD_FAB2_LIB.BASEBOARD_FAB2(SCH_1):FM_ADR_COMPLETE_DEF_N

SCONN288_H44441004_PIP  I167  J4A2   [SCONN288_H44441004_PIP-SCONN,HA]
   77  PVTT_DEF       VTT<1>  @BASEBOARD_FAB2_LIB.BASEBOARD_FAB2(SCH_1):PVTT_DEF
  221  PVTT_DEF       VTT<0>  @BASEBOARD_FAB2_LIB.BASEBOARD_FAB2(SCH_1):PVTT_DEF
  142  PVPP_DEF       VPP<4>  @BASEBOARD_FAB2_LIB.BASEBOARD_FAB2(SCH_1):PVPP_DEF
  143  PVPP_DEF       VPP<3>  @BASEBOARD_FAB2_LIB.BASEBOARD_FAB2(SCH_1):PVPP_DEF
  288  PVPP_DEF       VPP<2>  @BASEBOARD_FAB2_LIB.BASEBOARD_FAB2(SCH_1):PVPP_DEF
  286  PVPP_DEF       VPP<1>  @BASEBOARD_FAB2_LIB.BASEBOARD_FAB2(SCH_1):PVPP_DEF
  287  PVPP_DEF       VPP<0>  @BASEBOARD_FAB2_LIB.BASEBOARD_FAB2(SCH_1):PVPP_DEF
   59  PVDDQ_DEF      VDD<25>  @BASEBOARD_FAB2_LIB.BASEBOARD_FAB2(SCH_1):PVDDQ_DEF
   61  PVDDQ_DEF      VDD<24>  @BASEBOARD_FAB2_LIB.BASEBOARD_FAB2(SCH_1):PVDDQ_DEF
   64  PVDDQ_DEF      VDD<23>  @BASEBOARD_FAB2_LIB.BASEBOARD_FAB2(SCH_1):PVDDQ_DEF
   67  PVDDQ_DEF      VDD<22>  @BASEBOARD_FAB2_LIB.BASEBOARD_FAB2(SCH_1):PVDDQ_DEF
   70  PVDDQ_DEF      VDD<21>  @BASEBOARD_FAB2_LIB.BASEBOARD_FAB2(SCH_1):PVDDQ_DEF
   73  PVDDQ_DEF      VDD<20>  @BASEBOARD_FAB2_LIB.BASEBOARD_FAB2(SCH_1):PVDDQ_DEF
   76  PVDDQ_DEF      VDD<19>  @BASEBOARD_FAB2_LIB.BASEBOARD_FAB2(SCH_1):PVDDQ_DEF
   80  PVDDQ_DEF      VDD<18>  @BASEBOARD_FAB2_LIB.BASEBOARD_FAB2(SCH_1):PVDDQ_DEF
   83  PVDDQ_DEF      VDD<17>  @BASEBOARD_FAB2_LIB.BASEBOARD_FAB2(SCH_1):PVDDQ_DEF
   85  PVDDQ_DEF      VDD<16>  @BASEBOARD_FAB2_LIB.BASEBOARD_FAB2(SCH_1):PVDDQ_DEF
   88  PVDDQ_DEF      VDD<15>  @BASEBOARD_FAB2_LIB.BASEBOARD_FAB2(SCH_1):PVDDQ_DEF
   90  PVDDQ_DEF      VDD<14>  @BASEBOARD_FAB2_LIB.BASEBOARD_FAB2(SCH_1):PVDDQ_DEF
   92  PVDDQ_DEF      VDD<13>  @BASEBOARD_FAB2_LIB.BASEBOARD_FAB2(SCH_1):PVDDQ_DEF
  204  PVDDQ_DEF      VDD<12>  @BASEBOARD_FAB2_LIB.BASEBOARD_FAB2(SCH_1):PVDDQ_DEF
  206  PVDDQ_DEF      VDD<11>  @BASEBOARD_FAB2_LIB.BASEBOARD_FAB2(SCH_1):PVDDQ_DEF
  209  PVDDQ_DEF      VDD<10>  @BASEBOARD_FAB2_LIB.BASEBOARD_FAB2(SCH_1):PVDDQ_DEF
  212  PVDDQ_DEF      VDD<9>  @BASEBOARD_FAB2_LIB.BASEBOARD_FAB2(SCH_1):PVDDQ_DEF
  215  PVDDQ_DEF      VDD<8>  @BASEBOARD_FAB2_LIB.BASEBOARD_FAB2(SCH_1):PVDDQ_DEF
  217  PVDDQ_DEF      VDD<7>  @BASEBOARD_FAB2_LIB.BASEBOARD_FAB2(SCH_1):PVDDQ_DEF
  220  PVDDQ_DEF      VDD<6>  @BASEBOARD_FAB2_LIB.BASEBOARD_FAB2(SCH_1):PVDDQ_DEF
  223  PVDDQ_DEF      VDD<5>  @BASEBOARD_FAB2_LIB.BASEBOARD_FAB2(SCH_1):PVDDQ_DEF
  226  PVDDQ_DEF      VDD<4>  @BASEBOARD_FAB2_LIB.BASEBOARD_FAB2(SCH_1):PVDDQ_DEF
  229  PVDDQ_DEF      VDD<3>  @BASEBOARD_FAB2_LIB.BASEBOARD_FAB2(SCH_1):PVDDQ_DEF
  231  PVDDQ_DEF      VDD<2>  @BASEBOARD_FAB2_LIB.BASEBOARD_FAB2(SCH_1):PVDDQ_DEF
  233  PVDDQ_DEF      VDD<1>  @BASEBOARD_FAB2_LIB.BASEBOARD_FAB2(SCH_1):PVDDQ_DEF
  236  PVDDQ_DEF      VDD<0>  @BASEBOARD_FAB2_LIB.BASEBOARD_FAB2(SCH_1):PVDDQ_DEF
    1  P12V_NVDIMM_DEF  12V<1>  @BASEBOARD_FAB2_LIB.BASEBOARD_FAB2(SCH_1):P12V_NVDIMM_DEF
  145  P12V_NVDIMM_DEF  12V<0>  @BASEBOARD_FAB2_LIB.BASEBOARD_FAB2(SCH_1):P12V_NVDIMM_DEF

SCONN288_H44441004_PIP  I43  J4A2   [SCONN288_H44441004_PIP-SCONN,HA]
    2  GND            VSS<93>  @BASEBOARD_FAB2_LIB.BASEBOARD_FAB2(SCH_1):GND
    4  GND            VSS<92>  @BASEBOARD_FAB2_LIB.BASEBOARD_FAB2(SCH_1):GND
    6  GND            VSS<91>  @BASEBOARD_FAB2_LIB.BASEBOARD_FAB2(SCH_1):GND
    9  GND            VSS<90>  @BASEBOARD_FAB2_LIB.BASEBOARD_FAB2(SCH_1):GND
   11  GND            VSS<89>  @BASEBOARD_FAB2_LIB.BASEBOARD_FAB2(SCH_1):GND
   13  GND            VSS<88>  @BASEBOARD_FAB2_LIB.BASEBOARD_FAB2(SCH_1):GND
   15  GND            VSS<87>  @BASEBOARD_FAB2_LIB.BASEBOARD_FAB2(SCH_1):GND
   17  GND            VSS<86>  @BASEBOARD_FAB2_LIB.BASEBOARD_FAB2(SCH_1):GND
   20  GND            VSS<85>  @BASEBOARD_FAB2_LIB.BASEBOARD_FAB2(SCH_1):GND
   22  GND            VSS<84>  @BASEBOARD_FAB2_LIB.BASEBOARD_FAB2(SCH_1):GND
   24  GND            VSS<83>  @BASEBOARD_FAB2_LIB.BASEBOARD_FAB2(SCH_1):GND
   26  GND            VSS<82>  @BASEBOARD_FAB2_LIB.BASEBOARD_FAB2(SCH_1):GND
   28  GND            VSS<81>  @BASEBOARD_FAB2_LIB.BASEBOARD_FAB2(SCH_1):GND
   31  GND            VSS<80>  @BASEBOARD_FAB2_LIB.BASEBOARD_FAB2(SCH_1):GND
   33  GND            VSS<79>  @BASEBOARD_FAB2_LIB.BASEBOARD_FAB2(SCH_1):GND
   35  GND            VSS<78>  @BASEBOARD_FAB2_LIB.BASEBOARD_FAB2(SCH_1):GND
   37  GND            VSS<77>  @BASEBOARD_FAB2_LIB.BASEBOARD_FAB2(SCH_1):GND
   39  GND            VSS<76>  @BASEBOARD_FAB2_LIB.BASEBOARD_FAB2(SCH_1):GND
   42  GND            VSS<75>  @BASEBOARD_FAB2_LIB.BASEBOARD_FAB2(SCH_1):GND
   44  GND            VSS<74>  @BASEBOARD_FAB2_LIB.BASEBOARD_FAB2(SCH_1):GND
   46  GND            VSS<73>  @BASEBOARD_FAB2_LIB.BASEBOARD_FAB2(SCH_1):GND
   48  GND            VSS<72>  @BASEBOARD_FAB2_LIB.BASEBOARD_FAB2(SCH_1):GND
   50  GND            VSS<71>  @BASEBOARD_FAB2_LIB.BASEBOARD_FAB2(SCH_1):GND
   53  GND            VSS<70>  @BASEBOARD_FAB2_LIB.BASEBOARD_FAB2(SCH_1):GND
   55  GND            VSS<69>  @BASEBOARD_FAB2_LIB.BASEBOARD_FAB2(SCH_1):GND
   57  GND            VSS<68>  @BASEBOARD_FAB2_LIB.BASEBOARD_FAB2(SCH_1):GND
   94  GND            VSS<67>  @BASEBOARD_FAB2_LIB.BASEBOARD_FAB2(SCH_1):GND
   96  GND            VSS<66>  @BASEBOARD_FAB2_LIB.BASEBOARD_FAB2(SCH_1):GND
   98  GND            VSS<65>  @BASEBOARD_FAB2_LIB.BASEBOARD_FAB2(SCH_1):GND
  101  GND            VSS<64>  @BASEBOARD_FAB2_LIB.BASEBOARD_FAB2(SCH_1):GND
  103  GND            VSS<63>  @BASEBOARD_FAB2_LIB.BASEBOARD_FAB2(SCH_1):GND
  105  GND            VSS<62>  @BASEBOARD_FAB2_LIB.BASEBOARD_FAB2(SCH_1):GND
  107  GND            VSS<61>  @BASEBOARD_FAB2_LIB.BASEBOARD_FAB2(SCH_1):GND
  109  GND            VSS<60>  @BASEBOARD_FAB2_LIB.BASEBOARD_FAB2(SCH_1):GND
  112  GND            VSS<59>  @BASEBOARD_FAB2_LIB.BASEBOARD_FAB2(SCH_1):GND
  114  GND            VSS<58>  @BASEBOARD_FAB2_LIB.BASEBOARD_FAB2(SCH_1):GND
  116  GND            VSS<57>  @BASEBOARD_FAB2_LIB.BASEBOARD_FAB2(SCH_1):GND
  118  GND            VSS<56>  @BASEBOARD_FAB2_LIB.BASEBOARD_FAB2(SCH_1):GND
  120  GND            VSS<55>  @BASEBOARD_FAB2_LIB.BASEBOARD_FAB2(SCH_1):GND
  123  GND            VSS<54>  @BASEBOARD_FAB2_LIB.BASEBOARD_FAB2(SCH_1):GND
  125  GND            VSS<53>  @BASEBOARD_FAB2_LIB.BASEBOARD_FAB2(SCH_1):GND
  127  GND            VSS<52>  @BASEBOARD_FAB2_LIB.BASEBOARD_FAB2(SCH_1):GND
  129  GND            VSS<51>  @BASEBOARD_FAB2_LIB.BASEBOARD_FAB2(SCH_1):GND
  131  GND            VSS<50>  @BASEBOARD_FAB2_LIB.BASEBOARD_FAB2(SCH_1):GND
  134  GND            VSS<49>  @BASEBOARD_FAB2_LIB.BASEBOARD_FAB2(SCH_1):GND
  136  GND            VSS<48>  @BASEBOARD_FAB2_LIB.BASEBOARD_FAB2(SCH_1):GND
  138  GND            VSS<47>  @BASEBOARD_FAB2_LIB.BASEBOARD_FAB2(SCH_1):GND
  147  GND            VSS<46>  @BASEBOARD_FAB2_LIB.BASEBOARD_FAB2(SCH_1):GND
  149  GND            VSS<45>  @BASEBOARD_FAB2_LIB.BASEBOARD_FAB2(SCH_1):GND
  151  GND            VSS<44>  @BASEBOARD_FAB2_LIB.BASEBOARD_FAB2(SCH_1):GND
  154  GND            VSS<43>  @BASEBOARD_FAB2_LIB.BASEBOARD_FAB2(SCH_1):GND
  156  GND            VSS<42>  @BASEBOARD_FAB2_LIB.BASEBOARD_FAB2(SCH_1):GND
  158  GND            VSS<41>  @BASEBOARD_FAB2_LIB.BASEBOARD_FAB2(SCH_1):GND
  160  GND            VSS<40>  @BASEBOARD_FAB2_LIB.BASEBOARD_FAB2(SCH_1):GND
  162  GND            VSS<39>  @BASEBOARD_FAB2_LIB.BASEBOARD_FAB2(SCH_1):GND
  165  GND            VSS<38>  @BASEBOARD_FAB2_LIB.BASEBOARD_FAB2(SCH_1):GND
  167  GND            VSS<37>  @BASEBOARD_FAB2_LIB.BASEBOARD_FAB2(SCH_1):GND
  169  GND            VSS<36>  @BASEBOARD_FAB2_LIB.BASEBOARD_FAB2(SCH_1):GND
  171  GND            VSS<35>  @BASEBOARD_FAB2_LIB.BASEBOARD_FAB2(SCH_1):GND
  173  GND            VSS<34>  @BASEBOARD_FAB2_LIB.BASEBOARD_FAB2(SCH_1):GND
  176  GND            VSS<33>  @BASEBOARD_FAB2_LIB.BASEBOARD_FAB2(SCH_1):GND
  178  GND            VSS<32>  @BASEBOARD_FAB2_LIB.BASEBOARD_FAB2(SCH_1):GND
  180  GND            VSS<31>  @BASEBOARD_FAB2_LIB.BASEBOARD_FAB2(SCH_1):GND
  182  GND            VSS<30>  @BASEBOARD_FAB2_LIB.BASEBOARD_FAB2(SCH_1):GND
  184  GND            VSS<29>  @BASEBOARD_FAB2_LIB.BASEBOARD_FAB2(SCH_1):GND
  187  GND            VSS<28>  @BASEBOARD_FAB2_LIB.BASEBOARD_FAB2(SCH_1):GND
  189  GND            VSS<27>  @BASEBOARD_FAB2_LIB.BASEBOARD_FAB2(SCH_1):GND
  191  GND            VSS<26>  @BASEBOARD_FAB2_LIB.BASEBOARD_FAB2(SCH_1):GND
  193  GND            VSS<25>  @BASEBOARD_FAB2_LIB.BASEBOARD_FAB2(SCH_1):GND
  195  GND            VSS<24>  @BASEBOARD_FAB2_LIB.BASEBOARD_FAB2(SCH_1):GND
  198  GND            VSS<23>  @BASEBOARD_FAB2_LIB.BASEBOARD_FAB2(SCH_1):GND
  200  GND            VSS<22>  @BASEBOARD_FAB2_LIB.BASEBOARD_FAB2(SCH_1):GND
  202  GND            VSS<21>  @BASEBOARD_FAB2_LIB.BASEBOARD_FAB2(SCH_1):GND
  239  GND            VSS<20>  @BASEBOARD_FAB2_LIB.BASEBOARD_FAB2(SCH_1):GND
  241  GND            VSS<19>  @BASEBOARD_FAB2_LIB.BASEBOARD_FAB2(SCH_1):GND
  243  GND            VSS<18>  @BASEBOARD_FAB2_LIB.BASEBOARD_FAB2(SCH_1):GND
  246  GND            VSS<17>  @BASEBOARD_FAB2_LIB.BASEBOARD_FAB2(SCH_1):GND
  248  GND            VSS<16>  @BASEBOARD_FAB2_LIB.BASEBOARD_FAB2(SCH_1):GND
  250  GND            VSS<15>  @BASEBOARD_FAB2_LIB.BASEBOARD_FAB2(SCH_1):GND
  252  GND            VSS<14>  @BASEBOARD_FAB2_LIB.BASEBOARD_FAB2(SCH_1):GND
  254  GND            VSS<13>  @BASEBOARD_FAB2_LIB.BASEBOARD_FAB2(SCH_1):GND
  257  GND            VSS<12>  @BASEBOARD_FAB2_LIB.BASEBOARD_FAB2(SCH_1):GND
  259  GND            VSS<11>  @BASEBOARD_FAB2_LIB.BASEBOARD_FAB2(SCH_1):GND
  261  GND            VSS<10>  @BASEBOARD_FAB2_LIB.BASEBOARD_FAB2(SCH_1):GND
  263  GND            VSS<9>  @BASEBOARD_FAB2_LIB.BASEBOARD_FAB2(SCH_1):GND
  265  GND            VSS<8>  @BASEBOARD_FAB2_LIB.BASEBOARD_FAB2(SCH_1):GND
  268  GND            VSS<7>  @BASEBOARD_FAB2_LIB.BASEBOARD_FAB2(SCH_1):GND
  270  GND            VSS<6>  @BASEBOARD_FAB2_LIB.BASEBOARD_FAB2(SCH_1):GND
  272  GND            VSS<5>  @BASEBOARD_FAB2_LIB.BASEBOARD_FAB2(SCH_1):GND
  274  GND            VSS<4>  @BASEBOARD_FAB2_LIB.BASEBOARD_FAB2(SCH_1):GND
  276  GND            VSS<3>  @BASEBOARD_FAB2_LIB.BASEBOARD_FAB2(SCH_1):GND
  279  GND            VSS<2>  @BASEBOARD_FAB2_LIB.BASEBOARD_FAB2(SCH_1):GND
  281  GND            VSS<1>  @BASEBOARD_FAB2_LIB.BASEBOARD_FAB2(SCH_1):GND
  283  GND            VSS<0>  @BASEBOARD_FAB2_LIB.BASEBOARD_FAB2(SCH_1):GND

SCONN288_H44441004_PIP  I66  J4A2   [SCONN288_H44441004_PIP-SCONN,HA]
    7  M_E_DQS_DP<9>  DQS9P  @BASEBOARD_FAB2_LIB.BASEBOARD_FAB2(SCH_1):M_E_DQS_DP<9>
  197  M_E_DQS_DP<8>  DQS8P  @BASEBOARD_FAB2_LIB.BASEBOARD_FAB2(SCH_1):M_E_DQS_DP<8>
  278  M_E_DQS_DP<7>  DQS7P  @BASEBOARD_FAB2_LIB.BASEBOARD_FAB2(SCH_1):M_E_DQS_DP<7>
  267  M_E_DQS_DP<6>  DQS6P  @BASEBOARD_FAB2_LIB.BASEBOARD_FAB2(SCH_1):M_E_DQS_DP<6>
  256  M_E_DQS_DP<5>  DQS5P  @BASEBOARD_FAB2_LIB.BASEBOARD_FAB2(SCH_1):M_E_DQS_DP<5>
  245  M_E_DQS_DP<4>  DQS4P  @BASEBOARD_FAB2_LIB.BASEBOARD_FAB2(SCH_1):M_E_DQS_DP<4>
  186  M_E_DQS_DP<3>  DQS3P  @BASEBOARD_FAB2_LIB.BASEBOARD_FAB2(SCH_1):M_E_DQS_DP<3>
  175  M_E_DQS_DP<2>  DQS2P  @BASEBOARD_FAB2_LIB.BASEBOARD_FAB2(SCH_1):M_E_DQS_DP<2>
  164  M_E_DQS_DP<1>  DQS1P  @BASEBOARD_FAB2_LIB.BASEBOARD_FAB2(SCH_1):M_E_DQS_DP<1>
   51  M_E_DQS_DP<17>  DQS17P  @BASEBOARD_FAB2_LIB.BASEBOARD_FAB2(SCH_1):M_E_DQS_DP<17>
  132  M_E_DQS_DP<16>  DQS16P  @BASEBOARD_FAB2_LIB.BASEBOARD_FAB2(SCH_1):M_E_DQS_DP<16>
  121  M_E_DQS_DP<15>  DQS15P  @BASEBOARD_FAB2_LIB.BASEBOARD_FAB2(SCH_1):M_E_DQS_DP<15>
  110  M_E_DQS_DP<14>  DQS14P  @BASEBOARD_FAB2_LIB.BASEBOARD_FAB2(SCH_1):M_E_DQS_DP<14>
   99  M_E_DQS_DP<13>  DQS13P  @BASEBOARD_FAB2_LIB.BASEBOARD_FAB2(SCH_1):M_E_DQS_DP<13>
   40  M_E_DQS_DP<12>  DQS12P  @BASEBOARD_FAB2_LIB.BASEBOARD_FAB2(SCH_1):M_E_DQS_DP<12>
   29  M_E_DQS_DP<11>  DQS11P  @BASEBOARD_FAB2_LIB.BASEBOARD_FAB2(SCH_1):M_E_DQS_DP<11>
   18  M_E_DQS_DP<10>  DQS10P  @BASEBOARD_FAB2_LIB.BASEBOARD_FAB2(SCH_1):M_E_DQS_DP<10>
  153  M_E_DQS_DP<0>  DQS0P  @BASEBOARD_FAB2_LIB.BASEBOARD_FAB2(SCH_1):M_E_DQS_DP<0>
    8  M_E_DQS_DN<9>  DQS9N  @BASEBOARD_FAB2_LIB.BASEBOARD_FAB2(SCH_1):M_E_DQS_DN<9>
  196  M_E_DQS_DN<8>  DQS8N  @BASEBOARD_FAB2_LIB.BASEBOARD_FAB2(SCH_1):M_E_DQS_DN<8>
  277  M_E_DQS_DN<7>  DQS7N  @BASEBOARD_FAB2_LIB.BASEBOARD_FAB2(SCH_1):M_E_DQS_DN<7>
  266  M_E_DQS_DN<6>  DQS6N  @BASEBOARD_FAB2_LIB.BASEBOARD_FAB2(SCH_1):M_E_DQS_DN<6>
  255  M_E_DQS_DN<5>  DQS5N  @BASEBOARD_FAB2_LIB.BASEBOARD_FAB2(SCH_1):M_E_DQS_DN<5>
  244  M_E_DQS_DN<4>  DQS4N  @BASEBOARD_FAB2_LIB.BASEBOARD_FAB2(SCH_1):M_E_DQS_DN<4>
  185  M_E_DQS_DN<3>  DQS3N  @BASEBOARD_FAB2_LIB.BASEBOARD_FAB2(SCH_1):M_E_DQS_DN<3>
  174  M_E_DQS_DN<2>  DQS2N  @BASEBOARD_FAB2_LIB.BASEBOARD_FAB2(SCH_1):M_E_DQS_DN<2>
  163  M_E_DQS_DN<1>  DQS1N  @BASEBOARD_FAB2_LIB.BASEBOARD_FAB2(SCH_1):M_E_DQS_DN<1>
   52  M_E_DQS_DN<17>  DQS17N  @BASEBOARD_FAB2_LIB.BASEBOARD_FAB2(SCH_1):M_E_DQS_DN<17>
  133  M_E_DQS_DN<16>  DQS16N  @BASEBOARD_FAB2_LIB.BASEBOARD_FAB2(SCH_1):M_E_DQS_DN<16>
  122  M_E_DQS_DN<15>  DQS15N  @BASEBOARD_FAB2_LIB.BASEBOARD_FAB2(SCH_1):M_E_DQS_DN<15>
  111  M_E_DQS_DN<14>  DQS14N  @BASEBOARD_FAB2_LIB.BASEBOARD_FAB2(SCH_1):M_E_DQS_DN<14>
  100  M_E_DQS_DN<13>  DQS13N  @BASEBOARD_FAB2_LIB.BASEBOARD_FAB2(SCH_1):M_E_DQS_DN<13>
   41  M_E_DQS_DN<12>  DQS12N  @BASEBOARD_FAB2_LIB.BASEBOARD_FAB2(SCH_1):M_E_DQS_DN<12>
   30  M_E_DQS_DN<11>  DQS11N  @BASEBOARD_FAB2_LIB.BASEBOARD_FAB2(SCH_1):M_E_DQS_DN<11>
   19  M_E_DQS_DN<10>  DQS10N  @BASEBOARD_FAB2_LIB.BASEBOARD_FAB2(SCH_1):M_E_DQS_DN<10>
  152  M_E_DQS_DN<0>  DQS0N  @BASEBOARD_FAB2_LIB.BASEBOARD_FAB2(SCH_1):M_E_DQS_DN<0>

SCONN288_H44441004_PIP  I111  J4A2   [SCONN288_H44441004_PIP-SCONN,HA]
  144  TP_CH_E_DIMM_E0_RFU_2  RFU<2>  @BASEBOARD_FAB2_LIB.BASEBOARD_FAB2(SCH_1):TP_CH_E_DIMM_E0_RFU_2
  227  TP_CH_E_DIMM_E0_RFU_1  RFU<1>  @BASEBOARD_FAB2_LIB.BASEBOARD_FAB2(SCH_1):TP_CH_E_DIMM_E0_RFU_1
  205  TP_CH_E_DIMM_E0_RFU_0  RFU<0>  @BASEBOARD_FAB2_LIB.BASEBOARD_FAB2(SCH_1):TP_CH_E_DIMM_E0_RFU_0
  285  SMB_DDR_DEF_VPP_SDA    SDA  @BASEBOARD_FAB2_LIB.BASEBOARD_FAB2(SCH_1):SMB_DDR_DEF_VPP_SDA
  141  SMB_DDR_DEF_VPP_SCL    SCL  @BASEBOARD_FAB2_LIB.BASEBOARD_FAB2(SCH_1):SMB_DDR_DEF_VPP_SCL
  284  PVPP_DEF       VDDSPD  @BASEBOARD_FAB2_LIB.BASEBOARD_FAB2(SCH_1):PVPP_DEF
  140  PVPP_DEF       SA<1>  @BASEBOARD_FAB2_LIB.BASEBOARD_FAB2(SCH_1):PVPP_DEF
  146  M_E_VREF       VREFCA  @BASEBOARD_FAB2_LIB.BASEBOARD_FAB2(SCH_1):M_E_VREF
  222  M_E_PAR          PAR  @BASEBOARD_FAB2_LIB.BASEBOARD_FAB2(SCH_1):M_E_PAR
   91  M_E_ODT<1>     ODT<1>  @BASEBOARD_FAB2_LIB.BASEBOARD_FAB2(SCH_1):M_E_ODT<1>
   87  M_E_ODT<0>     ODT<0>  @BASEBOARD_FAB2_LIB.BASEBOARD_FAB2(SCH_1):M_E_ODT<0>
   66  M_E_MA<9>         A9  @BASEBOARD_FAB2_LIB.BASEBOARD_FAB2(SCH_1):M_E_MA<9>
   68  M_E_MA<8>         A8  @BASEBOARD_FAB2_LIB.BASEBOARD_FAB2(SCH_1):M_E_MA<8>
  211  M_E_MA<7>         A7  @BASEBOARD_FAB2_LIB.BASEBOARD_FAB2(SCH_1):M_E_MA<7>
   69  M_E_MA<6>         A6  @BASEBOARD_FAB2_LIB.BASEBOARD_FAB2(SCH_1):M_E_MA<6>
  213  M_E_MA<5>         A5  @BASEBOARD_FAB2_LIB.BASEBOARD_FAB2(SCH_1):M_E_MA<5>
  214  M_E_MA<4>         A4  @BASEBOARD_FAB2_LIB.BASEBOARD_FAB2(SCH_1):M_E_MA<4>
   71  M_E_MA<3>         A3  @BASEBOARD_FAB2_LIB.BASEBOARD_FAB2(SCH_1):M_E_MA<3>
  216  M_E_MA<2>         A2  @BASEBOARD_FAB2_LIB.BASEBOARD_FAB2(SCH_1):M_E_MA<2>
   72  M_E_MA<1>         A1  @BASEBOARD_FAB2_LIB.BASEBOARD_FAB2(SCH_1):M_E_MA<1>
  234  M_E_MA<17>       A17  @BASEBOARD_FAB2_LIB.BASEBOARD_FAB2(SCH_1):M_E_MA<17>
   82  M_E_MA<16>     A16_RAS_N  @BASEBOARD_FAB2_LIB.BASEBOARD_FAB2(SCH_1):M_E_MA<16>
   86  M_E_MA<15>     A15_CAS_N  @BASEBOARD_FAB2_LIB.BASEBOARD_FAB2(SCH_1):M_E_MA<15>
  228  M_E_MA<14>     A14_WE_N  @BASEBOARD_FAB2_LIB.BASEBOARD_FAB2(SCH_1):M_E_MA<14>
  232  M_E_MA<13>       A13  @BASEBOARD_FAB2_LIB.BASEBOARD_FAB2(SCH_1):M_E_MA<13>
   65  M_E_MA<12>       A12  @BASEBOARD_FAB2_LIB.BASEBOARD_FAB2(SCH_1):M_E_MA<12>
  210  M_E_MA<11>       A11  @BASEBOARD_FAB2_LIB.BASEBOARD_FAB2(SCH_1):M_E_MA<11>
  225  M_E_MA<10>       A10  @BASEBOARD_FAB2_LIB.BASEBOARD_FAB2(SCH_1):M_E_MA<10>
   79  M_E_MA<0>         A0  @BASEBOARD_FAB2_LIB.BASEBOARD_FAB2(SCH_1):M_E_MA<0>
   54  M_E_ECC<7>     CB<6>  @BASEBOARD_FAB2_LIB.BASEBOARD_FAB2(SCH_1):M_E_ECC<7>
  199  M_E_ECC<6>     CB<7>  @BASEBOARD_FAB2_LIB.BASEBOARD_FAB2(SCH_1):M_E_ECC<6>
   47  M_E_ECC<5>     CB<4>  @BASEBOARD_FAB2_LIB.BASEBOARD_FAB2(SCH_1):M_E_ECC<5>
  192  M_E_ECC<4>     CB<5>  @BASEBOARD_FAB2_LIB.BASEBOARD_FAB2(SCH_1):M_E_ECC<4>
   56  M_E_ECC<3>     CB<2>  @BASEBOARD_FAB2_LIB.BASEBOARD_FAB2(SCH_1):M_E_ECC<3>
  201  M_E_ECC<2>     CB<3>  @BASEBOARD_FAB2_LIB.BASEBOARD_FAB2(SCH_1):M_E_ECC<2>
   49  M_E_ECC<1>     CB<0>  @BASEBOARD_FAB2_LIB.BASEBOARD_FAB2(SCH_1):M_E_ECC<1>
  194  M_E_ECC<0>     CB<1>  @BASEBOARD_FAB2_LIB.BASEBOARD_FAB2(SCH_1):M_E_ECC<0>
   16  M_E_DQ<9>      DQ<8>  @BASEBOARD_FAB2_LIB.BASEBOARD_FAB2(SCH_1):M_E_DQ<9>
  161  M_E_DQ<8>      DQ<9>  @BASEBOARD_FAB2_LIB.BASEBOARD_FAB2(SCH_1):M_E_DQ<8>
   10  M_E_DQ<7>      DQ<6>  @BASEBOARD_FAB2_LIB.BASEBOARD_FAB2(SCH_1):M_E_DQ<7>
  155  M_E_DQ<6>      DQ<7>  @BASEBOARD_FAB2_LIB.BASEBOARD_FAB2(SCH_1):M_E_DQ<6>
  135  M_E_DQ<63>     DQ<62>  @BASEBOARD_FAB2_LIB.BASEBOARD_FAB2(SCH_1):M_E_DQ<63>
  280  M_E_DQ<62>     DQ<63>  @BASEBOARD_FAB2_LIB.BASEBOARD_FAB2(SCH_1):M_E_DQ<62>
  128  M_E_DQ<61>     DQ<60>  @BASEBOARD_FAB2_LIB.BASEBOARD_FAB2(SCH_1):M_E_DQ<61>
  273  M_E_DQ<60>     DQ<61>  @BASEBOARD_FAB2_LIB.BASEBOARD_FAB2(SCH_1):M_E_DQ<60>
    3  M_E_DQ<5>      DQ<4>  @BASEBOARD_FAB2_LIB.BASEBOARD_FAB2(SCH_1):M_E_DQ<5>
  137  M_E_DQ<59>     DQ<58>  @BASEBOARD_FAB2_LIB.BASEBOARD_FAB2(SCH_1):M_E_DQ<59>
  282  M_E_DQ<58>     DQ<59>  @BASEBOARD_FAB2_LIB.BASEBOARD_FAB2(SCH_1):M_E_DQ<58>
  130  M_E_DQ<57>     DQ<56>  @BASEBOARD_FAB2_LIB.BASEBOARD_FAB2(SCH_1):M_E_DQ<57>
  275  M_E_DQ<56>     DQ<57>  @BASEBOARD_FAB2_LIB.BASEBOARD_FAB2(SCH_1):M_E_DQ<56>
  124  M_E_DQ<55>     DQ<54>  @BASEBOARD_FAB2_LIB.BASEBOARD_FAB2(SCH_1):M_E_DQ<55>
  269  M_E_DQ<54>     DQ<55>  @BASEBOARD_FAB2_LIB.BASEBOARD_FAB2(SCH_1):M_E_DQ<54>
  117  M_E_DQ<53>     DQ<52>  @BASEBOARD_FAB2_LIB.BASEBOARD_FAB2(SCH_1):M_E_DQ<53>
  262  M_E_DQ<52>     DQ<53>  @BASEBOARD_FAB2_LIB.BASEBOARD_FAB2(SCH_1):M_E_DQ<52>
  126  M_E_DQ<51>     DQ<50>  @BASEBOARD_FAB2_LIB.BASEBOARD_FAB2(SCH_1):M_E_DQ<51>
  271  M_E_DQ<50>     DQ<51>  @BASEBOARD_FAB2_LIB.BASEBOARD_FAB2(SCH_1):M_E_DQ<50>
  148  M_E_DQ<4>      DQ<5>  @BASEBOARD_FAB2_LIB.BASEBOARD_FAB2(SCH_1):M_E_DQ<4>
  119  M_E_DQ<49>     DQ<48>  @BASEBOARD_FAB2_LIB.BASEBOARD_FAB2(SCH_1):M_E_DQ<49>
  264  M_E_DQ<48>     DQ<49>  @BASEBOARD_FAB2_LIB.BASEBOARD_FAB2(SCH_1):M_E_DQ<48>
  113  M_E_DQ<47>     DQ<46>  @BASEBOARD_FAB2_LIB.BASEBOARD_FAB2(SCH_1):M_E_DQ<47>
  258  M_E_DQ<46>     DQ<47>  @BASEBOARD_FAB2_LIB.BASEBOARD_FAB2(SCH_1):M_E_DQ<46>
  106  M_E_DQ<45>     DQ<44>  @BASEBOARD_FAB2_LIB.BASEBOARD_FAB2(SCH_1):M_E_DQ<45>
  251  M_E_DQ<44>     DQ<45>  @BASEBOARD_FAB2_LIB.BASEBOARD_FAB2(SCH_1):M_E_DQ<44>
  115  M_E_DQ<43>     DQ<42>  @BASEBOARD_FAB2_LIB.BASEBOARD_FAB2(SCH_1):M_E_DQ<43>
  260  M_E_DQ<42>     DQ<43>  @BASEBOARD_FAB2_LIB.BASEBOARD_FAB2(SCH_1):M_E_DQ<42>
  108  M_E_DQ<41>     DQ<40>  @BASEBOARD_FAB2_LIB.BASEBOARD_FAB2(SCH_1):M_E_DQ<41>
  253  M_E_DQ<40>     DQ<41>  @BASEBOARD_FAB2_LIB.BASEBOARD_FAB2(SCH_1):M_E_DQ<40>
   12  M_E_DQ<3>      DQ<2>  @BASEBOARD_FAB2_LIB.BASEBOARD_FAB2(SCH_1):M_E_DQ<3>
  102  M_E_DQ<39>     DQ<38>  @BASEBOARD_FAB2_LIB.BASEBOARD_FAB2(SCH_1):M_E_DQ<39>
  247  M_E_DQ<38>     DQ<39>  @BASEBOARD_FAB2_LIB.BASEBOARD_FAB2(SCH_1):M_E_DQ<38>
   95  M_E_DQ<37>     DQ<36>  @BASEBOARD_FAB2_LIB.BASEBOARD_FAB2(SCH_1):M_E_DQ<37>
  240  M_E_DQ<36>     DQ<37>  @BASEBOARD_FAB2_LIB.BASEBOARD_FAB2(SCH_1):M_E_DQ<36>
  104  M_E_DQ<35>     DQ<34>  @BASEBOARD_FAB2_LIB.BASEBOARD_FAB2(SCH_1):M_E_DQ<35>
  249  M_E_DQ<34>     DQ<35>  @BASEBOARD_FAB2_LIB.BASEBOARD_FAB2(SCH_1):M_E_DQ<34>
   97  M_E_DQ<33>     DQ<32>  @BASEBOARD_FAB2_LIB.BASEBOARD_FAB2(SCH_1):M_E_DQ<33>
  242  M_E_DQ<32>     DQ<33>  @BASEBOARD_FAB2_LIB.BASEBOARD_FAB2(SCH_1):M_E_DQ<32>
   43  M_E_DQ<31>     DQ<30>  @BASEBOARD_FAB2_LIB.BASEBOARD_FAB2(SCH_1):M_E_DQ<31>
  188  M_E_DQ<30>     DQ<31>  @BASEBOARD_FAB2_LIB.BASEBOARD_FAB2(SCH_1):M_E_DQ<30>
  157  M_E_DQ<2>      DQ<3>  @BASEBOARD_FAB2_LIB.BASEBOARD_FAB2(SCH_1):M_E_DQ<2>
   36  M_E_DQ<29>     DQ<28>  @BASEBOARD_FAB2_LIB.BASEBOARD_FAB2(SCH_1):M_E_DQ<29>
  181  M_E_DQ<28>     DQ<29>  @BASEBOARD_FAB2_LIB.BASEBOARD_FAB2(SCH_1):M_E_DQ<28>
   45  M_E_DQ<27>     DQ<26>  @BASEBOARD_FAB2_LIB.BASEBOARD_FAB2(SCH_1):M_E_DQ<27>
  190  M_E_DQ<26>     DQ<27>  @BASEBOARD_FAB2_LIB.BASEBOARD_FAB2(SCH_1):M_E_DQ<26>
   38  M_E_DQ<25>     DQ<24>  @BASEBOARD_FAB2_LIB.BASEBOARD_FAB2(SCH_1):M_E_DQ<25>
  183  M_E_DQ<24>     DQ<25>  @BASEBOARD_FAB2_LIB.BASEBOARD_FAB2(SCH_1):M_E_DQ<24>
   32  M_E_DQ<23>     DQ<22>  @BASEBOARD_FAB2_LIB.BASEBOARD_FAB2(SCH_1):M_E_DQ<23>
  177  M_E_DQ<22>     DQ<23>  @BASEBOARD_FAB2_LIB.BASEBOARD_FAB2(SCH_1):M_E_DQ<22>
   25  M_E_DQ<21>     DQ<20>  @BASEBOARD_FAB2_LIB.BASEBOARD_FAB2(SCH_1):M_E_DQ<21>
  170  M_E_DQ<20>     DQ<21>  @BASEBOARD_FAB2_LIB.BASEBOARD_FAB2(SCH_1):M_E_DQ<20>
    5  M_E_DQ<1>      DQ<0>  @BASEBOARD_FAB2_LIB.BASEBOARD_FAB2(SCH_1):M_E_DQ<1>
   34  M_E_DQ<19>     DQ<18>  @BASEBOARD_FAB2_LIB.BASEBOARD_FAB2(SCH_1):M_E_DQ<19>
  179  M_E_DQ<18>     DQ<19>  @BASEBOARD_FAB2_LIB.BASEBOARD_FAB2(SCH_1):M_E_DQ<18>
   27  M_E_DQ<17>     DQ<16>  @BASEBOARD_FAB2_LIB.BASEBOARD_FAB2(SCH_1):M_E_DQ<17>
  172  M_E_DQ<16>     DQ<17>  @BASEBOARD_FAB2_LIB.BASEBOARD_FAB2(SCH_1):M_E_DQ<16>
   21  M_E_DQ<15>     DQ<14>  @BASEBOARD_FAB2_LIB.BASEBOARD_FAB2(SCH_1):M_E_DQ<15>
  166  M_E_DQ<14>     DQ<15>  @BASEBOARD_FAB2_LIB.BASEBOARD_FAB2(SCH_1):M_E_DQ<14>
   14  M_E_DQ<13>     DQ<12>  @BASEBOARD_FAB2_LIB.BASEBOARD_FAB2(SCH_1):M_E_DQ<13>
  159  M_E_DQ<12>     DQ<13>  @BASEBOARD_FAB2_LIB.BASEBOARD_FAB2(SCH_1):M_E_DQ<12>
   23  M_E_DQ<11>     DQ<10>  @BASEBOARD_FAB2_LIB.BASEBOARD_FAB2(SCH_1):M_E_DQ<11>
  168  M_E_DQ<10>     DQ<11>  @BASEBOARD_FAB2_LIB.BASEBOARD_FAB2(SCH_1):M_E_DQ<10>
  150  M_E_DQ<0>      DQ<1>  @BASEBOARD_FAB2_LIB.BASEBOARD_FAB2(SCH_1):M_E_DQ<0>
  237  M_E_CS_N<3>    S3_N_C<1>  @BASEBOARD_FAB2_LIB.BASEBOARD_FAB2(SCH_1):M_E_CS_N<3>
   93  M_E_CS_N<2>    S2_N_C<0>  @BASEBOARD_FAB2_LIB.BASEBOARD_FAB2(SCH_1):M_E_CS_N<2>
   89  M_E_CS_N<1>     S1_N  @BASEBOARD_FAB2_LIB.BASEBOARD_FAB2(SCH_1):M_E_CS_N<1>
   84  M_E_CS_N<0>     S0_N  @BASEBOARD_FAB2_LIB.BASEBOARD_FAB2(SCH_1):M_E_CS_N<0>
  218  M_E_CLK_DP<1>   CK1P  @BASEBOARD_FAB2_LIB.BASEBOARD_FAB2(SCH_1):M_E_CLK_DP<1>
   74  M_E_CLK_DP<0>   CK0P  @BASEBOARD_FAB2_LIB.BASEBOARD_FAB2(SCH_1):M_E_CLK_DP<0>
  219  M_E_CLK_DN<1>   CK1N  @BASEBOARD_FAB2_LIB.BASEBOARD_FAB2(SCH_1):M_E_CLK_DN<1>
   75  M_E_CLK_DN<0>   CK0N  @BASEBOARD_FAB2_LIB.BASEBOARD_FAB2(SCH_1):M_E_CLK_DN<0>
  203  M_E_CKE<1>     CKE<1>  @BASEBOARD_FAB2_LIB.BASEBOARD_FAB2(SCH_1):M_E_CKE<1>
   60  M_E_CKE<0>     CKE<0>  @BASEBOARD_FAB2_LIB.BASEBOARD_FAB2(SCH_1):M_E_CKE<0>
  235  M_E_C<2>        C<2>  @BASEBOARD_FAB2_LIB.BASEBOARD_FAB2(SCH_1):M_E_C<2>
  207  M_E_BG<1>      BG<1>  @BASEBOARD_FAB2_LIB.BASEBOARD_FAB2(SCH_1):M_E_BG<1>
   63  M_E_BG<0>      BG<0>  @BASEBOARD_FAB2_LIB.BASEBOARD_FAB2(SCH_1):M_E_BG<0>
  224  M_E_BA<1>      BA<1>  @BASEBOARD_FAB2_LIB.BASEBOARD_FAB2(SCH_1):M_E_BA<1>
   81  M_E_BA<0>      BA<0>  @BASEBOARD_FAB2_LIB.BASEBOARD_FAB2(SCH_1):M_E_BA<0>
  208  M_E_ALERT_N    ALERT_N  @BASEBOARD_FAB2_LIB.BASEBOARD_FAB2(SCH_1):M_E_ALERT_N
   62  M_E_ACT_N      ACT_N  @BASEBOARD_FAB2_LIB.BASEBOARD_FAB2(SCH_1):M_E_ACT_N
   58  M_DEF_RST_N    RESET_N  @BASEBOARD_FAB2_LIB.BASEBOARD_FAB2(SCH_1):M_DEF_RST_N
  238  GND            SA<2>  @BASEBOARD_FAB2_LIB.BASEBOARD_FAB2(SCH_1):GND
  139  GND            SA<0>  @BASEBOARD_FAB2_LIB.BASEBOARD_FAB2(SCH_1):GND
   78  FM_DIMM_EVENT_COD_N  EVENT_N  @BASEBOARD_FAB2_LIB.BASEBOARD_FAB2(SCH_1):FM_DIMM_EVENT_COD_N
  230  FM_ADR_COMPLETE_DEF_N  SAVE_N_NC  @BASEBOARD_FAB2_LIB.BASEBOARD_FAB2(SCH_1):FM_ADR_COMPLETE_DEF_N

SCONN288_H44441004_PIP  I169  J4B1   [SCONN288_H44441004_PIP-SCONN,HA]
   77  PVTT_DEF       VTT<1>  @BASEBOARD_FAB2_LIB.BASEBOARD_FAB2(SCH_1):PVTT_DEF
  221  PVTT_DEF       VTT<0>  @BASEBOARD_FAB2_LIB.BASEBOARD_FAB2(SCH_1):PVTT_DEF
  142  PVPP_DEF       VPP<4>  @BASEBOARD_FAB2_LIB.BASEBOARD_FAB2(SCH_1):PVPP_DEF
  143  PVPP_DEF       VPP<3>  @BASEBOARD_FAB2_LIB.BASEBOARD_FAB2(SCH_1):PVPP_DEF
  288  PVPP_DEF       VPP<2>  @BASEBOARD_FAB2_LIB.BASEBOARD_FAB2(SCH_1):PVPP_DEF
  286  PVPP_DEF       VPP<1>  @BASEBOARD_FAB2_LIB.BASEBOARD_FAB2(SCH_1):PVPP_DEF
  287  PVPP_DEF       VPP<0>  @BASEBOARD_FAB2_LIB.BASEBOARD_FAB2(SCH_1):PVPP_DEF
   59  PVDDQ_DEF      VDD<25>  @BASEBOARD_FAB2_LIB.BASEBOARD_FAB2(SCH_1):PVDDQ_DEF
   61  PVDDQ_DEF      VDD<24>  @BASEBOARD_FAB2_LIB.BASEBOARD_FAB2(SCH_1):PVDDQ_DEF
   64  PVDDQ_DEF      VDD<23>  @BASEBOARD_FAB2_LIB.BASEBOARD_FAB2(SCH_1):PVDDQ_DEF
   67  PVDDQ_DEF      VDD<22>  @BASEBOARD_FAB2_LIB.BASEBOARD_FAB2(SCH_1):PVDDQ_DEF
   70  PVDDQ_DEF      VDD<21>  @BASEBOARD_FAB2_LIB.BASEBOARD_FAB2(SCH_1):PVDDQ_DEF
   73  PVDDQ_DEF      VDD<20>  @BASEBOARD_FAB2_LIB.BASEBOARD_FAB2(SCH_1):PVDDQ_DEF
   76  PVDDQ_DEF      VDD<19>  @BASEBOARD_FAB2_LIB.BASEBOARD_FAB2(SCH_1):PVDDQ_DEF
   80  PVDDQ_DEF      VDD<18>  @BASEBOARD_FAB2_LIB.BASEBOARD_FAB2(SCH_1):PVDDQ_DEF
   83  PVDDQ_DEF      VDD<17>  @BASEBOARD_FAB2_LIB.BASEBOARD_FAB2(SCH_1):PVDDQ_DEF
   85  PVDDQ_DEF      VDD<16>  @BASEBOARD_FAB2_LIB.BASEBOARD_FAB2(SCH_1):PVDDQ_DEF
   88  PVDDQ_DEF      VDD<15>  @BASEBOARD_FAB2_LIB.BASEBOARD_FAB2(SCH_1):PVDDQ_DEF
   90  PVDDQ_DEF      VDD<14>  @BASEBOARD_FAB2_LIB.BASEBOARD_FAB2(SCH_1):PVDDQ_DEF
   92  PVDDQ_DEF      VDD<13>  @BASEBOARD_FAB2_LIB.BASEBOARD_FAB2(SCH_1):PVDDQ_DEF
  204  PVDDQ_DEF      VDD<12>  @BASEBOARD_FAB2_LIB.BASEBOARD_FAB2(SCH_1):PVDDQ_DEF
  206  PVDDQ_DEF      VDD<11>  @BASEBOARD_FAB2_LIB.BASEBOARD_FAB2(SCH_1):PVDDQ_DEF
  209  PVDDQ_DEF      VDD<10>  @BASEBOARD_FAB2_LIB.BASEBOARD_FAB2(SCH_1):PVDDQ_DEF
  212  PVDDQ_DEF      VDD<9>  @BASEBOARD_FAB2_LIB.BASEBOARD_FAB2(SCH_1):PVDDQ_DEF
  215  PVDDQ_DEF      VDD<8>  @BASEBOARD_FAB2_LIB.BASEBOARD_FAB2(SCH_1):PVDDQ_DEF
  217  PVDDQ_DEF      VDD<7>  @BASEBOARD_FAB2_LIB.BASEBOARD_FAB2(SCH_1):PVDDQ_DEF
  220  PVDDQ_DEF      VDD<6>  @BASEBOARD_FAB2_LIB.BASEBOARD_FAB2(SCH_1):PVDDQ_DEF
  223  PVDDQ_DEF      VDD<5>  @BASEBOARD_FAB2_LIB.BASEBOARD_FAB2(SCH_1):PVDDQ_DEF
  226  PVDDQ_DEF      VDD<4>  @BASEBOARD_FAB2_LIB.BASEBOARD_FAB2(SCH_1):PVDDQ_DEF
  229  PVDDQ_DEF      VDD<3>  @BASEBOARD_FAB2_LIB.BASEBOARD_FAB2(SCH_1):PVDDQ_DEF
  231  PVDDQ_DEF      VDD<2>  @BASEBOARD_FAB2_LIB.BASEBOARD_FAB2(SCH_1):PVDDQ_DEF
  233  PVDDQ_DEF      VDD<1>  @BASEBOARD_FAB2_LIB.BASEBOARD_FAB2(SCH_1):PVDDQ_DEF
  236  PVDDQ_DEF      VDD<0>  @BASEBOARD_FAB2_LIB.BASEBOARD_FAB2(SCH_1):PVDDQ_DEF
    1  P12V_NVDIMM_DEF  12V<1>  @BASEBOARD_FAB2_LIB.BASEBOARD_FAB2(SCH_1):P12V_NVDIMM_DEF
  145  P12V_NVDIMM_DEF  12V<0>  @BASEBOARD_FAB2_LIB.BASEBOARD_FAB2(SCH_1):P12V_NVDIMM_DEF

SCONN288_H44441004_PIP  I43  J4B1   [SCONN288_H44441004_PIP-SCONN,HA]
    2  GND            VSS<93>  @BASEBOARD_FAB2_LIB.BASEBOARD_FAB2(SCH_1):GND
    4  GND            VSS<92>  @BASEBOARD_FAB2_LIB.BASEBOARD_FAB2(SCH_1):GND
    6  GND            VSS<91>  @BASEBOARD_FAB2_LIB.BASEBOARD_FAB2(SCH_1):GND
    9  GND            VSS<90>  @BASEBOARD_FAB2_LIB.BASEBOARD_FAB2(SCH_1):GND
   11  GND            VSS<89>  @BASEBOARD_FAB2_LIB.BASEBOARD_FAB2(SCH_1):GND
   13  GND            VSS<88>  @BASEBOARD_FAB2_LIB.BASEBOARD_FAB2(SCH_1):GND
   15  GND            VSS<87>  @BASEBOARD_FAB2_LIB.BASEBOARD_FAB2(SCH_1):GND
   17  GND            VSS<86>  @BASEBOARD_FAB2_LIB.BASEBOARD_FAB2(SCH_1):GND
   20  GND            VSS<85>  @BASEBOARD_FAB2_LIB.BASEBOARD_FAB2(SCH_1):GND
   22  GND            VSS<84>  @BASEBOARD_FAB2_LIB.BASEBOARD_FAB2(SCH_1):GND
   24  GND            VSS<83>  @BASEBOARD_FAB2_LIB.BASEBOARD_FAB2(SCH_1):GND
   26  GND            VSS<82>  @BASEBOARD_FAB2_LIB.BASEBOARD_FAB2(SCH_1):GND
   28  GND            VSS<81>  @BASEBOARD_FAB2_LIB.BASEBOARD_FAB2(SCH_1):GND
   31  GND            VSS<80>  @BASEBOARD_FAB2_LIB.BASEBOARD_FAB2(SCH_1):GND
   33  GND            VSS<79>  @BASEBOARD_FAB2_LIB.BASEBOARD_FAB2(SCH_1):GND
   35  GND            VSS<78>  @BASEBOARD_FAB2_LIB.BASEBOARD_FAB2(SCH_1):GND
   37  GND            VSS<77>  @BASEBOARD_FAB2_LIB.BASEBOARD_FAB2(SCH_1):GND
   39  GND            VSS<76>  @BASEBOARD_FAB2_LIB.BASEBOARD_FAB2(SCH_1):GND
   42  GND            VSS<75>  @BASEBOARD_FAB2_LIB.BASEBOARD_FAB2(SCH_1):GND
   44  GND            VSS<74>  @BASEBOARD_FAB2_LIB.BASEBOARD_FAB2(SCH_1):GND
   46  GND            VSS<73>  @BASEBOARD_FAB2_LIB.BASEBOARD_FAB2(SCH_1):GND
   48  GND            VSS<72>  @BASEBOARD_FAB2_LIB.BASEBOARD_FAB2(SCH_1):GND
   50  GND            VSS<71>  @BASEBOARD_FAB2_LIB.BASEBOARD_FAB2(SCH_1):GND
   53  GND            VSS<70>  @BASEBOARD_FAB2_LIB.BASEBOARD_FAB2(SCH_1):GND
   55  GND            VSS<69>  @BASEBOARD_FAB2_LIB.BASEBOARD_FAB2(SCH_1):GND
   57  GND            VSS<68>  @BASEBOARD_FAB2_LIB.BASEBOARD_FAB2(SCH_1):GND
   94  GND            VSS<67>  @BASEBOARD_FAB2_LIB.BASEBOARD_FAB2(SCH_1):GND
   96  GND            VSS<66>  @BASEBOARD_FAB2_LIB.BASEBOARD_FAB2(SCH_1):GND
   98  GND            VSS<65>  @BASEBOARD_FAB2_LIB.BASEBOARD_FAB2(SCH_1):GND
  101  GND            VSS<64>  @BASEBOARD_FAB2_LIB.BASEBOARD_FAB2(SCH_1):GND
  103  GND            VSS<63>  @BASEBOARD_FAB2_LIB.BASEBOARD_FAB2(SCH_1):GND
  105  GND            VSS<62>  @BASEBOARD_FAB2_LIB.BASEBOARD_FAB2(SCH_1):GND
  107  GND            VSS<61>  @BASEBOARD_FAB2_LIB.BASEBOARD_FAB2(SCH_1):GND
  109  GND            VSS<60>  @BASEBOARD_FAB2_LIB.BASEBOARD_FAB2(SCH_1):GND
  112  GND            VSS<59>  @BASEBOARD_FAB2_LIB.BASEBOARD_FAB2(SCH_1):GND
  114  GND            VSS<58>  @BASEBOARD_FAB2_LIB.BASEBOARD_FAB2(SCH_1):GND
  116  GND            VSS<57>  @BASEBOARD_FAB2_LIB.BASEBOARD_FAB2(SCH_1):GND
  118  GND            VSS<56>  @BASEBOARD_FAB2_LIB.BASEBOARD_FAB2(SCH_1):GND
  120  GND            VSS<55>  @BASEBOARD_FAB2_LIB.BASEBOARD_FAB2(SCH_1):GND
  123  GND            VSS<54>  @BASEBOARD_FAB2_LIB.BASEBOARD_FAB2(SCH_1):GND
  125  GND            VSS<53>  @BASEBOARD_FAB2_LIB.BASEBOARD_FAB2(SCH_1):GND
  127  GND            VSS<52>  @BASEBOARD_FAB2_LIB.BASEBOARD_FAB2(SCH_1):GND
  129  GND            VSS<51>  @BASEBOARD_FAB2_LIB.BASEBOARD_FAB2(SCH_1):GND
  131  GND            VSS<50>  @BASEBOARD_FAB2_LIB.BASEBOARD_FAB2(SCH_1):GND
  134  GND            VSS<49>  @BASEBOARD_FAB2_LIB.BASEBOARD_FAB2(SCH_1):GND
  136  GND            VSS<48>  @BASEBOARD_FAB2_LIB.BASEBOARD_FAB2(SCH_1):GND
  138  GND            VSS<47>  @BASEBOARD_FAB2_LIB.BASEBOARD_FAB2(SCH_1):GND
  147  GND            VSS<46>  @BASEBOARD_FAB2_LIB.BASEBOARD_FAB2(SCH_1):GND
  149  GND            VSS<45>  @BASEBOARD_FAB2_LIB.BASEBOARD_FAB2(SCH_1):GND
  151  GND            VSS<44>  @BASEBOARD_FAB2_LIB.BASEBOARD_FAB2(SCH_1):GND
  154  GND            VSS<43>  @BASEBOARD_FAB2_LIB.BASEBOARD_FAB2(SCH_1):GND
  156  GND            VSS<42>  @BASEBOARD_FAB2_LIB.BASEBOARD_FAB2(SCH_1):GND
  158  GND            VSS<41>  @BASEBOARD_FAB2_LIB.BASEBOARD_FAB2(SCH_1):GND
  160  GND            VSS<40>  @BASEBOARD_FAB2_LIB.BASEBOARD_FAB2(SCH_1):GND
  162  GND            VSS<39>  @BASEBOARD_FAB2_LIB.BASEBOARD_FAB2(SCH_1):GND
  165  GND            VSS<38>  @BASEBOARD_FAB2_LIB.BASEBOARD_FAB2(SCH_1):GND
  167  GND            VSS<37>  @BASEBOARD_FAB2_LIB.BASEBOARD_FAB2(SCH_1):GND
  169  GND            VSS<36>  @BASEBOARD_FAB2_LIB.BASEBOARD_FAB2(SCH_1):GND
  171  GND            VSS<35>  @BASEBOARD_FAB2_LIB.BASEBOARD_FAB2(SCH_1):GND
  173  GND            VSS<34>  @BASEBOARD_FAB2_LIB.BASEBOARD_FAB2(SCH_1):GND
  176  GND            VSS<33>  @BASEBOARD_FAB2_LIB.BASEBOARD_FAB2(SCH_1):GND
  178  GND            VSS<32>  @BASEBOARD_FAB2_LIB.BASEBOARD_FAB2(SCH_1):GND
  180  GND            VSS<31>  @BASEBOARD_FAB2_LIB.BASEBOARD_FAB2(SCH_1):GND
  182  GND            VSS<30>  @BASEBOARD_FAB2_LIB.BASEBOARD_FAB2(SCH_1):GND
  184  GND            VSS<29>  @BASEBOARD_FAB2_LIB.BASEBOARD_FAB2(SCH_1):GND
  187  GND            VSS<28>  @BASEBOARD_FAB2_LIB.BASEBOARD_FAB2(SCH_1):GND
  189  GND            VSS<27>  @BASEBOARD_FAB2_LIB.BASEBOARD_FAB2(SCH_1):GND
  191  GND            VSS<26>  @BASEBOARD_FAB2_LIB.BASEBOARD_FAB2(SCH_1):GND
  193  GND            VSS<25>  @BASEBOARD_FAB2_LIB.BASEBOARD_FAB2(SCH_1):GND
  195  GND            VSS<24>  @BASEBOARD_FAB2_LIB.BASEBOARD_FAB2(SCH_1):GND
  198  GND            VSS<23>  @BASEBOARD_FAB2_LIB.BASEBOARD_FAB2(SCH_1):GND
  200  GND            VSS<22>  @BASEBOARD_FAB2_LIB.BASEBOARD_FAB2(SCH_1):GND
  202  GND            VSS<21>  @BASEBOARD_FAB2_LIB.BASEBOARD_FAB2(SCH_1):GND
  239  GND            VSS<20>  @BASEBOARD_FAB2_LIB.BASEBOARD_FAB2(SCH_1):GND
  241  GND            VSS<19>  @BASEBOARD_FAB2_LIB.BASEBOARD_FAB2(SCH_1):GND
  243  GND            VSS<18>  @BASEBOARD_FAB2_LIB.BASEBOARD_FAB2(SCH_1):GND
  246  GND            VSS<17>  @BASEBOARD_FAB2_LIB.BASEBOARD_FAB2(SCH_1):GND
  248  GND            VSS<16>  @BASEBOARD_FAB2_LIB.BASEBOARD_FAB2(SCH_1):GND
  250  GND            VSS<15>  @BASEBOARD_FAB2_LIB.BASEBOARD_FAB2(SCH_1):GND
  252  GND            VSS<14>  @BASEBOARD_FAB2_LIB.BASEBOARD_FAB2(SCH_1):GND
  254  GND            VSS<13>  @BASEBOARD_FAB2_LIB.BASEBOARD_FAB2(SCH_1):GND
  257  GND            VSS<12>  @BASEBOARD_FAB2_LIB.BASEBOARD_FAB2(SCH_1):GND
  259  GND            VSS<11>  @BASEBOARD_FAB2_LIB.BASEBOARD_FAB2(SCH_1):GND
  261  GND            VSS<10>  @BASEBOARD_FAB2_LIB.BASEBOARD_FAB2(SCH_1):GND
  263  GND            VSS<9>  @BASEBOARD_FAB2_LIB.BASEBOARD_FAB2(SCH_1):GND
  265  GND            VSS<8>  @BASEBOARD_FAB2_LIB.BASEBOARD_FAB2(SCH_1):GND
  268  GND            VSS<7>  @BASEBOARD_FAB2_LIB.BASEBOARD_FAB2(SCH_1):GND
  270  GND            VSS<6>  @BASEBOARD_FAB2_LIB.BASEBOARD_FAB2(SCH_1):GND
  272  GND            VSS<5>  @BASEBOARD_FAB2_LIB.BASEBOARD_FAB2(SCH_1):GND
  274  GND            VSS<4>  @BASEBOARD_FAB2_LIB.BASEBOARD_FAB2(SCH_1):GND
  276  GND            VSS<3>  @BASEBOARD_FAB2_LIB.BASEBOARD_FAB2(SCH_1):GND
  279  GND            VSS<2>  @BASEBOARD_FAB2_LIB.BASEBOARD_FAB2(SCH_1):GND
  281  GND            VSS<1>  @BASEBOARD_FAB2_LIB.BASEBOARD_FAB2(SCH_1):GND
  283  GND            VSS<0>  @BASEBOARD_FAB2_LIB.BASEBOARD_FAB2(SCH_1):GND

SCONN288_H44441004_PIP  I66  J4B1   [SCONN288_H44441004_PIP-SCONN,HA]
    7  M_D_DQS_DP<9>  DQS9P  @BASEBOARD_FAB2_LIB.BASEBOARD_FAB2(SCH_1):M_D_DQS_DP<9>
  197  M_D_DQS_DP<8>  DQS8P  @BASEBOARD_FAB2_LIB.BASEBOARD_FAB2(SCH_1):M_D_DQS_DP<8>
  278  M_D_DQS_DP<7>  DQS7P  @BASEBOARD_FAB2_LIB.BASEBOARD_FAB2(SCH_1):M_D_DQS_DP<7>
  267  M_D_DQS_DP<6>  DQS6P  @BASEBOARD_FAB2_LIB.BASEBOARD_FAB2(SCH_1):M_D_DQS_DP<6>
  256  M_D_DQS_DP<5>  DQS5P  @BASEBOARD_FAB2_LIB.BASEBOARD_FAB2(SCH_1):M_D_DQS_DP<5>
  245  M_D_DQS_DP<4>  DQS4P  @BASEBOARD_FAB2_LIB.BASEBOARD_FAB2(SCH_1):M_D_DQS_DP<4>
  186  M_D_DQS_DP<3>  DQS3P  @BASEBOARD_FAB2_LIB.BASEBOARD_FAB2(SCH_1):M_D_DQS_DP<3>
  175  M_D_DQS_DP<2>  DQS2P  @BASEBOARD_FAB2_LIB.BASEBOARD_FAB2(SCH_1):M_D_DQS_DP<2>
  164  M_D_DQS_DP<1>  DQS1P  @BASEBOARD_FAB2_LIB.BASEBOARD_FAB2(SCH_1):M_D_DQS_DP<1>
   51  M_D_DQS_DP<17>  DQS17P  @BASEBOARD_FAB2_LIB.BASEBOARD_FAB2(SCH_1):M_D_DQS_DP<17>
  132  M_D_DQS_DP<16>  DQS16P  @BASEBOARD_FAB2_LIB.BASEBOARD_FAB2(SCH_1):M_D_DQS_DP<16>
  121  M_D_DQS_DP<15>  DQS15P  @BASEBOARD_FAB2_LIB.BASEBOARD_FAB2(SCH_1):M_D_DQS_DP<15>
  110  M_D_DQS_DP<14>  DQS14P  @BASEBOARD_FAB2_LIB.BASEBOARD_FAB2(SCH_1):M_D_DQS_DP<14>
   99  M_D_DQS_DP<13>  DQS13P  @BASEBOARD_FAB2_LIB.BASEBOARD_FAB2(SCH_1):M_D_DQS_DP<13>
   40  M_D_DQS_DP<12>  DQS12P  @BASEBOARD_FAB2_LIB.BASEBOARD_FAB2(SCH_1):M_D_DQS_DP<12>
   29  M_D_DQS_DP<11>  DQS11P  @BASEBOARD_FAB2_LIB.BASEBOARD_FAB2(SCH_1):M_D_DQS_DP<11>
   18  M_D_DQS_DP<10>  DQS10P  @BASEBOARD_FAB2_LIB.BASEBOARD_FAB2(SCH_1):M_D_DQS_DP<10>
  153  M_D_DQS_DP<0>  DQS0P  @BASEBOARD_FAB2_LIB.BASEBOARD_FAB2(SCH_1):M_D_DQS_DP<0>
    8  M_D_DQS_DN<9>  DQS9N  @BASEBOARD_FAB2_LIB.BASEBOARD_FAB2(SCH_1):M_D_DQS_DN<9>
  196  M_D_DQS_DN<8>  DQS8N  @BASEBOARD_FAB2_LIB.BASEBOARD_FAB2(SCH_1):M_D_DQS_DN<8>
  277  M_D_DQS_DN<7>  DQS7N  @BASEBOARD_FAB2_LIB.BASEBOARD_FAB2(SCH_1):M_D_DQS_DN<7>
  266  M_D_DQS_DN<6>  DQS6N  @BASEBOARD_FAB2_LIB.BASEBOARD_FAB2(SCH_1):M_D_DQS_DN<6>
  255  M_D_DQS_DN<5>  DQS5N  @BASEBOARD_FAB2_LIB.BASEBOARD_FAB2(SCH_1):M_D_DQS_DN<5>
  244  M_D_DQS_DN<4>  DQS4N  @BASEBOARD_FAB2_LIB.BASEBOARD_FAB2(SCH_1):M_D_DQS_DN<4>
  185  M_D_DQS_DN<3>  DQS3N  @BASEBOARD_FAB2_LIB.BASEBOARD_FAB2(SCH_1):M_D_DQS_DN<3>
  174  M_D_DQS_DN<2>  DQS2N  @BASEBOARD_FAB2_LIB.BASEBOARD_FAB2(SCH_1):M_D_DQS_DN<2>
  163  M_D_DQS_DN<1>  DQS1N  @BASEBOARD_FAB2_LIB.BASEBOARD_FAB2(SCH_1):M_D_DQS_DN<1>
   52  M_D_DQS_DN<17>  DQS17N  @BASEBOARD_FAB2_LIB.BASEBOARD_FAB2(SCH_1):M_D_DQS_DN<17>
  133  M_D_DQS_DN<16>  DQS16N  @BASEBOARD_FAB2_LIB.BASEBOARD_FAB2(SCH_1):M_D_DQS_DN<16>
  122  M_D_DQS_DN<15>  DQS15N  @BASEBOARD_FAB2_LIB.BASEBOARD_FAB2(SCH_1):M_D_DQS_DN<15>
  111  M_D_DQS_DN<14>  DQS14N  @BASEBOARD_FAB2_LIB.BASEBOARD_FAB2(SCH_1):M_D_DQS_DN<14>
  100  M_D_DQS_DN<13>  DQS13N  @BASEBOARD_FAB2_LIB.BASEBOARD_FAB2(SCH_1):M_D_DQS_DN<13>
   41  M_D_DQS_DN<12>  DQS12N  @BASEBOARD_FAB2_LIB.BASEBOARD_FAB2(SCH_1):M_D_DQS_DN<12>
   30  M_D_DQS_DN<11>  DQS11N  @BASEBOARD_FAB2_LIB.BASEBOARD_FAB2(SCH_1):M_D_DQS_DN<11>
   19  M_D_DQS_DN<10>  DQS10N  @BASEBOARD_FAB2_LIB.BASEBOARD_FAB2(SCH_1):M_D_DQS_DN<10>
  152  M_D_DQS_DN<0>  DQS0N  @BASEBOARD_FAB2_LIB.BASEBOARD_FAB2(SCH_1):M_D_DQS_DN<0>

SCONN288_H44441004_PIP  I111  J4B1   [SCONN288_H44441004_PIP-SCONN,HA]
  144  TP_CH_D_DIMM_D0_RFU_2  RFU<2>  @BASEBOARD_FAB2_LIB.BASEBOARD_FAB2(SCH_1):TP_CH_D_DIMM_D0_RFU_2
  227  TP_CH_D_DIMM_D0_RFU_1  RFU<1>  @BASEBOARD_FAB2_LIB.BASEBOARD_FAB2(SCH_1):TP_CH_D_DIMM_D0_RFU_1
  205  TP_CH_D_DIMM_D0_RFU_0  RFU<0>  @BASEBOARD_FAB2_LIB.BASEBOARD_FAB2(SCH_1):TP_CH_D_DIMM_D0_RFU_0
  285  SMB_DDR_DEF_VPP_SDA    SDA  @BASEBOARD_FAB2_LIB.BASEBOARD_FAB2(SCH_1):SMB_DDR_DEF_VPP_SDA
  141  SMB_DDR_DEF_VPP_SCL    SCL  @BASEBOARD_FAB2_LIB.BASEBOARD_FAB2(SCH_1):SMB_DDR_DEF_VPP_SCL
  284  PVPP_DEF       VDDSPD  @BASEBOARD_FAB2_LIB.BASEBOARD_FAB2(SCH_1):PVPP_DEF
  146  M_D_VREF       VREFCA  @BASEBOARD_FAB2_LIB.BASEBOARD_FAB2(SCH_1):M_D_VREF
  222  M_D_PAR          PAR  @BASEBOARD_FAB2_LIB.BASEBOARD_FAB2(SCH_1):M_D_PAR
   91  M_D_ODT<1>     ODT<1>  @BASEBOARD_FAB2_LIB.BASEBOARD_FAB2(SCH_1):M_D_ODT<1>
   87  M_D_ODT<0>     ODT<0>  @BASEBOARD_FAB2_LIB.BASEBOARD_FAB2(SCH_1):M_D_ODT<0>
   66  M_D_MA<9>         A9  @BASEBOARD_FAB2_LIB.BASEBOARD_FAB2(SCH_1):M_D_MA<9>
   68  M_D_MA<8>         A8  @BASEBOARD_FAB2_LIB.BASEBOARD_FAB2(SCH_1):M_D_MA<8>
  211  M_D_MA<7>         A7  @BASEBOARD_FAB2_LIB.BASEBOARD_FAB2(SCH_1):M_D_MA<7>
   69  M_D_MA<6>         A6  @BASEBOARD_FAB2_LIB.BASEBOARD_FAB2(SCH_1):M_D_MA<6>
  213  M_D_MA<5>         A5  @BASEBOARD_FAB2_LIB.BASEBOARD_FAB2(SCH_1):M_D_MA<5>
  214  M_D_MA<4>         A4  @BASEBOARD_FAB2_LIB.BASEBOARD_FAB2(SCH_1):M_D_MA<4>
   71  M_D_MA<3>         A3  @BASEBOARD_FAB2_LIB.BASEBOARD_FAB2(SCH_1):M_D_MA<3>
  216  M_D_MA<2>         A2  @BASEBOARD_FAB2_LIB.BASEBOARD_FAB2(SCH_1):M_D_MA<2>
   72  M_D_MA<1>         A1  @BASEBOARD_FAB2_LIB.BASEBOARD_FAB2(SCH_1):M_D_MA<1>
  234  M_D_MA<17>       A17  @BASEBOARD_FAB2_LIB.BASEBOARD_FAB2(SCH_1):M_D_MA<17>
   82  M_D_MA<16>     A16_RAS_N  @BASEBOARD_FAB2_LIB.BASEBOARD_FAB2(SCH_1):M_D_MA<16>
   86  M_D_MA<15>     A15_CAS_N  @BASEBOARD_FAB2_LIB.BASEBOARD_FAB2(SCH_1):M_D_MA<15>
  228  M_D_MA<14>     A14_WE_N  @BASEBOARD_FAB2_LIB.BASEBOARD_FAB2(SCH_1):M_D_MA<14>
  232  M_D_MA<13>       A13  @BASEBOARD_FAB2_LIB.BASEBOARD_FAB2(SCH_1):M_D_MA<13>
   65  M_D_MA<12>       A12  @BASEBOARD_FAB2_LIB.BASEBOARD_FAB2(SCH_1):M_D_MA<12>
  210  M_D_MA<11>       A11  @BASEBOARD_FAB2_LIB.BASEBOARD_FAB2(SCH_1):M_D_MA<11>
  225  M_D_MA<10>       A10  @BASEBOARD_FAB2_LIB.BASEBOARD_FAB2(SCH_1):M_D_MA<10>
   79  M_D_MA<0>         A0  @BASEBOARD_FAB2_LIB.BASEBOARD_FAB2(SCH_1):M_D_MA<0>
   54  M_D_ECC<7>     CB<6>  @BASEBOARD_FAB2_LIB.BASEBOARD_FAB2(SCH_1):M_D_ECC<7>
  199  M_D_ECC<6>     CB<7>  @BASEBOARD_FAB2_LIB.BASEBOARD_FAB2(SCH_1):M_D_ECC<6>
   47  M_D_ECC<5>     CB<4>  @BASEBOARD_FAB2_LIB.BASEBOARD_FAB2(SCH_1):M_D_ECC<5>
  192  M_D_ECC<4>     CB<5>  @BASEBOARD_FAB2_LIB.BASEBOARD_FAB2(SCH_1):M_D_ECC<4>
   56  M_D_ECC<3>     CB<2>  @BASEBOARD_FAB2_LIB.BASEBOARD_FAB2(SCH_1):M_D_ECC<3>
  201  M_D_ECC<2>     CB<3>  @BASEBOARD_FAB2_LIB.BASEBOARD_FAB2(SCH_1):M_D_ECC<2>
   49  M_D_ECC<1>     CB<0>  @BASEBOARD_FAB2_LIB.BASEBOARD_FAB2(SCH_1):M_D_ECC<1>
  194  M_D_ECC<0>     CB<1>  @BASEBOARD_FAB2_LIB.BASEBOARD_FAB2(SCH_1):M_D_ECC<0>
   16  M_D_DQ<9>      DQ<8>  @BASEBOARD_FAB2_LIB.BASEBOARD_FAB2(SCH_1):M_D_DQ<9>
  161  M_D_DQ<8>      DQ<9>  @BASEBOARD_FAB2_LIB.BASEBOARD_FAB2(SCH_1):M_D_DQ<8>
   10  M_D_DQ<7>      DQ<6>  @BASEBOARD_FAB2_LIB.BASEBOARD_FAB2(SCH_1):M_D_DQ<7>
  155  M_D_DQ<6>      DQ<7>  @BASEBOARD_FAB2_LIB.BASEBOARD_FAB2(SCH_1):M_D_DQ<6>
  135  M_D_DQ<63>     DQ<62>  @BASEBOARD_FAB2_LIB.BASEBOARD_FAB2(SCH_1):M_D_DQ<63>
  280  M_D_DQ<62>     DQ<63>  @BASEBOARD_FAB2_LIB.BASEBOARD_FAB2(SCH_1):M_D_DQ<62>
  128  M_D_DQ<61>     DQ<60>  @BASEBOARD_FAB2_LIB.BASEBOARD_FAB2(SCH_1):M_D_DQ<61>
  273  M_D_DQ<60>     DQ<61>  @BASEBOARD_FAB2_LIB.BASEBOARD_FAB2(SCH_1):M_D_DQ<60>
    3  M_D_DQ<5>      DQ<4>  @BASEBOARD_FAB2_LIB.BASEBOARD_FAB2(SCH_1):M_D_DQ<5>
  137  M_D_DQ<59>     DQ<58>  @BASEBOARD_FAB2_LIB.BASEBOARD_FAB2(SCH_1):M_D_DQ<59>
  282  M_D_DQ<58>     DQ<59>  @BASEBOARD_FAB2_LIB.BASEBOARD_FAB2(SCH_1):M_D_DQ<58>
  130  M_D_DQ<57>     DQ<56>  @BASEBOARD_FAB2_LIB.BASEBOARD_FAB2(SCH_1):M_D_DQ<57>
  275  M_D_DQ<56>     DQ<57>  @BASEBOARD_FAB2_LIB.BASEBOARD_FAB2(SCH_1):M_D_DQ<56>
  124  M_D_DQ<55>     DQ<54>  @BASEBOARD_FAB2_LIB.BASEBOARD_FAB2(SCH_1):M_D_DQ<55>
  269  M_D_DQ<54>     DQ<55>  @BASEBOARD_FAB2_LIB.BASEBOARD_FAB2(SCH_1):M_D_DQ<54>
  117  M_D_DQ<53>     DQ<52>  @BASEBOARD_FAB2_LIB.BASEBOARD_FAB2(SCH_1):M_D_DQ<53>
  262  M_D_DQ<52>     DQ<53>  @BASEBOARD_FAB2_LIB.BASEBOARD_FAB2(SCH_1):M_D_DQ<52>
  126  M_D_DQ<51>     DQ<50>  @BASEBOARD_FAB2_LIB.BASEBOARD_FAB2(SCH_1):M_D_DQ<51>
  271  M_D_DQ<50>     DQ<51>  @BASEBOARD_FAB2_LIB.BASEBOARD_FAB2(SCH_1):M_D_DQ<50>
  148  M_D_DQ<4>      DQ<5>  @BASEBOARD_FAB2_LIB.BASEBOARD_FAB2(SCH_1):M_D_DQ<4>
  119  M_D_DQ<49>     DQ<48>  @BASEBOARD_FAB2_LIB.BASEBOARD_FAB2(SCH_1):M_D_DQ<49>
  264  M_D_DQ<48>     DQ<49>  @BASEBOARD_FAB2_LIB.BASEBOARD_FAB2(SCH_1):M_D_DQ<48>
  113  M_D_DQ<47>     DQ<46>  @BASEBOARD_FAB2_LIB.BASEBOARD_FAB2(SCH_1):M_D_DQ<47>
  258  M_D_DQ<46>     DQ<47>  @BASEBOARD_FAB2_LIB.BASEBOARD_FAB2(SCH_1):M_D_DQ<46>
  106  M_D_DQ<45>     DQ<44>  @BASEBOARD_FAB2_LIB.BASEBOARD_FAB2(SCH_1):M_D_DQ<45>
  251  M_D_DQ<44>     DQ<45>  @BASEBOARD_FAB2_LIB.BASEBOARD_FAB2(SCH_1):M_D_DQ<44>
  115  M_D_DQ<43>     DQ<42>  @BASEBOARD_FAB2_LIB.BASEBOARD_FAB2(SCH_1):M_D_DQ<43>
  260  M_D_DQ<42>     DQ<43>  @BASEBOARD_FAB2_LIB.BASEBOARD_FAB2(SCH_1):M_D_DQ<42>
  108  M_D_DQ<41>     DQ<40>  @BASEBOARD_FAB2_LIB.BASEBOARD_FAB2(SCH_1):M_D_DQ<41>
  253  M_D_DQ<40>     DQ<41>  @BASEBOARD_FAB2_LIB.BASEBOARD_FAB2(SCH_1):M_D_DQ<40>
   12  M_D_DQ<3>      DQ<2>  @BASEBOARD_FAB2_LIB.BASEBOARD_FAB2(SCH_1):M_D_DQ<3>
  102  M_D_DQ<39>     DQ<38>  @BASEBOARD_FAB2_LIB.BASEBOARD_FAB2(SCH_1):M_D_DQ<39>
  247  M_D_DQ<38>     DQ<39>  @BASEBOARD_FAB2_LIB.BASEBOARD_FAB2(SCH_1):M_D_DQ<38>
   95  M_D_DQ<37>     DQ<36>  @BASEBOARD_FAB2_LIB.BASEBOARD_FAB2(SCH_1):M_D_DQ<37>
  240  M_D_DQ<36>     DQ<37>  @BASEBOARD_FAB2_LIB.BASEBOARD_FAB2(SCH_1):M_D_DQ<36>
  104  M_D_DQ<35>     DQ<34>  @BASEBOARD_FAB2_LIB.BASEBOARD_FAB2(SCH_1):M_D_DQ<35>
  249  M_D_DQ<34>     DQ<35>  @BASEBOARD_FAB2_LIB.BASEBOARD_FAB2(SCH_1):M_D_DQ<34>
   97  M_D_DQ<33>     DQ<32>  @BASEBOARD_FAB2_LIB.BASEBOARD_FAB2(SCH_1):M_D_DQ<33>
  242  M_D_DQ<32>     DQ<33>  @BASEBOARD_FAB2_LIB.BASEBOARD_FAB2(SCH_1):M_D_DQ<32>
   43  M_D_DQ<31>     DQ<30>  @BASEBOARD_FAB2_LIB.BASEBOARD_FAB2(SCH_1):M_D_DQ<31>
  188  M_D_DQ<30>     DQ<31>  @BASEBOARD_FAB2_LIB.BASEBOARD_FAB2(SCH_1):M_D_DQ<30>
  157  M_D_DQ<2>      DQ<3>  @BASEBOARD_FAB2_LIB.BASEBOARD_FAB2(SCH_1):M_D_DQ<2>
   36  M_D_DQ<29>     DQ<28>  @BASEBOARD_FAB2_LIB.BASEBOARD_FAB2(SCH_1):M_D_DQ<29>
  181  M_D_DQ<28>     DQ<29>  @BASEBOARD_FAB2_LIB.BASEBOARD_FAB2(SCH_1):M_D_DQ<28>
   45  M_D_DQ<27>     DQ<26>  @BASEBOARD_FAB2_LIB.BASEBOARD_FAB2(SCH_1):M_D_DQ<27>
  190  M_D_DQ<26>     DQ<27>  @BASEBOARD_FAB2_LIB.BASEBOARD_FAB2(SCH_1):M_D_DQ<26>
   38  M_D_DQ<25>     DQ<24>  @BASEBOARD_FAB2_LIB.BASEBOARD_FAB2(SCH_1):M_D_DQ<25>
  183  M_D_DQ<24>     DQ<25>  @BASEBOARD_FAB2_LIB.BASEBOARD_FAB2(SCH_1):M_D_DQ<24>
   32  M_D_DQ<23>     DQ<22>  @BASEBOARD_FAB2_LIB.BASEBOARD_FAB2(SCH_1):M_D_DQ<23>
  177  M_D_DQ<22>     DQ<23>  @BASEBOARD_FAB2_LIB.BASEBOARD_FAB2(SCH_1):M_D_DQ<22>
   25  M_D_DQ<21>     DQ<20>  @BASEBOARD_FAB2_LIB.BASEBOARD_FAB2(SCH_1):M_D_DQ<21>
  170  M_D_DQ<20>     DQ<21>  @BASEBOARD_FAB2_LIB.BASEBOARD_FAB2(SCH_1):M_D_DQ<20>
    5  M_D_DQ<1>      DQ<0>  @BASEBOARD_FAB2_LIB.BASEBOARD_FAB2(SCH_1):M_D_DQ<1>
   34  M_D_DQ<19>     DQ<18>  @BASEBOARD_FAB2_LIB.BASEBOARD_FAB2(SCH_1):M_D_DQ<19>
  179  M_D_DQ<18>     DQ<19>  @BASEBOARD_FAB2_LIB.BASEBOARD_FAB2(SCH_1):M_D_DQ<18>
   27  M_D_DQ<17>     DQ<16>  @BASEBOARD_FAB2_LIB.BASEBOARD_FAB2(SCH_1):M_D_DQ<17>
  172  M_D_DQ<16>     DQ<17>  @BASEBOARD_FAB2_LIB.BASEBOARD_FAB2(SCH_1):M_D_DQ<16>
   21  M_D_DQ<15>     DQ<14>  @BASEBOARD_FAB2_LIB.BASEBOARD_FAB2(SCH_1):M_D_DQ<15>
  166  M_D_DQ<14>     DQ<15>  @BASEBOARD_FAB2_LIB.BASEBOARD_FAB2(SCH_1):M_D_DQ<14>
   14  M_D_DQ<13>     DQ<12>  @BASEBOARD_FAB2_LIB.BASEBOARD_FAB2(SCH_1):M_D_DQ<13>
  159  M_D_DQ<12>     DQ<13>  @BASEBOARD_FAB2_LIB.BASEBOARD_FAB2(SCH_1):M_D_DQ<12>
   23  M_D_DQ<11>     DQ<10>  @BASEBOARD_FAB2_LIB.BASEBOARD_FAB2(SCH_1):M_D_DQ<11>
  168  M_D_DQ<10>     DQ<11>  @BASEBOARD_FAB2_LIB.BASEBOARD_FAB2(SCH_1):M_D_DQ<10>
  150  M_D_DQ<0>      DQ<1>  @BASEBOARD_FAB2_LIB.BASEBOARD_FAB2(SCH_1):M_D_DQ<0>
  237  M_D_CS_N<3>    S3_N_C<1>  @BASEBOARD_FAB2_LIB.BASEBOARD_FAB2(SCH_1):M_D_CS_N<3>
   93  M_D_CS_N<2>    S2_N_C<0>  @BASEBOARD_FAB2_LIB.BASEBOARD_FAB2(SCH_1):M_D_CS_N<2>
   89  M_D_CS_N<1>     S1_N  @BASEBOARD_FAB2_LIB.BASEBOARD_FAB2(SCH_1):M_D_CS_N<1>
   84  M_D_CS_N<0>     S0_N  @BASEBOARD_FAB2_LIB.BASEBOARD_FAB2(SCH_1):M_D_CS_N<0>
  218  M_D_CLK_DP<1>   CK1P  @BASEBOARD_FAB2_LIB.BASEBOARD_FAB2(SCH_1):M_D_CLK_DP<1>
   74  M_D_CLK_DP<0>   CK0P  @BASEBOARD_FAB2_LIB.BASEBOARD_FAB2(SCH_1):M_D_CLK_DP<0>
  219  M_D_CLK_DN<1>   CK1N  @BASEBOARD_FAB2_LIB.BASEBOARD_FAB2(SCH_1):M_D_CLK_DN<1>
   75  M_D_CLK_DN<0>   CK0N  @BASEBOARD_FAB2_LIB.BASEBOARD_FAB2(SCH_1):M_D_CLK_DN<0>
  203  M_D_CKE<1>     CKE<1>  @BASEBOARD_FAB2_LIB.BASEBOARD_FAB2(SCH_1):M_D_CKE<1>
   60  M_D_CKE<0>     CKE<0>  @BASEBOARD_FAB2_LIB.BASEBOARD_FAB2(SCH_1):M_D_CKE<0>
  235  M_D_C<2>        C<2>  @BASEBOARD_FAB2_LIB.BASEBOARD_FAB2(SCH_1):M_D_C<2>
  207  M_D_BG<1>      BG<1>  @BASEBOARD_FAB2_LIB.BASEBOARD_FAB2(SCH_1):M_D_BG<1>
   63  M_D_BG<0>      BG<0>  @BASEBOARD_FAB2_LIB.BASEBOARD_FAB2(SCH_1):M_D_BG<0>
  224  M_D_BA<1>      BA<1>  @BASEBOARD_FAB2_LIB.BASEBOARD_FAB2(SCH_1):M_D_BA<1>
   81  M_D_BA<0>      BA<0>  @BASEBOARD_FAB2_LIB.BASEBOARD_FAB2(SCH_1):M_D_BA<0>
  208  M_D_ALERT_N    ALERT_N  @BASEBOARD_FAB2_LIB.BASEBOARD_FAB2(SCH_1):M_D_ALERT_N
   62  M_D_ACT_N      ACT_N  @BASEBOARD_FAB2_LIB.BASEBOARD_FAB2(SCH_1):M_D_ACT_N
   58  M_DEF_RST_N    RESET_N  @BASEBOARD_FAB2_LIB.BASEBOARD_FAB2(SCH_1):M_DEF_RST_N
  238  GND            SA<2>  @BASEBOARD_FAB2_LIB.BASEBOARD_FAB2(SCH_1):GND
  140  GND            SA<1>  @BASEBOARD_FAB2_LIB.BASEBOARD_FAB2(SCH_1):GND
  139  GND            SA<0>  @BASEBOARD_FAB2_LIB.BASEBOARD_FAB2(SCH_1):GND
   78  FM_DIMM_EVENT_COD_N  EVENT_N  @BASEBOARD_FAB2_LIB.BASEBOARD_FAB2(SCH_1):FM_DIMM_EVENT_COD_N
  230  FM_ADR_COMPLETE_DEF_N  SAVE_N_NC  @BASEBOARD_FAB2_LIB.BASEBOARD_FAB2(SCH_1):FM_ADR_COMPLETE_DEF_N

SCONN120_H61426002_SM  I46  J4B2   [SCONN120_H61426002_SM-CONN,H61A]
   E8  VSENSE_PVCCIOMCP_CPU1_SKT_VSEN   IOE8  @BASEBOARD_FAB2_LIB.BASEBOARD_FAB2(SCH_1):VSENSE_PVCCIOMCP_CPU1_SKT_VSEN
   F8  VSENSE_PVCCIOMCP_CPU1_SKT_VRTN   IOF8  @BASEBOARD_FAB2_LIB.BASEBOARD_FAB2(SCH_1):VSENSE_PVCCIOMCP_CPU1_SKT_VRTN
  F10  VR_PVCCMCP_CPU1_XADDR2  IOF10  @BASEBOARD_FAB2_LIB.BASEBOARD_FAB2(SCH_1):VR_PVCCMCP_CPU1_XADDR2
  E10  VR_PVCCIOMCP_CPU1_XADDR1  IOE10  @BASEBOARD_FAB2_LIB.BASEBOARD_FAB2(SCH_1):VR_PVCCIOMCP_CPU1_XADDR1
  F20  SVID_DIO1_CPU1_R  IOF20  @BASEBOARD_FAB2_LIB.BASEBOARD_FAB2(SCH_1):SVID_DIO1_CPU1_R
  B20  SVID_DIO0_CPU1_R  IOB20  @BASEBOARD_FAB2_LIB.BASEBOARD_FAB2(SCH_1):SVID_DIO0_CPU1_R
  E20  SVID_CLK1_CPU1_R  IOE20  @BASEBOARD_FAB2_LIB.BASEBOARD_FAB2(SCH_1):SVID_CLK1_CPU1_R
  A20  SVID_CLK0_CPU1_R  IOA20  @BASEBOARD_FAB2_LIB.BASEBOARD_FAB2(SCH_1):SVID_CLK0_CPU1_R
  B19  SVID_ALERT1_CPU1_R_N  IOB19  @BASEBOARD_FAB2_LIB.BASEBOARD_FAB2(SCH_1):SVID_ALERT1_CPU1_R_N
  A19  SVID_ALERT0_CPU1_R_N  IOA19  @BASEBOARD_FAB2_LIB.BASEBOARD_FAB2(SCH_1):SVID_ALERT0_CPU1_R_N
  B18  SMB_VR_STBY_LVC3_SDA  IOB18  @BASEBOARD_FAB2_LIB.BASEBOARD_FAB2(SCH_1):SMB_VR_STBY_LVC3_SDA
  A18  SMB_VR_STBY_LVC3_SCL  IOA18  @BASEBOARD_FAB2_LIB.BASEBOARD_FAB2(SCH_1):SMB_VR_STBY_LVC3_SCL
  D20  PWRGD_PVCCMCP_CPU1  IOD20  @BASEBOARD_FAB2_LIB.BASEBOARD_FAB2(SCH_1):PWRGD_PVCCMCP_CPU1
  B16  PWRGD_PVCCIOMCP_CPU1  IOB16  @BASEBOARD_FAB2_LIB.BASEBOARD_FAB2(SCH_1):PWRGD_PVCCIOMCP_CPU1
  B15  PWRGD_P1V8MCP_CPU1  IOB15  @BASEBOARD_FAB2_LIB.BASEBOARD_FAB2(SCH_1):PWRGD_P1V8MCP_CPU1
   F1  PVCCIO_CPU1     IOF1  @BASEBOARD_FAB2_LIB.BASEBOARD_FAB2(SCH_1):PVCCIO_CPU1
  F19  PVCCIOMCP_CPU1  IOF19  @BASEBOARD_FAB2_LIB.BASEBOARD_FAB2(SCH_1):PVCCIOMCP_CPU1
  F18  PVCCIOMCP_CPU1  IOF18  @BASEBOARD_FAB2_LIB.BASEBOARD_FAB2(SCH_1):PVCCIOMCP_CPU1
  F17  PVCCIOMCP_CPU1  IOF17  @BASEBOARD_FAB2_LIB.BASEBOARD_FAB2(SCH_1):PVCCIOMCP_CPU1
  F16  PVCCIOMCP_CPU1  IOF16  @BASEBOARD_FAB2_LIB.BASEBOARD_FAB2(SCH_1):PVCCIOMCP_CPU1
  F15  PVCCIOMCP_CPU1  IOF15  @BASEBOARD_FAB2_LIB.BASEBOARD_FAB2(SCH_1):PVCCIOMCP_CPU1
  E19  PVCCIOMCP_CPU1  IOE19  @BASEBOARD_FAB2_LIB.BASEBOARD_FAB2(SCH_1):PVCCIOMCP_CPU1
  E18  PVCCIOMCP_CPU1  IOE18  @BASEBOARD_FAB2_LIB.BASEBOARD_FAB2(SCH_1):PVCCIOMCP_CPU1
  E17  PVCCIOMCP_CPU1  IOE17  @BASEBOARD_FAB2_LIB.BASEBOARD_FAB2(SCH_1):PVCCIOMCP_CPU1
  E16  PVCCIOMCP_CPU1  IOE16  @BASEBOARD_FAB2_LIB.BASEBOARD_FAB2(SCH_1):PVCCIOMCP_CPU1
  E15  PVCCIOMCP_CPU1  IOE15  @BASEBOARD_FAB2_LIB.BASEBOARD_FAB2(SCH_1):PVCCIOMCP_CPU1
  D19  PVCCIOMCP_CPU1  IOD19  @BASEBOARD_FAB2_LIB.BASEBOARD_FAB2(SCH_1):PVCCIOMCP_CPU1
  D18  PVCCIOMCP_CPU1  IOD18  @BASEBOARD_FAB2_LIB.BASEBOARD_FAB2(SCH_1):PVCCIOMCP_CPU1
  D17  PVCCIOMCP_CPU1  IOD17  @BASEBOARD_FAB2_LIB.BASEBOARD_FAB2(SCH_1):PVCCIOMCP_CPU1
  D16  PVCCIOMCP_CPU1  IOD16  @BASEBOARD_FAB2_LIB.BASEBOARD_FAB2(SCH_1):PVCCIOMCP_CPU1
  D15  PVCCIOMCP_CPU1  IOD15  @BASEBOARD_FAB2_LIB.BASEBOARD_FAB2(SCH_1):PVCCIOMCP_CPU1
  C19  PVCCIOMCP_CPU1  IOC19  @BASEBOARD_FAB2_LIB.BASEBOARD_FAB2(SCH_1):PVCCIOMCP_CPU1
  C18  PVCCIOMCP_CPU1  IOC18  @BASEBOARD_FAB2_LIB.BASEBOARD_FAB2(SCH_1):PVCCIOMCP_CPU1
  C17  PVCCIOMCP_CPU1  IOC17  @BASEBOARD_FAB2_LIB.BASEBOARD_FAB2(SCH_1):PVCCIOMCP_CPU1
  C13  P5V_STBY       IOC13  @BASEBOARD_FAB2_LIB.BASEBOARD_FAB2(SCH_1):P5V_STBY
  B13  P5V_STBY       IOB13  @BASEBOARD_FAB2_LIB.BASEBOARD_FAB2(SCH_1):P5V_STBY
  A13  P5V_STBY       IOA13  @BASEBOARD_FAB2_LIB.BASEBOARD_FAB2(SCH_1):P5V_STBY
  C11  P3V3_STBY      IOC11  @BASEBOARD_FAB2_LIB.BASEBOARD_FAB2(SCH_1):P3V3_STBY
  B11  P3V3_STBY      IOB11  @BASEBOARD_FAB2_LIB.BASEBOARD_FAB2(SCH_1):P3V3_STBY
  A11  P3V3_STBY      IOA11  @BASEBOARD_FAB2_LIB.BASEBOARD_FAB2(SCH_1):P3V3_STBY
   D1  P3V3            IOD1  @BASEBOARD_FAB2_LIB.BASEBOARD_FAB2(SCH_1):P3V3
   B8  P12V_STBY       IOB8  @BASEBOARD_FAB2_LIB.BASEBOARD_FAB2(SCH_1):P12V_STBY
   B7  P12V_STBY       IOB7  @BASEBOARD_FAB2_LIB.BASEBOARD_FAB2(SCH_1):P12V_STBY
   B6  P12V_STBY       IOB6  @BASEBOARD_FAB2_LIB.BASEBOARD_FAB2(SCH_1):P12V_STBY
   B5  P12V_STBY       IOB5  @BASEBOARD_FAB2_LIB.BASEBOARD_FAB2(SCH_1):P12V_STBY
   B4  P12V_STBY       IOB4  @BASEBOARD_FAB2_LIB.BASEBOARD_FAB2(SCH_1):P12V_STBY
   B3  P12V_STBY       IOB3  @BASEBOARD_FAB2_LIB.BASEBOARD_FAB2(SCH_1):P12V_STBY
   B2  P12V_STBY       IOB2  @BASEBOARD_FAB2_LIB.BASEBOARD_FAB2(SCH_1):P12V_STBY
   B1  P12V_STBY       IOB1  @BASEBOARD_FAB2_LIB.BASEBOARD_FAB2(SCH_1):P12V_STBY
   A8  P12V_STBY       IOA8  @BASEBOARD_FAB2_LIB.BASEBOARD_FAB2(SCH_1):P12V_STBY
   A7  P12V_STBY       IOA7  @BASEBOARD_FAB2_LIB.BASEBOARD_FAB2(SCH_1):P12V_STBY
   A6  P12V_STBY       IOA6  @BASEBOARD_FAB2_LIB.BASEBOARD_FAB2(SCH_1):P12V_STBY
   A5  P12V_STBY       IOA5  @BASEBOARD_FAB2_LIB.BASEBOARD_FAB2(SCH_1):P12V_STBY
   A4  P12V_STBY       IOA4  @BASEBOARD_FAB2_LIB.BASEBOARD_FAB2(SCH_1):P12V_STBY
   A3  P12V_STBY       IOA3  @BASEBOARD_FAB2_LIB.BASEBOARD_FAB2(SCH_1):P12V_STBY
   A2  P12V_STBY       IOA2  @BASEBOARD_FAB2_LIB.BASEBOARD_FAB2(SCH_1):P12V_STBY
   A1  P12V_STBY       IOA1  @BASEBOARD_FAB2_LIB.BASEBOARD_FAB2(SCH_1):P12V_STBY
  F14  GND            IOF14  @BASEBOARD_FAB2_LIB.BASEBOARD_FAB2(SCH_1):GND
  F13  GND            IOF13  @BASEBOARD_FAB2_LIB.BASEBOARD_FAB2(SCH_1):GND
  F12  GND            IOF12  @BASEBOARD_FAB2_LIB.BASEBOARD_FAB2(SCH_1):GND
  F11  GND            IOF11  @BASEBOARD_FAB2_LIB.BASEBOARD_FAB2(SCH_1):GND
   F9  GND             IOF9  @BASEBOARD_FAB2_LIB.BASEBOARD_FAB2(SCH_1):GND
   F7  GND             IOF7  @BASEBOARD_FAB2_LIB.BASEBOARD_FAB2(SCH_1):GND
   F6  GND             IOF6  @BASEBOARD_FAB2_LIB.BASEBOARD_FAB2(SCH_1):GND
   F5  GND             IOF5  @BASEBOARD_FAB2_LIB.BASEBOARD_FAB2(SCH_1):GND
   F4  GND             IOF4  @BASEBOARD_FAB2_LIB.BASEBOARD_FAB2(SCH_1):GND
   F3  GND             IOF3  @BASEBOARD_FAB2_LIB.BASEBOARD_FAB2(SCH_1):GND
   F2  GND             IOF2  @BASEBOARD_FAB2_LIB.BASEBOARD_FAB2(SCH_1):GND
  E14  GND            IOE14  @BASEBOARD_FAB2_LIB.BASEBOARD_FAB2(SCH_1):GND
  E13  GND            IOE13  @BASEBOARD_FAB2_LIB.BASEBOARD_FAB2(SCH_1):GND
  E12  GND            IOE12  @BASEBOARD_FAB2_LIB.BASEBOARD_FAB2(SCH_1):GND
  E11  GND            IOE11  @BASEBOARD_FAB2_LIB.BASEBOARD_FAB2(SCH_1):GND
   E9  GND             IOE9  @BASEBOARD_FAB2_LIB.BASEBOARD_FAB2(SCH_1):GND
   E7  GND             IOE7  @BASEBOARD_FAB2_LIB.BASEBOARD_FAB2(SCH_1):GND
   E6  GND             IOE6  @BASEBOARD_FAB2_LIB.BASEBOARD_FAB2(SCH_1):GND
   E5  GND             IOE5  @BASEBOARD_FAB2_LIB.BASEBOARD_FAB2(SCH_1):GND
   E4  GND             IOE4  @BASEBOARD_FAB2_LIB.BASEBOARD_FAB2(SCH_1):GND
   E3  GND             IOE3  @BASEBOARD_FAB2_LIB.BASEBOARD_FAB2(SCH_1):GND
   E2  GND             IOE2  @BASEBOARD_FAB2_LIB.BASEBOARD_FAB2(SCH_1):GND
  D14  GND            IOD14  @BASEBOARD_FAB2_LIB.BASEBOARD_FAB2(SCH_1):GND
  D13  GND            IOD13  @BASEBOARD_FAB2_LIB.BASEBOARD_FAB2(SCH_1):GND
  D12  GND            IOD12  @BASEBOARD_FAB2_LIB.BASEBOARD_FAB2(SCH_1):GND
  D11  GND            IOD11  @BASEBOARD_FAB2_LIB.BASEBOARD_FAB2(SCH_1):GND
  D10  GND            IOD10  @BASEBOARD_FAB2_LIB.BASEBOARD_FAB2(SCH_1):GND
   D9  GND             IOD9  @BASEBOARD_FAB2_LIB.BASEBOARD_FAB2(SCH_1):GND
   D8  GND             IOD8  @BASEBOARD_FAB2_LIB.BASEBOARD_FAB2(SCH_1):GND
   D7  GND             IOD7  @BASEBOARD_FAB2_LIB.BASEBOARD_FAB2(SCH_1):GND
   D6  GND             IOD6  @BASEBOARD_FAB2_LIB.BASEBOARD_FAB2(SCH_1):GND
   D5  GND             IOD5  @BASEBOARD_FAB2_LIB.BASEBOARD_FAB2(SCH_1):GND
   D4  GND             IOD4  @BASEBOARD_FAB2_LIB.BASEBOARD_FAB2(SCH_1):GND
   D3  GND             IOD3  @BASEBOARD_FAB2_LIB.BASEBOARD_FAB2(SCH_1):GND
   D2  GND             IOD2  @BASEBOARD_FAB2_LIB.BASEBOARD_FAB2(SCH_1):GND
  C16  GND            IOC16  @BASEBOARD_FAB2_LIB.BASEBOARD_FAB2(SCH_1):GND
  C15  GND            IOC15  @BASEBOARD_FAB2_LIB.BASEBOARD_FAB2(SCH_1):GND
  C14  GND            IOC14  @BASEBOARD_FAB2_LIB.BASEBOARD_FAB2(SCH_1):GND
  C12  GND            IOC12  @BASEBOARD_FAB2_LIB.BASEBOARD_FAB2(SCH_1):GND
  C10  GND            IOC10  @BASEBOARD_FAB2_LIB.BASEBOARD_FAB2(SCH_1):GND
   C9  GND             IOC9  @BASEBOARD_FAB2_LIB.BASEBOARD_FAB2(SCH_1):GND
   C8  GND             IOC8  @BASEBOARD_FAB2_LIB.BASEBOARD_FAB2(SCH_1):GND
   C7  GND             IOC7  @BASEBOARD_FAB2_LIB.BASEBOARD_FAB2(SCH_1):GND
   C6  GND             IOC6  @BASEBOARD_FAB2_LIB.BASEBOARD_FAB2(SCH_1):GND
   C5  GND             IOC5  @BASEBOARD_FAB2_LIB.BASEBOARD_FAB2(SCH_1):GND
   C4  GND             IOC4  @BASEBOARD_FAB2_LIB.BASEBOARD_FAB2(SCH_1):GND
   C3  GND             IOC3  @BASEBOARD_FAB2_LIB.BASEBOARD_FAB2(SCH_1):GND
   C2  GND             IOC2  @BASEBOARD_FAB2_LIB.BASEBOARD_FAB2(SCH_1):GND
   C1  GND             IOC1  @BASEBOARD_FAB2_LIB.BASEBOARD_FAB2(SCH_1):GND
  B17  GND            IOB17  @BASEBOARD_FAB2_LIB.BASEBOARD_FAB2(SCH_1):GND
  B14  GND            IOB14  @BASEBOARD_FAB2_LIB.BASEBOARD_FAB2(SCH_1):GND
  B12  GND            IOB12  @BASEBOARD_FAB2_LIB.BASEBOARD_FAB2(SCH_1):GND
  B10  GND            IOB10  @BASEBOARD_FAB2_LIB.BASEBOARD_FAB2(SCH_1):GND
   B9  GND             IOB9  @BASEBOARD_FAB2_LIB.BASEBOARD_FAB2(SCH_1):GND
  A17  GND            IOA17  @BASEBOARD_FAB2_LIB.BASEBOARD_FAB2(SCH_1):GND
  A14  GND            IOA14  @BASEBOARD_FAB2_LIB.BASEBOARD_FAB2(SCH_1):GND
  A12  GND            IOA12  @BASEBOARD_FAB2_LIB.BASEBOARD_FAB2(SCH_1):GND
  A10  GND            IOA10  @BASEBOARD_FAB2_LIB.BASEBOARD_FAB2(SCH_1):GND
   A9  GND             IOA9  @BASEBOARD_FAB2_LIB.BASEBOARD_FAB2(SCH_1):GND
  C20  FM_PVCCMCP_CPU1_EN  IOC20  @BASEBOARD_FAB2_LIB.BASEBOARD_FAB2(SCH_1):FM_PVCCMCP_CPU1_EN
  A16  FM_PVCCIOMCP_CPU1_EN  IOA16  @BASEBOARD_FAB2_LIB.BASEBOARD_FAB2(SCH_1):FM_PVCCIOMCP_CPU1_EN
  A15  FM_P1V8MCP_CPU1_EN  IOA15  @BASEBOARD_FAB2_LIB.BASEBOARD_FAB2(SCH_1):FM_P1V8MCP_CPU1_EN
   E1  FM_CPU1_VRM_322M_156M_OSC_EN   IOE1  @BASEBOARD_FAB2_LIB.BASEBOARD_FAB2(SCH_1):FM_CPU1_VRM_322M_156M_OSC_EN

SCONN120_H61426002_SM  I45  J4E1   [SCONN120_H61426002_SM-CONN,H61A]
   A4  VSENSE_PVCCMCP_CPU1_SKT_VSEN   IOA4  @BASEBOARD_FAB2_LIB.BASEBOARD_FAB2(SCH_1):VSENSE_PVCCMCP_CPU1_SKT_VSEN
   B4  VSENSE_PVCCMCP_CPU1_SKT_VRTN   IOB4  @BASEBOARD_FAB2_LIB.BASEBOARD_FAB2(SCH_1):VSENSE_PVCCMCP_CPU1_SKT_VRTN
   D1  VSENSE_P1V8MCP_CPU1_SKT_VSEN   IOD1  @BASEBOARD_FAB2_LIB.BASEBOARD_FAB2(SCH_1):VSENSE_P1V8MCP_CPU1_SKT_VSEN
   D2  VSENSE_P1V8MCP_CPU1_SKT_VRTN   IOD2  @BASEBOARD_FAB2_LIB.BASEBOARD_FAB2(SCH_1):VSENSE_P1V8MCP_CPU1_SKT_VRTN
  C18  PVCCMCP_CPU1   IOC18  @BASEBOARD_FAB2_LIB.BASEBOARD_FAB2(SCH_1):PVCCMCP_CPU1
  C17  PVCCMCP_CPU1   IOC17  @BASEBOARD_FAB2_LIB.BASEBOARD_FAB2(SCH_1):PVCCMCP_CPU1
  C16  PVCCMCP_CPU1   IOC16  @BASEBOARD_FAB2_LIB.BASEBOARD_FAB2(SCH_1):PVCCMCP_CPU1
  C15  PVCCMCP_CPU1   IOC15  @BASEBOARD_FAB2_LIB.BASEBOARD_FAB2(SCH_1):PVCCMCP_CPU1
  C14  PVCCMCP_CPU1   IOC14  @BASEBOARD_FAB2_LIB.BASEBOARD_FAB2(SCH_1):PVCCMCP_CPU1
  C13  PVCCMCP_CPU1   IOC13  @BASEBOARD_FAB2_LIB.BASEBOARD_FAB2(SCH_1):PVCCMCP_CPU1
  C12  PVCCMCP_CPU1   IOC12  @BASEBOARD_FAB2_LIB.BASEBOARD_FAB2(SCH_1):PVCCMCP_CPU1
  C11  PVCCMCP_CPU1   IOC11  @BASEBOARD_FAB2_LIB.BASEBOARD_FAB2(SCH_1):PVCCMCP_CPU1
  C10  PVCCMCP_CPU1   IOC10  @BASEBOARD_FAB2_LIB.BASEBOARD_FAB2(SCH_1):PVCCMCP_CPU1
   C9  PVCCMCP_CPU1    IOC9  @BASEBOARD_FAB2_LIB.BASEBOARD_FAB2(SCH_1):PVCCMCP_CPU1
   C8  PVCCMCP_CPU1    IOC8  @BASEBOARD_FAB2_LIB.BASEBOARD_FAB2(SCH_1):PVCCMCP_CPU1
   C7  PVCCMCP_CPU1    IOC7  @BASEBOARD_FAB2_LIB.BASEBOARD_FAB2(SCH_1):PVCCMCP_CPU1
   C6  PVCCMCP_CPU1    IOC6  @BASEBOARD_FAB2_LIB.BASEBOARD_FAB2(SCH_1):PVCCMCP_CPU1
   C5  PVCCMCP_CPU1    IOC5  @BASEBOARD_FAB2_LIB.BASEBOARD_FAB2(SCH_1):PVCCMCP_CPU1
   C4  PVCCMCP_CPU1    IOC4  @BASEBOARD_FAB2_LIB.BASEBOARD_FAB2(SCH_1):PVCCMCP_CPU1
   C3  PVCCMCP_CPU1    IOC3  @BASEBOARD_FAB2_LIB.BASEBOARD_FAB2(SCH_1):PVCCMCP_CPU1
   C2  PVCCMCP_CPU1    IOC2  @BASEBOARD_FAB2_LIB.BASEBOARD_FAB2(SCH_1):PVCCMCP_CPU1
   C1  PVCCMCP_CPU1    IOC1  @BASEBOARD_FAB2_LIB.BASEBOARD_FAB2(SCH_1):PVCCMCP_CPU1
  B18  PVCCMCP_CPU1   IOB18  @BASEBOARD_FAB2_LIB.BASEBOARD_FAB2(SCH_1):PVCCMCP_CPU1
  B17  PVCCMCP_CPU1   IOB17  @BASEBOARD_FAB2_LIB.BASEBOARD_FAB2(SCH_1):PVCCMCP_CPU1
  B16  PVCCMCP_CPU1   IOB16  @BASEBOARD_FAB2_LIB.BASEBOARD_FAB2(SCH_1):PVCCMCP_CPU1
  B15  PVCCMCP_CPU1   IOB15  @BASEBOARD_FAB2_LIB.BASEBOARD_FAB2(SCH_1):PVCCMCP_CPU1
  B14  PVCCMCP_CPU1   IOB14  @BASEBOARD_FAB2_LIB.BASEBOARD_FAB2(SCH_1):PVCCMCP_CPU1
  B13  PVCCMCP_CPU1   IOB13  @BASEBOARD_FAB2_LIB.BASEBOARD_FAB2(SCH_1):PVCCMCP_CPU1
  B12  PVCCMCP_CPU1   IOB12  @BASEBOARD_FAB2_LIB.BASEBOARD_FAB2(SCH_1):PVCCMCP_CPU1
  B11  PVCCMCP_CPU1   IOB11  @BASEBOARD_FAB2_LIB.BASEBOARD_FAB2(SCH_1):PVCCMCP_CPU1
  B10  PVCCMCP_CPU1   IOB10  @BASEBOARD_FAB2_LIB.BASEBOARD_FAB2(SCH_1):PVCCMCP_CPU1
   B9  PVCCMCP_CPU1    IOB9  @BASEBOARD_FAB2_LIB.BASEBOARD_FAB2(SCH_1):PVCCMCP_CPU1
   B8  PVCCMCP_CPU1    IOB8  @BASEBOARD_FAB2_LIB.BASEBOARD_FAB2(SCH_1):PVCCMCP_CPU1
   B7  PVCCMCP_CPU1    IOB7  @BASEBOARD_FAB2_LIB.BASEBOARD_FAB2(SCH_1):PVCCMCP_CPU1
   B6  PVCCMCP_CPU1    IOB6  @BASEBOARD_FAB2_LIB.BASEBOARD_FAB2(SCH_1):PVCCMCP_CPU1
   B5  PVCCMCP_CPU1    IOB5  @BASEBOARD_FAB2_LIB.BASEBOARD_FAB2(SCH_1):PVCCMCP_CPU1
   B3  PVCCMCP_CPU1    IOB3  @BASEBOARD_FAB2_LIB.BASEBOARD_FAB2(SCH_1):PVCCMCP_CPU1
   B2  PVCCMCP_CPU1    IOB2  @BASEBOARD_FAB2_LIB.BASEBOARD_FAB2(SCH_1):PVCCMCP_CPU1
   B1  PVCCMCP_CPU1    IOB1  @BASEBOARD_FAB2_LIB.BASEBOARD_FAB2(SCH_1):PVCCMCP_CPU1
  A18  PVCCMCP_CPU1   IOA18  @BASEBOARD_FAB2_LIB.BASEBOARD_FAB2(SCH_1):PVCCMCP_CPU1
  A17  PVCCMCP_CPU1   IOA17  @BASEBOARD_FAB2_LIB.BASEBOARD_FAB2(SCH_1):PVCCMCP_CPU1
  A16  PVCCMCP_CPU1   IOA16  @BASEBOARD_FAB2_LIB.BASEBOARD_FAB2(SCH_1):PVCCMCP_CPU1
  A15  PVCCMCP_CPU1   IOA15  @BASEBOARD_FAB2_LIB.BASEBOARD_FAB2(SCH_1):PVCCMCP_CPU1
  A14  PVCCMCP_CPU1   IOA14  @BASEBOARD_FAB2_LIB.BASEBOARD_FAB2(SCH_1):PVCCMCP_CPU1
  A13  PVCCMCP_CPU1   IOA13  @BASEBOARD_FAB2_LIB.BASEBOARD_FAB2(SCH_1):PVCCMCP_CPU1
  A12  PVCCMCP_CPU1   IOA12  @BASEBOARD_FAB2_LIB.BASEBOARD_FAB2(SCH_1):PVCCMCP_CPU1
  A11  PVCCMCP_CPU1   IOA11  @BASEBOARD_FAB2_LIB.BASEBOARD_FAB2(SCH_1):PVCCMCP_CPU1
  A10  PVCCMCP_CPU1   IOA10  @BASEBOARD_FAB2_LIB.BASEBOARD_FAB2(SCH_1):PVCCMCP_CPU1
   A9  PVCCMCP_CPU1    IOA9  @BASEBOARD_FAB2_LIB.BASEBOARD_FAB2(SCH_1):PVCCMCP_CPU1
   A8  PVCCMCP_CPU1    IOA8  @BASEBOARD_FAB2_LIB.BASEBOARD_FAB2(SCH_1):PVCCMCP_CPU1
   A7  PVCCMCP_CPU1    IOA7  @BASEBOARD_FAB2_LIB.BASEBOARD_FAB2(SCH_1):PVCCMCP_CPU1
   A6  PVCCMCP_CPU1    IOA6  @BASEBOARD_FAB2_LIB.BASEBOARD_FAB2(SCH_1):PVCCMCP_CPU1
   A5  PVCCMCP_CPU1    IOA5  @BASEBOARD_FAB2_LIB.BASEBOARD_FAB2(SCH_1):PVCCMCP_CPU1
   A3  PVCCMCP_CPU1    IOA3  @BASEBOARD_FAB2_LIB.BASEBOARD_FAB2(SCH_1):PVCCMCP_CPU1
   A2  PVCCMCP_CPU1    IOA2  @BASEBOARD_FAB2_LIB.BASEBOARD_FAB2(SCH_1):PVCCMCP_CPU1
   A1  PVCCMCP_CPU1    IOA1  @BASEBOARD_FAB2_LIB.BASEBOARD_FAB2(SCH_1):PVCCMCP_CPU1
   F2  P1V8_MCP_CPU1   IOF2  @BASEBOARD_FAB2_LIB.BASEBOARD_FAB2(SCH_1):P1V8_MCP_CPU1
   F1  P1V8_MCP_CPU1   IOF1  @BASEBOARD_FAB2_LIB.BASEBOARD_FAB2(SCH_1):P1V8_MCP_CPU1
   E2  P1V8_MCP_CPU1   IOE2  @BASEBOARD_FAB2_LIB.BASEBOARD_FAB2(SCH_1):P1V8_MCP_CPU1
   E1  P1V8_MCP_CPU1   IOE1  @BASEBOARD_FAB2_LIB.BASEBOARD_FAB2(SCH_1):P1V8_MCP_CPU1
  F20  GND            IOF20  @BASEBOARD_FAB2_LIB.BASEBOARD_FAB2(SCH_1):GND
  F19  GND            IOF19  @BASEBOARD_FAB2_LIB.BASEBOARD_FAB2(SCH_1):GND
  F18  GND            IOF18  @BASEBOARD_FAB2_LIB.BASEBOARD_FAB2(SCH_1):GND
  F17  GND            IOF17  @BASEBOARD_FAB2_LIB.BASEBOARD_FAB2(SCH_1):GND
  F16  GND            IOF16  @BASEBOARD_FAB2_LIB.BASEBOARD_FAB2(SCH_1):GND
  F15  GND            IOF15  @BASEBOARD_FAB2_LIB.BASEBOARD_FAB2(SCH_1):GND
  F14  GND            IOF14  @BASEBOARD_FAB2_LIB.BASEBOARD_FAB2(SCH_1):GND
  F13  GND            IOF13  @BASEBOARD_FAB2_LIB.BASEBOARD_FAB2(SCH_1):GND
  F12  GND            IOF12  @BASEBOARD_FAB2_LIB.BASEBOARD_FAB2(SCH_1):GND
  F11  GND            IOF11  @BASEBOARD_FAB2_LIB.BASEBOARD_FAB2(SCH_1):GND
  F10  GND            IOF10  @BASEBOARD_FAB2_LIB.BASEBOARD_FAB2(SCH_1):GND
   F9  GND             IOF9  @BASEBOARD_FAB2_LIB.BASEBOARD_FAB2(SCH_1):GND
   F8  GND             IOF8  @BASEBOARD_FAB2_LIB.BASEBOARD_FAB2(SCH_1):GND
   F7  GND             IOF7  @BASEBOARD_FAB2_LIB.BASEBOARD_FAB2(SCH_1):GND
   F6  GND             IOF6  @BASEBOARD_FAB2_LIB.BASEBOARD_FAB2(SCH_1):GND
   F4  GND             IOF4  @BASEBOARD_FAB2_LIB.BASEBOARD_FAB2(SCH_1):GND
   F3  GND             IOF3  @BASEBOARD_FAB2_LIB.BASEBOARD_FAB2(SCH_1):GND
  E20  GND            IOE20  @BASEBOARD_FAB2_LIB.BASEBOARD_FAB2(SCH_1):GND
  E19  GND            IOE19  @BASEBOARD_FAB2_LIB.BASEBOARD_FAB2(SCH_1):GND
  E18  GND            IOE18  @BASEBOARD_FAB2_LIB.BASEBOARD_FAB2(SCH_1):GND
  E17  GND            IOE17  @BASEBOARD_FAB2_LIB.BASEBOARD_FAB2(SCH_1):GND
  E16  GND            IOE16  @BASEBOARD_FAB2_LIB.BASEBOARD_FAB2(SCH_1):GND
  E15  GND            IOE15  @BASEBOARD_FAB2_LIB.BASEBOARD_FAB2(SCH_1):GND
  E14  GND            IOE14  @BASEBOARD_FAB2_LIB.BASEBOARD_FAB2(SCH_1):GND
  E13  GND            IOE13  @BASEBOARD_FAB2_LIB.BASEBOARD_FAB2(SCH_1):GND
  E12  GND            IOE12  @BASEBOARD_FAB2_LIB.BASEBOARD_FAB2(SCH_1):GND
  E11  GND            IOE11  @BASEBOARD_FAB2_LIB.BASEBOARD_FAB2(SCH_1):GND
  E10  GND            IOE10  @BASEBOARD_FAB2_LIB.BASEBOARD_FAB2(SCH_1):GND
   E9  GND             IOE9  @BASEBOARD_FAB2_LIB.BASEBOARD_FAB2(SCH_1):GND
   E8  GND             IOE8  @BASEBOARD_FAB2_LIB.BASEBOARD_FAB2(SCH_1):GND
   E7  GND             IOE7  @BASEBOARD_FAB2_LIB.BASEBOARD_FAB2(SCH_1):GND
   E6  GND             IOE6  @BASEBOARD_FAB2_LIB.BASEBOARD_FAB2(SCH_1):GND
   E4  GND             IOE4  @BASEBOARD_FAB2_LIB.BASEBOARD_FAB2(SCH_1):GND
   E3  GND             IOE3  @BASEBOARD_FAB2_LIB.BASEBOARD_FAB2(SCH_1):GND
  D20  GND            IOD20  @BASEBOARD_FAB2_LIB.BASEBOARD_FAB2(SCH_1):GND
  D19  GND            IOD19  @BASEBOARD_FAB2_LIB.BASEBOARD_FAB2(SCH_1):GND
  D18  GND            IOD18  @BASEBOARD_FAB2_LIB.BASEBOARD_FAB2(SCH_1):GND
  D17  GND            IOD17  @BASEBOARD_FAB2_LIB.BASEBOARD_FAB2(SCH_1):GND
  D16  GND            IOD16  @BASEBOARD_FAB2_LIB.BASEBOARD_FAB2(SCH_1):GND
  D15  GND            IOD15  @BASEBOARD_FAB2_LIB.BASEBOARD_FAB2(SCH_1):GND
  D14  GND            IOD14  @BASEBOARD_FAB2_LIB.BASEBOARD_FAB2(SCH_1):GND
  D13  GND            IOD13  @BASEBOARD_FAB2_LIB.BASEBOARD_FAB2(SCH_1):GND
  D12  GND            IOD12  @BASEBOARD_FAB2_LIB.BASEBOARD_FAB2(SCH_1):GND
  D11  GND            IOD11  @BASEBOARD_FAB2_LIB.BASEBOARD_FAB2(SCH_1):GND
  D10  GND            IOD10  @BASEBOARD_FAB2_LIB.BASEBOARD_FAB2(SCH_1):GND
   D9  GND             IOD9  @BASEBOARD_FAB2_LIB.BASEBOARD_FAB2(SCH_1):GND
   D8  GND             IOD8  @BASEBOARD_FAB2_LIB.BASEBOARD_FAB2(SCH_1):GND
   D7  GND             IOD7  @BASEBOARD_FAB2_LIB.BASEBOARD_FAB2(SCH_1):GND
   D6  GND             IOD6  @BASEBOARD_FAB2_LIB.BASEBOARD_FAB2(SCH_1):GND
   D5  GND             IOD5  @BASEBOARD_FAB2_LIB.BASEBOARD_FAB2(SCH_1):GND
   D4  GND             IOD4  @BASEBOARD_FAB2_LIB.BASEBOARD_FAB2(SCH_1):GND
   D3  GND             IOD3  @BASEBOARD_FAB2_LIB.BASEBOARD_FAB2(SCH_1):GND
  C20  GND            IOC20  @BASEBOARD_FAB2_LIB.BASEBOARD_FAB2(SCH_1):GND
  C19  GND            IOC19  @BASEBOARD_FAB2_LIB.BASEBOARD_FAB2(SCH_1):GND
  B20  GND            IOB20  @BASEBOARD_FAB2_LIB.BASEBOARD_FAB2(SCH_1):GND
  B19  GND            IOB19  @BASEBOARD_FAB2_LIB.BASEBOARD_FAB2(SCH_1):GND
  A20  GND            IOA20  @BASEBOARD_FAB2_LIB.BASEBOARD_FAB2(SCH_1):GND
  A19  GND            IOA19  @BASEBOARD_FAB2_LIB.BASEBOARD_FAB2(SCH_1):GND
   E5  CLK_322M_156M_CPU1_OSC_VRM_DP   IOE5  @BASEBOARD_FAB2_LIB.BASEBOARD_FAB2(SCH_1):CLK_322M_156M_CPU1_OSC_VRM_DP
   F5  CLK_322M_156M_CPU1_OSC_VRM_DN   IOF5  @BASEBOARD_FAB2_LIB.BASEBOARD_FAB2(SCH_1):CLK_322M_156M_CPU1_OSC_VRM_DN

SCONN288_H44441004_PIP  I260  J4G1   [SCONN288_H44441004_PIP-SCONN,HA]
   77  PVTT_ABC       VTT<1>  @BASEBOARD_FAB2_LIB.BASEBOARD_FAB2(SCH_1):PVTT_ABC
  221  PVTT_ABC       VTT<0>  @BASEBOARD_FAB2_LIB.BASEBOARD_FAB2(SCH_1):PVTT_ABC
  142  PVPP_ABC       VPP<4>  @BASEBOARD_FAB2_LIB.BASEBOARD_FAB2(SCH_1):PVPP_ABC
  143  PVPP_ABC       VPP<3>  @BASEBOARD_FAB2_LIB.BASEBOARD_FAB2(SCH_1):PVPP_ABC
  288  PVPP_ABC       VPP<2>  @BASEBOARD_FAB2_LIB.BASEBOARD_FAB2(SCH_1):PVPP_ABC
  286  PVPP_ABC       VPP<1>  @BASEBOARD_FAB2_LIB.BASEBOARD_FAB2(SCH_1):PVPP_ABC
  287  PVPP_ABC       VPP<0>  @BASEBOARD_FAB2_LIB.BASEBOARD_FAB2(SCH_1):PVPP_ABC
   59  PVDDQ_ABC      VDD<25>  @BASEBOARD_FAB2_LIB.BASEBOARD_FAB2(SCH_1):PVDDQ_ABC
   61  PVDDQ_ABC      VDD<24>  @BASEBOARD_FAB2_LIB.BASEBOARD_FAB2(SCH_1):PVDDQ_ABC
   64  PVDDQ_ABC      VDD<23>  @BASEBOARD_FAB2_LIB.BASEBOARD_FAB2(SCH_1):PVDDQ_ABC
   67  PVDDQ_ABC      VDD<22>  @BASEBOARD_FAB2_LIB.BASEBOARD_FAB2(SCH_1):PVDDQ_ABC
   70  PVDDQ_ABC      VDD<21>  @BASEBOARD_FAB2_LIB.BASEBOARD_FAB2(SCH_1):PVDDQ_ABC
   73  PVDDQ_ABC      VDD<20>  @BASEBOARD_FAB2_LIB.BASEBOARD_FAB2(SCH_1):PVDDQ_ABC
   76  PVDDQ_ABC      VDD<19>  @BASEBOARD_FAB2_LIB.BASEBOARD_FAB2(SCH_1):PVDDQ_ABC
   80  PVDDQ_ABC      VDD<18>  @BASEBOARD_FAB2_LIB.BASEBOARD_FAB2(SCH_1):PVDDQ_ABC
   83  PVDDQ_ABC      VDD<17>  @BASEBOARD_FAB2_LIB.BASEBOARD_FAB2(SCH_1):PVDDQ_ABC
   85  PVDDQ_ABC      VDD<16>  @BASEBOARD_FAB2_LIB.BASEBOARD_FAB2(SCH_1):PVDDQ_ABC
   88  PVDDQ_ABC      VDD<15>  @BASEBOARD_FAB2_LIB.BASEBOARD_FAB2(SCH_1):PVDDQ_ABC
   90  PVDDQ_ABC      VDD<14>  @BASEBOARD_FAB2_LIB.BASEBOARD_FAB2(SCH_1):PVDDQ_ABC
   92  PVDDQ_ABC      VDD<13>  @BASEBOARD_FAB2_LIB.BASEBOARD_FAB2(SCH_1):PVDDQ_ABC
  204  PVDDQ_ABC      VDD<12>  @BASEBOARD_FAB2_LIB.BASEBOARD_FAB2(SCH_1):PVDDQ_ABC
  206  PVDDQ_ABC      VDD<11>  @BASEBOARD_FAB2_LIB.BASEBOARD_FAB2(SCH_1):PVDDQ_ABC
  209  PVDDQ_ABC      VDD<10>  @BASEBOARD_FAB2_LIB.BASEBOARD_FAB2(SCH_1):PVDDQ_ABC
  212  PVDDQ_ABC      VDD<9>  @BASEBOARD_FAB2_LIB.BASEBOARD_FAB2(SCH_1):PVDDQ_ABC
  215  PVDDQ_ABC      VDD<8>  @BASEBOARD_FAB2_LIB.BASEBOARD_FAB2(SCH_1):PVDDQ_ABC
  217  PVDDQ_ABC      VDD<7>  @BASEBOARD_FAB2_LIB.BASEBOARD_FAB2(SCH_1):PVDDQ_ABC
  220  PVDDQ_ABC      VDD<6>  @BASEBOARD_FAB2_LIB.BASEBOARD_FAB2(SCH_1):PVDDQ_ABC
  223  PVDDQ_ABC      VDD<5>  @BASEBOARD_FAB2_LIB.BASEBOARD_FAB2(SCH_1):PVDDQ_ABC
  226  PVDDQ_ABC      VDD<4>  @BASEBOARD_FAB2_LIB.BASEBOARD_FAB2(SCH_1):PVDDQ_ABC
  229  PVDDQ_ABC      VDD<3>  @BASEBOARD_FAB2_LIB.BASEBOARD_FAB2(SCH_1):PVDDQ_ABC
  231  PVDDQ_ABC      VDD<2>  @BASEBOARD_FAB2_LIB.BASEBOARD_FAB2(SCH_1):PVDDQ_ABC
  233  PVDDQ_ABC      VDD<1>  @BASEBOARD_FAB2_LIB.BASEBOARD_FAB2(SCH_1):PVDDQ_ABC
  236  PVDDQ_ABC      VDD<0>  @BASEBOARD_FAB2_LIB.BASEBOARD_FAB2(SCH_1):PVDDQ_ABC
    1  P12V_NVDIMM_ABC  12V<1>  @BASEBOARD_FAB2_LIB.BASEBOARD_FAB2(SCH_1):P12V_NVDIMM_ABC
  145  P12V_NVDIMM_ABC  12V<0>  @BASEBOARD_FAB2_LIB.BASEBOARD_FAB2(SCH_1):P12V_NVDIMM_ABC

SCONN288_H44441004_PIP  I259  J4G1   [SCONN288_H44441004_PIP-SCONN,HA]
    2  GND            VSS<93>  @BASEBOARD_FAB2_LIB.BASEBOARD_FAB2(SCH_1):GND
    4  GND            VSS<92>  @BASEBOARD_FAB2_LIB.BASEBOARD_FAB2(SCH_1):GND
    6  GND            VSS<91>  @BASEBOARD_FAB2_LIB.BASEBOARD_FAB2(SCH_1):GND
    9  GND            VSS<90>  @BASEBOARD_FAB2_LIB.BASEBOARD_FAB2(SCH_1):GND
   11  GND            VSS<89>  @BASEBOARD_FAB2_LIB.BASEBOARD_FAB2(SCH_1):GND
   13  GND            VSS<88>  @BASEBOARD_FAB2_LIB.BASEBOARD_FAB2(SCH_1):GND
   15  GND            VSS<87>  @BASEBOARD_FAB2_LIB.BASEBOARD_FAB2(SCH_1):GND
   17  GND            VSS<86>  @BASEBOARD_FAB2_LIB.BASEBOARD_FAB2(SCH_1):GND
   20  GND            VSS<85>  @BASEBOARD_FAB2_LIB.BASEBOARD_FAB2(SCH_1):GND
   22  GND            VSS<84>  @BASEBOARD_FAB2_LIB.BASEBOARD_FAB2(SCH_1):GND
   24  GND            VSS<83>  @BASEBOARD_FAB2_LIB.BASEBOARD_FAB2(SCH_1):GND
   26  GND            VSS<82>  @BASEBOARD_FAB2_LIB.BASEBOARD_FAB2(SCH_1):GND
   28  GND            VSS<81>  @BASEBOARD_FAB2_LIB.BASEBOARD_FAB2(SCH_1):GND
   31  GND            VSS<80>  @BASEBOARD_FAB2_LIB.BASEBOARD_FAB2(SCH_1):GND
   33  GND            VSS<79>  @BASEBOARD_FAB2_LIB.BASEBOARD_FAB2(SCH_1):GND
   35  GND            VSS<78>  @BASEBOARD_FAB2_LIB.BASEBOARD_FAB2(SCH_1):GND
   37  GND            VSS<77>  @BASEBOARD_FAB2_LIB.BASEBOARD_FAB2(SCH_1):GND
   39  GND            VSS<76>  @BASEBOARD_FAB2_LIB.BASEBOARD_FAB2(SCH_1):GND
   42  GND            VSS<75>  @BASEBOARD_FAB2_LIB.BASEBOARD_FAB2(SCH_1):GND
   44  GND            VSS<74>  @BASEBOARD_FAB2_LIB.BASEBOARD_FAB2(SCH_1):GND
   46  GND            VSS<73>  @BASEBOARD_FAB2_LIB.BASEBOARD_FAB2(SCH_1):GND
   48  GND            VSS<72>  @BASEBOARD_FAB2_LIB.BASEBOARD_FAB2(SCH_1):GND
   50  GND            VSS<71>  @BASEBOARD_FAB2_LIB.BASEBOARD_FAB2(SCH_1):GND
   53  GND            VSS<70>  @BASEBOARD_FAB2_LIB.BASEBOARD_FAB2(SCH_1):GND
   55  GND            VSS<69>  @BASEBOARD_FAB2_LIB.BASEBOARD_FAB2(SCH_1):GND
   57  GND            VSS<68>  @BASEBOARD_FAB2_LIB.BASEBOARD_FAB2(SCH_1):GND
   94  GND            VSS<67>  @BASEBOARD_FAB2_LIB.BASEBOARD_FAB2(SCH_1):GND
   96  GND            VSS<66>  @BASEBOARD_FAB2_LIB.BASEBOARD_FAB2(SCH_1):GND
   98  GND            VSS<65>  @BASEBOARD_FAB2_LIB.BASEBOARD_FAB2(SCH_1):GND
  101  GND            VSS<64>  @BASEBOARD_FAB2_LIB.BASEBOARD_FAB2(SCH_1):GND
  103  GND            VSS<63>  @BASEBOARD_FAB2_LIB.BASEBOARD_FAB2(SCH_1):GND
  105  GND            VSS<62>  @BASEBOARD_FAB2_LIB.BASEBOARD_FAB2(SCH_1):GND
  107  GND            VSS<61>  @BASEBOARD_FAB2_LIB.BASEBOARD_FAB2(SCH_1):GND
  109  GND            VSS<60>  @BASEBOARD_FAB2_LIB.BASEBOARD_FAB2(SCH_1):GND
  112  GND            VSS<59>  @BASEBOARD_FAB2_LIB.BASEBOARD_FAB2(SCH_1):GND
  114  GND            VSS<58>  @BASEBOARD_FAB2_LIB.BASEBOARD_FAB2(SCH_1):GND
  116  GND            VSS<57>  @BASEBOARD_FAB2_LIB.BASEBOARD_FAB2(SCH_1):GND
  118  GND            VSS<56>  @BASEBOARD_FAB2_LIB.BASEBOARD_FAB2(SCH_1):GND
  120  GND            VSS<55>  @BASEBOARD_FAB2_LIB.BASEBOARD_FAB2(SCH_1):GND
  123  GND            VSS<54>  @BASEBOARD_FAB2_LIB.BASEBOARD_FAB2(SCH_1):GND
  125  GND            VSS<53>  @BASEBOARD_FAB2_LIB.BASEBOARD_FAB2(SCH_1):GND
  127  GND            VSS<52>  @BASEBOARD_FAB2_LIB.BASEBOARD_FAB2(SCH_1):GND
  129  GND            VSS<51>  @BASEBOARD_FAB2_LIB.BASEBOARD_FAB2(SCH_1):GND
  131  GND            VSS<50>  @BASEBOARD_FAB2_LIB.BASEBOARD_FAB2(SCH_1):GND
  134  GND            VSS<49>  @BASEBOARD_FAB2_LIB.BASEBOARD_FAB2(SCH_1):GND
  136  GND            VSS<48>  @BASEBOARD_FAB2_LIB.BASEBOARD_FAB2(SCH_1):GND
  138  GND            VSS<47>  @BASEBOARD_FAB2_LIB.BASEBOARD_FAB2(SCH_1):GND
  147  GND            VSS<46>  @BASEBOARD_FAB2_LIB.BASEBOARD_FAB2(SCH_1):GND
  149  GND            VSS<45>  @BASEBOARD_FAB2_LIB.BASEBOARD_FAB2(SCH_1):GND
  151  GND            VSS<44>  @BASEBOARD_FAB2_LIB.BASEBOARD_FAB2(SCH_1):GND
  154  GND            VSS<43>  @BASEBOARD_FAB2_LIB.BASEBOARD_FAB2(SCH_1):GND
  156  GND            VSS<42>  @BASEBOARD_FAB2_LIB.BASEBOARD_FAB2(SCH_1):GND
  158  GND            VSS<41>  @BASEBOARD_FAB2_LIB.BASEBOARD_FAB2(SCH_1):GND
  160  GND            VSS<40>  @BASEBOARD_FAB2_LIB.BASEBOARD_FAB2(SCH_1):GND
  162  GND            VSS<39>  @BASEBOARD_FAB2_LIB.BASEBOARD_FAB2(SCH_1):GND
  165  GND            VSS<38>  @BASEBOARD_FAB2_LIB.BASEBOARD_FAB2(SCH_1):GND
  167  GND            VSS<37>  @BASEBOARD_FAB2_LIB.BASEBOARD_FAB2(SCH_1):GND
  169  GND            VSS<36>  @BASEBOARD_FAB2_LIB.BASEBOARD_FAB2(SCH_1):GND
  171  GND            VSS<35>  @BASEBOARD_FAB2_LIB.BASEBOARD_FAB2(SCH_1):GND
  173  GND            VSS<34>  @BASEBOARD_FAB2_LIB.BASEBOARD_FAB2(SCH_1):GND
  176  GND            VSS<33>  @BASEBOARD_FAB2_LIB.BASEBOARD_FAB2(SCH_1):GND
  178  GND            VSS<32>  @BASEBOARD_FAB2_LIB.BASEBOARD_FAB2(SCH_1):GND
  180  GND            VSS<31>  @BASEBOARD_FAB2_LIB.BASEBOARD_FAB2(SCH_1):GND
  182  GND            VSS<30>  @BASEBOARD_FAB2_LIB.BASEBOARD_FAB2(SCH_1):GND
  184  GND            VSS<29>  @BASEBOARD_FAB2_LIB.BASEBOARD_FAB2(SCH_1):GND
  187  GND            VSS<28>  @BASEBOARD_FAB2_LIB.BASEBOARD_FAB2(SCH_1):GND
  189  GND            VSS<27>  @BASEBOARD_FAB2_LIB.BASEBOARD_FAB2(SCH_1):GND
  191  GND            VSS<26>  @BASEBOARD_FAB2_LIB.BASEBOARD_FAB2(SCH_1):GND
  193  GND            VSS<25>  @BASEBOARD_FAB2_LIB.BASEBOARD_FAB2(SCH_1):GND
  195  GND            VSS<24>  @BASEBOARD_FAB2_LIB.BASEBOARD_FAB2(SCH_1):GND
  198  GND            VSS<23>  @BASEBOARD_FAB2_LIB.BASEBOARD_FAB2(SCH_1):GND
  200  GND            VSS<22>  @BASEBOARD_FAB2_LIB.BASEBOARD_FAB2(SCH_1):GND
  202  GND            VSS<21>  @BASEBOARD_FAB2_LIB.BASEBOARD_FAB2(SCH_1):GND
  239  GND            VSS<20>  @BASEBOARD_FAB2_LIB.BASEBOARD_FAB2(SCH_1):GND
  241  GND            VSS<19>  @BASEBOARD_FAB2_LIB.BASEBOARD_FAB2(SCH_1):GND
  243  GND            VSS<18>  @BASEBOARD_FAB2_LIB.BASEBOARD_FAB2(SCH_1):GND
  246  GND            VSS<17>  @BASEBOARD_FAB2_LIB.BASEBOARD_FAB2(SCH_1):GND
  248  GND            VSS<16>  @BASEBOARD_FAB2_LIB.BASEBOARD_FAB2(SCH_1):GND
  250  GND            VSS<15>  @BASEBOARD_FAB2_LIB.BASEBOARD_FAB2(SCH_1):GND
  252  GND            VSS<14>  @BASEBOARD_FAB2_LIB.BASEBOARD_FAB2(SCH_1):GND
  254  GND            VSS<13>  @BASEBOARD_FAB2_LIB.BASEBOARD_FAB2(SCH_1):GND
  257  GND            VSS<12>  @BASEBOARD_FAB2_LIB.BASEBOARD_FAB2(SCH_1):GND
  259  GND            VSS<11>  @BASEBOARD_FAB2_LIB.BASEBOARD_FAB2(SCH_1):GND
  261  GND            VSS<10>  @BASEBOARD_FAB2_LIB.BASEBOARD_FAB2(SCH_1):GND
  263  GND            VSS<9>  @BASEBOARD_FAB2_LIB.BASEBOARD_FAB2(SCH_1):GND
  265  GND            VSS<8>  @BASEBOARD_FAB2_LIB.BASEBOARD_FAB2(SCH_1):GND
  268  GND            VSS<7>  @BASEBOARD_FAB2_LIB.BASEBOARD_FAB2(SCH_1):GND
  270  GND            VSS<6>  @BASEBOARD_FAB2_LIB.BASEBOARD_FAB2(SCH_1):GND
  272  GND            VSS<5>  @BASEBOARD_FAB2_LIB.BASEBOARD_FAB2(SCH_1):GND
  274  GND            VSS<4>  @BASEBOARD_FAB2_LIB.BASEBOARD_FAB2(SCH_1):GND
  276  GND            VSS<3>  @BASEBOARD_FAB2_LIB.BASEBOARD_FAB2(SCH_1):GND
  279  GND            VSS<2>  @BASEBOARD_FAB2_LIB.BASEBOARD_FAB2(SCH_1):GND
  281  GND            VSS<1>  @BASEBOARD_FAB2_LIB.BASEBOARD_FAB2(SCH_1):GND
  283  GND            VSS<0>  @BASEBOARD_FAB2_LIB.BASEBOARD_FAB2(SCH_1):GND

SCONN288_H44441004_PIP  I2   J4G1   [SCONN288_H44441004_PIP-SCONN,HA]
    7  M_A_DQS_DP<9>  DQS9P  @BASEBOARD_FAB2_LIB.BASEBOARD_FAB2(SCH_1):M_A_DQS_DP<9>
  197  M_A_DQS_DP<8>  DQS8P  @BASEBOARD_FAB2_LIB.BASEBOARD_FAB2(SCH_1):M_A_DQS_DP<8>
  278  M_A_DQS_DP<7>  DQS7P  @BASEBOARD_FAB2_LIB.BASEBOARD_FAB2(SCH_1):M_A_DQS_DP<7>
  267  M_A_DQS_DP<6>  DQS6P  @BASEBOARD_FAB2_LIB.BASEBOARD_FAB2(SCH_1):M_A_DQS_DP<6>
  256  M_A_DQS_DP<5>  DQS5P  @BASEBOARD_FAB2_LIB.BASEBOARD_FAB2(SCH_1):M_A_DQS_DP<5>
  245  M_A_DQS_DP<4>  DQS4P  @BASEBOARD_FAB2_LIB.BASEBOARD_FAB2(SCH_1):M_A_DQS_DP<4>
  186  M_A_DQS_DP<3>  DQS3P  @BASEBOARD_FAB2_LIB.BASEBOARD_FAB2(SCH_1):M_A_DQS_DP<3>
  175  M_A_DQS_DP<2>  DQS2P  @BASEBOARD_FAB2_LIB.BASEBOARD_FAB2(SCH_1):M_A_DQS_DP<2>
  164  M_A_DQS_DP<1>  DQS1P  @BASEBOARD_FAB2_LIB.BASEBOARD_FAB2(SCH_1):M_A_DQS_DP<1>
   51  M_A_DQS_DP<17>  DQS17P  @BASEBOARD_FAB2_LIB.BASEBOARD_FAB2(SCH_1):M_A_DQS_DP<17>
  132  M_A_DQS_DP<16>  DQS16P  @BASEBOARD_FAB2_LIB.BASEBOARD_FAB2(SCH_1):M_A_DQS_DP<16>
  121  M_A_DQS_DP<15>  DQS15P  @BASEBOARD_FAB2_LIB.BASEBOARD_FAB2(SCH_1):M_A_DQS_DP<15>
  110  M_A_DQS_DP<14>  DQS14P  @BASEBOARD_FAB2_LIB.BASEBOARD_FAB2(SCH_1):M_A_DQS_DP<14>
   99  M_A_DQS_DP<13>  DQS13P  @BASEBOARD_FAB2_LIB.BASEBOARD_FAB2(SCH_1):M_A_DQS_DP<13>
   40  M_A_DQS_DP<12>  DQS12P  @BASEBOARD_FAB2_LIB.BASEBOARD_FAB2(SCH_1):M_A_DQS_DP<12>
   29  M_A_DQS_DP<11>  DQS11P  @BASEBOARD_FAB2_LIB.BASEBOARD_FAB2(SCH_1):M_A_DQS_DP<11>
   18  M_A_DQS_DP<10>  DQS10P  @BASEBOARD_FAB2_LIB.BASEBOARD_FAB2(SCH_1):M_A_DQS_DP<10>
  153  M_A_DQS_DP<0>  DQS0P  @BASEBOARD_FAB2_LIB.BASEBOARD_FAB2(SCH_1):M_A_DQS_DP<0>
    8  M_A_DQS_DN<9>  DQS9N  @BASEBOARD_FAB2_LIB.BASEBOARD_FAB2(SCH_1):M_A_DQS_DN<9>
  196  M_A_DQS_DN<8>  DQS8N  @BASEBOARD_FAB2_LIB.BASEBOARD_FAB2(SCH_1):M_A_DQS_DN<8>
  277  M_A_DQS_DN<7>  DQS7N  @BASEBOARD_FAB2_LIB.BASEBOARD_FAB2(SCH_1):M_A_DQS_DN<7>
  266  M_A_DQS_DN<6>  DQS6N  @BASEBOARD_FAB2_LIB.BASEBOARD_FAB2(SCH_1):M_A_DQS_DN<6>
  255  M_A_DQS_DN<5>  DQS5N  @BASEBOARD_FAB2_LIB.BASEBOARD_FAB2(SCH_1):M_A_DQS_DN<5>
  244  M_A_DQS_DN<4>  DQS4N  @BASEBOARD_FAB2_LIB.BASEBOARD_FAB2(SCH_1):M_A_DQS_DN<4>
  185  M_A_DQS_DN<3>  DQS3N  @BASEBOARD_FAB2_LIB.BASEBOARD_FAB2(SCH_1):M_A_DQS_DN<3>
  174  M_A_DQS_DN<2>  DQS2N  @BASEBOARD_FAB2_LIB.BASEBOARD_FAB2(SCH_1):M_A_DQS_DN<2>
  163  M_A_DQS_DN<1>  DQS1N  @BASEBOARD_FAB2_LIB.BASEBOARD_FAB2(SCH_1):M_A_DQS_DN<1>
   52  M_A_DQS_DN<17>  DQS17N  @BASEBOARD_FAB2_LIB.BASEBOARD_FAB2(SCH_1):M_A_DQS_DN<17>
  133  M_A_DQS_DN<16>  DQS16N  @BASEBOARD_FAB2_LIB.BASEBOARD_FAB2(SCH_1):M_A_DQS_DN<16>
  122  M_A_DQS_DN<15>  DQS15N  @BASEBOARD_FAB2_LIB.BASEBOARD_FAB2(SCH_1):M_A_DQS_DN<15>
  111  M_A_DQS_DN<14>  DQS14N  @BASEBOARD_FAB2_LIB.BASEBOARD_FAB2(SCH_1):M_A_DQS_DN<14>
  100  M_A_DQS_DN<13>  DQS13N  @BASEBOARD_FAB2_LIB.BASEBOARD_FAB2(SCH_1):M_A_DQS_DN<13>
   41  M_A_DQS_DN<12>  DQS12N  @BASEBOARD_FAB2_LIB.BASEBOARD_FAB2(SCH_1):M_A_DQS_DN<12>
   30  M_A_DQS_DN<11>  DQS11N  @BASEBOARD_FAB2_LIB.BASEBOARD_FAB2(SCH_1):M_A_DQS_DN<11>
   19  M_A_DQS_DN<10>  DQS10N  @BASEBOARD_FAB2_LIB.BASEBOARD_FAB2(SCH_1):M_A_DQS_DN<10>
  152  M_A_DQS_DN<0>  DQS0N  @BASEBOARD_FAB2_LIB.BASEBOARD_FAB2(SCH_1):M_A_DQS_DN<0>

SCONN288_H44441004_PIP  I1   J4G1   [SCONN288_H44441004_PIP-SCONN,HA]
  144  TP_CH_A_DIMM_A0_RFU_2  RFU<2>  @BASEBOARD_FAB2_LIB.BASEBOARD_FAB2(SCH_1):TP_CH_A_DIMM_A0_RFU_2
  227  TP_CH_A_DIMM_A0_RFU_1  RFU<1>  @BASEBOARD_FAB2_LIB.BASEBOARD_FAB2(SCH_1):TP_CH_A_DIMM_A0_RFU_1
  205  TP_CH_A_DIMM_A0_RFU_0  RFU<0>  @BASEBOARD_FAB2_LIB.BASEBOARD_FAB2(SCH_1):TP_CH_A_DIMM_A0_RFU_0
  285  SMB_DDR_ABC_VPP_SDA    SDA  @BASEBOARD_FAB2_LIB.BASEBOARD_FAB2(SCH_1):SMB_DDR_ABC_VPP_SDA
  141  SMB_DDR_ABC_VPP_SCL    SCL  @BASEBOARD_FAB2_LIB.BASEBOARD_FAB2(SCH_1):SMB_DDR_ABC_VPP_SCL
  284  PVPP_ABC       VDDSPD  @BASEBOARD_FAB2_LIB.BASEBOARD_FAB2(SCH_1):PVPP_ABC
  146  M_A_VREF       VREFCA  @BASEBOARD_FAB2_LIB.BASEBOARD_FAB2(SCH_1):M_A_VREF
  222  M_A_PAR          PAR  @BASEBOARD_FAB2_LIB.BASEBOARD_FAB2(SCH_1):M_A_PAR
   91  M_A_ODT<1>     ODT<1>  @BASEBOARD_FAB2_LIB.BASEBOARD_FAB2(SCH_1):M_A_ODT<1>
   87  M_A_ODT<0>     ODT<0>  @BASEBOARD_FAB2_LIB.BASEBOARD_FAB2(SCH_1):M_A_ODT<0>
   66  M_A_MA<9>         A9  @BASEBOARD_FAB2_LIB.BASEBOARD_FAB2(SCH_1):M_A_MA<9>
   68  M_A_MA<8>         A8  @BASEBOARD_FAB2_LIB.BASEBOARD_FAB2(SCH_1):M_A_MA<8>
  211  M_A_MA<7>         A7  @BASEBOARD_FAB2_LIB.BASEBOARD_FAB2(SCH_1):M_A_MA<7>
   69  M_A_MA<6>         A6  @BASEBOARD_FAB2_LIB.BASEBOARD_FAB2(SCH_1):M_A_MA<6>
  213  M_A_MA<5>         A5  @BASEBOARD_FAB2_LIB.BASEBOARD_FAB2(SCH_1):M_A_MA<5>
  214  M_A_MA<4>         A4  @BASEBOARD_FAB2_LIB.BASEBOARD_FAB2(SCH_1):M_A_MA<4>
   71  M_A_MA<3>         A3  @BASEBOARD_FAB2_LIB.BASEBOARD_FAB2(SCH_1):M_A_MA<3>
  216  M_A_MA<2>         A2  @BASEBOARD_FAB2_LIB.BASEBOARD_FAB2(SCH_1):M_A_MA<2>
   72  M_A_MA<1>         A1  @BASEBOARD_FAB2_LIB.BASEBOARD_FAB2(SCH_1):M_A_MA<1>
  234  M_A_MA<17>       A17  @BASEBOARD_FAB2_LIB.BASEBOARD_FAB2(SCH_1):M_A_MA<17>
   82  M_A_MA<16>     A16_RAS_N  @BASEBOARD_FAB2_LIB.BASEBOARD_FAB2(SCH_1):M_A_MA<16>
   86  M_A_MA<15>     A15_CAS_N  @BASEBOARD_FAB2_LIB.BASEBOARD_FAB2(SCH_1):M_A_MA<15>
  228  M_A_MA<14>     A14_WE_N  @BASEBOARD_FAB2_LIB.BASEBOARD_FAB2(SCH_1):M_A_MA<14>
  232  M_A_MA<13>       A13  @BASEBOARD_FAB2_LIB.BASEBOARD_FAB2(SCH_1):M_A_MA<13>
   65  M_A_MA<12>       A12  @BASEBOARD_FAB2_LIB.BASEBOARD_FAB2(SCH_1):M_A_MA<12>
  210  M_A_MA<11>       A11  @BASEBOARD_FAB2_LIB.BASEBOARD_FAB2(SCH_1):M_A_MA<11>
  225  M_A_MA<10>       A10  @BASEBOARD_FAB2_LIB.BASEBOARD_FAB2(SCH_1):M_A_MA<10>
   79  M_A_MA<0>         A0  @BASEBOARD_FAB2_LIB.BASEBOARD_FAB2(SCH_1):M_A_MA<0>
   54  M_A_ECC<7>     CB<6>  @BASEBOARD_FAB2_LIB.BASEBOARD_FAB2(SCH_1):M_A_ECC<7>
  199  M_A_ECC<6>     CB<7>  @BASEBOARD_FAB2_LIB.BASEBOARD_FAB2(SCH_1):M_A_ECC<6>
   47  M_A_ECC<5>     CB<4>  @BASEBOARD_FAB2_LIB.BASEBOARD_FAB2(SCH_1):M_A_ECC<5>
  192  M_A_ECC<4>     CB<5>  @BASEBOARD_FAB2_LIB.BASEBOARD_FAB2(SCH_1):M_A_ECC<4>
   56  M_A_ECC<3>     CB<2>  @BASEBOARD_FAB2_LIB.BASEBOARD_FAB2(SCH_1):M_A_ECC<3>
  201  M_A_ECC<2>     CB<3>  @BASEBOARD_FAB2_LIB.BASEBOARD_FAB2(SCH_1):M_A_ECC<2>
   49  M_A_ECC<1>     CB<0>  @BASEBOARD_FAB2_LIB.BASEBOARD_FAB2(SCH_1):M_A_ECC<1>
  194  M_A_ECC<0>     CB<1>  @BASEBOARD_FAB2_LIB.BASEBOARD_FAB2(SCH_1):M_A_ECC<0>
   16  M_A_DQ<9>      DQ<8>  @BASEBOARD_FAB2_LIB.BASEBOARD_FAB2(SCH_1):M_A_DQ<9>
  161  M_A_DQ<8>      DQ<9>  @BASEBOARD_FAB2_LIB.BASEBOARD_FAB2(SCH_1):M_A_DQ<8>
   10  M_A_DQ<7>      DQ<6>  @BASEBOARD_FAB2_LIB.BASEBOARD_FAB2(SCH_1):M_A_DQ<7>
  155  M_A_DQ<6>      DQ<7>  @BASEBOARD_FAB2_LIB.BASEBOARD_FAB2(SCH_1):M_A_DQ<6>
  135  M_A_DQ<63>     DQ<62>  @BASEBOARD_FAB2_LIB.BASEBOARD_FAB2(SCH_1):M_A_DQ<63>
  280  M_A_DQ<62>     DQ<63>  @BASEBOARD_FAB2_LIB.BASEBOARD_FAB2(SCH_1):M_A_DQ<62>
  128  M_A_DQ<61>     DQ<60>  @BASEBOARD_FAB2_LIB.BASEBOARD_FAB2(SCH_1):M_A_DQ<61>
  273  M_A_DQ<60>     DQ<61>  @BASEBOARD_FAB2_LIB.BASEBOARD_FAB2(SCH_1):M_A_DQ<60>
    3  M_A_DQ<5>      DQ<4>  @BASEBOARD_FAB2_LIB.BASEBOARD_FAB2(SCH_1):M_A_DQ<5>
  137  M_A_DQ<59>     DQ<58>  @BASEBOARD_FAB2_LIB.BASEBOARD_FAB2(SCH_1):M_A_DQ<59>
  282  M_A_DQ<58>     DQ<59>  @BASEBOARD_FAB2_LIB.BASEBOARD_FAB2(SCH_1):M_A_DQ<58>
  130  M_A_DQ<57>     DQ<56>  @BASEBOARD_FAB2_LIB.BASEBOARD_FAB2(SCH_1):M_A_DQ<57>
  275  M_A_DQ<56>     DQ<57>  @BASEBOARD_FAB2_LIB.BASEBOARD_FAB2(SCH_1):M_A_DQ<56>
  124  M_A_DQ<55>     DQ<54>  @BASEBOARD_FAB2_LIB.BASEBOARD_FAB2(SCH_1):M_A_DQ<55>
  269  M_A_DQ<54>     DQ<55>  @BASEBOARD_FAB2_LIB.BASEBOARD_FAB2(SCH_1):M_A_DQ<54>
  117  M_A_DQ<53>     DQ<52>  @BASEBOARD_FAB2_LIB.BASEBOARD_FAB2(SCH_1):M_A_DQ<53>
  262  M_A_DQ<52>     DQ<53>  @BASEBOARD_FAB2_LIB.BASEBOARD_FAB2(SCH_1):M_A_DQ<52>
  126  M_A_DQ<51>     DQ<50>  @BASEBOARD_FAB2_LIB.BASEBOARD_FAB2(SCH_1):M_A_DQ<51>
  271  M_A_DQ<50>     DQ<51>  @BASEBOARD_FAB2_LIB.BASEBOARD_FAB2(SCH_1):M_A_DQ<50>
  148  M_A_DQ<4>      DQ<5>  @BASEBOARD_FAB2_LIB.BASEBOARD_FAB2(SCH_1):M_A_DQ<4>
  119  M_A_DQ<49>     DQ<48>  @BASEBOARD_FAB2_LIB.BASEBOARD_FAB2(SCH_1):M_A_DQ<49>
  264  M_A_DQ<48>     DQ<49>  @BASEBOARD_FAB2_LIB.BASEBOARD_FAB2(SCH_1):M_A_DQ<48>
  113  M_A_DQ<47>     DQ<46>  @BASEBOARD_FAB2_LIB.BASEBOARD_FAB2(SCH_1):M_A_DQ<47>
  258  M_A_DQ<46>     DQ<47>  @BASEBOARD_FAB2_LIB.BASEBOARD_FAB2(SCH_1):M_A_DQ<46>
  106  M_A_DQ<45>     DQ<44>  @BASEBOARD_FAB2_LIB.BASEBOARD_FAB2(SCH_1):M_A_DQ<45>
  251  M_A_DQ<44>     DQ<45>  @BASEBOARD_FAB2_LIB.BASEBOARD_FAB2(SCH_1):M_A_DQ<44>
  115  M_A_DQ<43>     DQ<42>  @BASEBOARD_FAB2_LIB.BASEBOARD_FAB2(SCH_1):M_A_DQ<43>
  260  M_A_DQ<42>     DQ<43>  @BASEBOARD_FAB2_LIB.BASEBOARD_FAB2(SCH_1):M_A_DQ<42>
  108  M_A_DQ<41>     DQ<40>  @BASEBOARD_FAB2_LIB.BASEBOARD_FAB2(SCH_1):M_A_DQ<41>
  253  M_A_DQ<40>     DQ<41>  @BASEBOARD_FAB2_LIB.BASEBOARD_FAB2(SCH_1):M_A_DQ<40>
   12  M_A_DQ<3>      DQ<2>  @BASEBOARD_FAB2_LIB.BASEBOARD_FAB2(SCH_1):M_A_DQ<3>
  102  M_A_DQ<39>     DQ<38>  @BASEBOARD_FAB2_LIB.BASEBOARD_FAB2(SCH_1):M_A_DQ<39>
  247  M_A_DQ<38>     DQ<39>  @BASEBOARD_FAB2_LIB.BASEBOARD_FAB2(SCH_1):M_A_DQ<38>
   95  M_A_DQ<37>     DQ<36>  @BASEBOARD_FAB2_LIB.BASEBOARD_FAB2(SCH_1):M_A_DQ<37>
  240  M_A_DQ<36>     DQ<37>  @BASEBOARD_FAB2_LIB.BASEBOARD_FAB2(SCH_1):M_A_DQ<36>
  104  M_A_DQ<35>     DQ<34>  @BASEBOARD_FAB2_LIB.BASEBOARD_FAB2(SCH_1):M_A_DQ<35>
  249  M_A_DQ<34>     DQ<35>  @BASEBOARD_FAB2_LIB.BASEBOARD_FAB2(SCH_1):M_A_DQ<34>
   97  M_A_DQ<33>     DQ<32>  @BASEBOARD_FAB2_LIB.BASEBOARD_FAB2(SCH_1):M_A_DQ<33>
  242  M_A_DQ<32>     DQ<33>  @BASEBOARD_FAB2_LIB.BASEBOARD_FAB2(SCH_1):M_A_DQ<32>
   43  M_A_DQ<31>     DQ<30>  @BASEBOARD_FAB2_LIB.BASEBOARD_FAB2(SCH_1):M_A_DQ<31>
  188  M_A_DQ<30>     DQ<31>  @BASEBOARD_FAB2_LIB.BASEBOARD_FAB2(SCH_1):M_A_DQ<30>
  157  M_A_DQ<2>      DQ<3>  @BASEBOARD_FAB2_LIB.BASEBOARD_FAB2(SCH_1):M_A_DQ<2>
   36  M_A_DQ<29>     DQ<28>  @BASEBOARD_FAB2_LIB.BASEBOARD_FAB2(SCH_1):M_A_DQ<29>
  181  M_A_DQ<28>     DQ<29>  @BASEBOARD_FAB2_LIB.BASEBOARD_FAB2(SCH_1):M_A_DQ<28>
   45  M_A_DQ<27>     DQ<26>  @BASEBOARD_FAB2_LIB.BASEBOARD_FAB2(SCH_1):M_A_DQ<27>
  190  M_A_DQ<26>     DQ<27>  @BASEBOARD_FAB2_LIB.BASEBOARD_FAB2(SCH_1):M_A_DQ<26>
   38  M_A_DQ<25>     DQ<24>  @BASEBOARD_FAB2_LIB.BASEBOARD_FAB2(SCH_1):M_A_DQ<25>
  183  M_A_DQ<24>     DQ<25>  @BASEBOARD_FAB2_LIB.BASEBOARD_FAB2(SCH_1):M_A_DQ<24>
   32  M_A_DQ<23>     DQ<22>  @BASEBOARD_FAB2_LIB.BASEBOARD_FAB2(SCH_1):M_A_DQ<23>
  177  M_A_DQ<22>     DQ<23>  @BASEBOARD_FAB2_LIB.BASEBOARD_FAB2(SCH_1):M_A_DQ<22>
   25  M_A_DQ<21>     DQ<20>  @BASEBOARD_FAB2_LIB.BASEBOARD_FAB2(SCH_1):M_A_DQ<21>
  170  M_A_DQ<20>     DQ<21>  @BASEBOARD_FAB2_LIB.BASEBOARD_FAB2(SCH_1):M_A_DQ<20>
    5  M_A_DQ<1>      DQ<0>  @BASEBOARD_FAB2_LIB.BASEBOARD_FAB2(SCH_1):M_A_DQ<1>
   34  M_A_DQ<19>     DQ<18>  @BASEBOARD_FAB2_LIB.BASEBOARD_FAB2(SCH_1):M_A_DQ<19>
  179  M_A_DQ<18>     DQ<19>  @BASEBOARD_FAB2_LIB.BASEBOARD_FAB2(SCH_1):M_A_DQ<18>
   27  M_A_DQ<17>     DQ<16>  @BASEBOARD_FAB2_LIB.BASEBOARD_FAB2(SCH_1):M_A_DQ<17>
  172  M_A_DQ<16>     DQ<17>  @BASEBOARD_FAB2_LIB.BASEBOARD_FAB2(SCH_1):M_A_DQ<16>
   21  M_A_DQ<15>     DQ<14>  @BASEBOARD_FAB2_LIB.BASEBOARD_FAB2(SCH_1):M_A_DQ<15>
  166  M_A_DQ<14>     DQ<15>  @BASEBOARD_FAB2_LIB.BASEBOARD_FAB2(SCH_1):M_A_DQ<14>
   14  M_A_DQ<13>     DQ<12>  @BASEBOARD_FAB2_LIB.BASEBOARD_FAB2(SCH_1):M_A_DQ<13>
  159  M_A_DQ<12>     DQ<13>  @BASEBOARD_FAB2_LIB.BASEBOARD_FAB2(SCH_1):M_A_DQ<12>
   23  M_A_DQ<11>     DQ<10>  @BASEBOARD_FAB2_LIB.BASEBOARD_FAB2(SCH_1):M_A_DQ<11>
  168  M_A_DQ<10>     DQ<11>  @BASEBOARD_FAB2_LIB.BASEBOARD_FAB2(SCH_1):M_A_DQ<10>
  150  M_A_DQ<0>      DQ<1>  @BASEBOARD_FAB2_LIB.BASEBOARD_FAB2(SCH_1):M_A_DQ<0>
  237  M_A_CS_N<3>    S3_N_C<1>  @BASEBOARD_FAB2_LIB.BASEBOARD_FAB2(SCH_1):M_A_CS_N<3>
   93  M_A_CS_N<2>    S2_N_C<0>  @BASEBOARD_FAB2_LIB.BASEBOARD_FAB2(SCH_1):M_A_CS_N<2>
   89  M_A_CS_N<1>     S1_N  @BASEBOARD_FAB2_LIB.BASEBOARD_FAB2(SCH_1):M_A_CS_N<1>
   84  M_A_CS_N<0>     S0_N  @BASEBOARD_FAB2_LIB.BASEBOARD_FAB2(SCH_1):M_A_CS_N<0>
  218  M_A_CLK_DP<1>   CK1P  @BASEBOARD_FAB2_LIB.BASEBOARD_FAB2(SCH_1):M_A_CLK_DP<1>
   74  M_A_CLK_DP<0>   CK0P  @BASEBOARD_FAB2_LIB.BASEBOARD_FAB2(SCH_1):M_A_CLK_DP<0>
  219  M_A_CLK_DN<1>   CK1N  @BASEBOARD_FAB2_LIB.BASEBOARD_FAB2(SCH_1):M_A_CLK_DN<1>
   75  M_A_CLK_DN<0>   CK0N  @BASEBOARD_FAB2_LIB.BASEBOARD_FAB2(SCH_1):M_A_CLK_DN<0>
  203  M_A_CKE<1>     CKE<1>  @BASEBOARD_FAB2_LIB.BASEBOARD_FAB2(SCH_1):M_A_CKE<1>
   60  M_A_CKE<0>     CKE<0>  @BASEBOARD_FAB2_LIB.BASEBOARD_FAB2(SCH_1):M_A_CKE<0>
  235  M_A_C<2>        C<2>  @BASEBOARD_FAB2_LIB.BASEBOARD_FAB2(SCH_1):M_A_C<2>
  207  M_A_BG<1>      BG<1>  @BASEBOARD_FAB2_LIB.BASEBOARD_FAB2(SCH_1):M_A_BG<1>
   63  M_A_BG<0>      BG<0>  @BASEBOARD_FAB2_LIB.BASEBOARD_FAB2(SCH_1):M_A_BG<0>
  224  M_A_BA<1>      BA<1>  @BASEBOARD_FAB2_LIB.BASEBOARD_FAB2(SCH_1):M_A_BA<1>
   81  M_A_BA<0>      BA<0>  @BASEBOARD_FAB2_LIB.BASEBOARD_FAB2(SCH_1):M_A_BA<0>
  208  M_A_ALERT_N    ALERT_N  @BASEBOARD_FAB2_LIB.BASEBOARD_FAB2(SCH_1):M_A_ALERT_N
   62  M_A_ACT_N      ACT_N  @BASEBOARD_FAB2_LIB.BASEBOARD_FAB2(SCH_1):M_A_ACT_N
   58  M_ABC_RST_N    RESET_N  @BASEBOARD_FAB2_LIB.BASEBOARD_FAB2(SCH_1):M_ABC_RST_N
  238  GND            SA<2>  @BASEBOARD_FAB2_LIB.BASEBOARD_FAB2(SCH_1):GND
  140  GND            SA<1>  @BASEBOARD_FAB2_LIB.BASEBOARD_FAB2(SCH_1):GND
  139  GND            SA<0>  @BASEBOARD_FAB2_LIB.BASEBOARD_FAB2(SCH_1):GND
   78  FM_DIMM_EVENT_COD_N  EVENT_N  @BASEBOARD_FAB2_LIB.BASEBOARD_FAB2(SCH_1):FM_DIMM_EVENT_COD_N
  230  FM_ADR_COMPLETE_ABC_N  SAVE_N_NC  @BASEBOARD_FAB2_LIB.BASEBOARD_FAB2(SCH_1):FM_ADR_COMPLETE_ABC_N

SCONN288_H44441004_PIP  I169  J4G2   [SCONN288_H44441004_PIP-SCONN,HA]
   77  PVTT_ABC       VTT<1>  @BASEBOARD_FAB2_LIB.BASEBOARD_FAB2(SCH_1):PVTT_ABC
  221  PVTT_ABC       VTT<0>  @BASEBOARD_FAB2_LIB.BASEBOARD_FAB2(SCH_1):PVTT_ABC
  142  PVPP_ABC       VPP<4>  @BASEBOARD_FAB2_LIB.BASEBOARD_FAB2(SCH_1):PVPP_ABC
  143  PVPP_ABC       VPP<3>  @BASEBOARD_FAB2_LIB.BASEBOARD_FAB2(SCH_1):PVPP_ABC
  288  PVPP_ABC       VPP<2>  @BASEBOARD_FAB2_LIB.BASEBOARD_FAB2(SCH_1):PVPP_ABC
  286  PVPP_ABC       VPP<1>  @BASEBOARD_FAB2_LIB.BASEBOARD_FAB2(SCH_1):PVPP_ABC
  287  PVPP_ABC       VPP<0>  @BASEBOARD_FAB2_LIB.BASEBOARD_FAB2(SCH_1):PVPP_ABC
   59  PVDDQ_ABC      VDD<25>  @BASEBOARD_FAB2_LIB.BASEBOARD_FAB2(SCH_1):PVDDQ_ABC
   61  PVDDQ_ABC      VDD<24>  @BASEBOARD_FAB2_LIB.BASEBOARD_FAB2(SCH_1):PVDDQ_ABC
   64  PVDDQ_ABC      VDD<23>  @BASEBOARD_FAB2_LIB.BASEBOARD_FAB2(SCH_1):PVDDQ_ABC
   67  PVDDQ_ABC      VDD<22>  @BASEBOARD_FAB2_LIB.BASEBOARD_FAB2(SCH_1):PVDDQ_ABC
   70  PVDDQ_ABC      VDD<21>  @BASEBOARD_FAB2_LIB.BASEBOARD_FAB2(SCH_1):PVDDQ_ABC
   73  PVDDQ_ABC      VDD<20>  @BASEBOARD_FAB2_LIB.BASEBOARD_FAB2(SCH_1):PVDDQ_ABC
   76  PVDDQ_ABC      VDD<19>  @BASEBOARD_FAB2_LIB.BASEBOARD_FAB2(SCH_1):PVDDQ_ABC
   80  PVDDQ_ABC      VDD<18>  @BASEBOARD_FAB2_LIB.BASEBOARD_FAB2(SCH_1):PVDDQ_ABC
   83  PVDDQ_ABC      VDD<17>  @BASEBOARD_FAB2_LIB.BASEBOARD_FAB2(SCH_1):PVDDQ_ABC
   85  PVDDQ_ABC      VDD<16>  @BASEBOARD_FAB2_LIB.BASEBOARD_FAB2(SCH_1):PVDDQ_ABC
   88  PVDDQ_ABC      VDD<15>  @BASEBOARD_FAB2_LIB.BASEBOARD_FAB2(SCH_1):PVDDQ_ABC
   90  PVDDQ_ABC      VDD<14>  @BASEBOARD_FAB2_LIB.BASEBOARD_FAB2(SCH_1):PVDDQ_ABC
   92  PVDDQ_ABC      VDD<13>  @BASEBOARD_FAB2_LIB.BASEBOARD_FAB2(SCH_1):PVDDQ_ABC
  204  PVDDQ_ABC      VDD<12>  @BASEBOARD_FAB2_LIB.BASEBOARD_FAB2(SCH_1):PVDDQ_ABC
  206  PVDDQ_ABC      VDD<11>  @BASEBOARD_FAB2_LIB.BASEBOARD_FAB2(SCH_1):PVDDQ_ABC
  209  PVDDQ_ABC      VDD<10>  @BASEBOARD_FAB2_LIB.BASEBOARD_FAB2(SCH_1):PVDDQ_ABC
  212  PVDDQ_ABC      VDD<9>  @BASEBOARD_FAB2_LIB.BASEBOARD_FAB2(SCH_1):PVDDQ_ABC
  215  PVDDQ_ABC      VDD<8>  @BASEBOARD_FAB2_LIB.BASEBOARD_FAB2(SCH_1):PVDDQ_ABC
  217  PVDDQ_ABC      VDD<7>  @BASEBOARD_FAB2_LIB.BASEBOARD_FAB2(SCH_1):PVDDQ_ABC
  220  PVDDQ_ABC      VDD<6>  @BASEBOARD_FAB2_LIB.BASEBOARD_FAB2(SCH_1):PVDDQ_ABC
  223  PVDDQ_ABC      VDD<5>  @BASEBOARD_FAB2_LIB.BASEBOARD_FAB2(SCH_1):PVDDQ_ABC
  226  PVDDQ_ABC      VDD<4>  @BASEBOARD_FAB2_LIB.BASEBOARD_FAB2(SCH_1):PVDDQ_ABC
  229  PVDDQ_ABC      VDD<3>  @BASEBOARD_FAB2_LIB.BASEBOARD_FAB2(SCH_1):PVDDQ_ABC
  231  PVDDQ_ABC      VDD<2>  @BASEBOARD_FAB2_LIB.BASEBOARD_FAB2(SCH_1):PVDDQ_ABC
  233  PVDDQ_ABC      VDD<1>  @BASEBOARD_FAB2_LIB.BASEBOARD_FAB2(SCH_1):PVDDQ_ABC
  236  PVDDQ_ABC      VDD<0>  @BASEBOARD_FAB2_LIB.BASEBOARD_FAB2(SCH_1):PVDDQ_ABC
    1  P12V_NVDIMM_ABC  12V<1>  @BASEBOARD_FAB2_LIB.BASEBOARD_FAB2(SCH_1):P12V_NVDIMM_ABC
  145  P12V_NVDIMM_ABC  12V<0>  @BASEBOARD_FAB2_LIB.BASEBOARD_FAB2(SCH_1):P12V_NVDIMM_ABC

SCONN288_H44441004_PIP  I43  J4G2   [SCONN288_H44441004_PIP-SCONN,HA]
    2  GND            VSS<93>  @BASEBOARD_FAB2_LIB.BASEBOARD_FAB2(SCH_1):GND
    4  GND            VSS<92>  @BASEBOARD_FAB2_LIB.BASEBOARD_FAB2(SCH_1):GND
    6  GND            VSS<91>  @BASEBOARD_FAB2_LIB.BASEBOARD_FAB2(SCH_1):GND
    9  GND            VSS<90>  @BASEBOARD_FAB2_LIB.BASEBOARD_FAB2(SCH_1):GND
   11  GND            VSS<89>  @BASEBOARD_FAB2_LIB.BASEBOARD_FAB2(SCH_1):GND
   13  GND            VSS<88>  @BASEBOARD_FAB2_LIB.BASEBOARD_FAB2(SCH_1):GND
   15  GND            VSS<87>  @BASEBOARD_FAB2_LIB.BASEBOARD_FAB2(SCH_1):GND
   17  GND            VSS<86>  @BASEBOARD_FAB2_LIB.BASEBOARD_FAB2(SCH_1):GND
   20  GND            VSS<85>  @BASEBOARD_FAB2_LIB.BASEBOARD_FAB2(SCH_1):GND
   22  GND            VSS<84>  @BASEBOARD_FAB2_LIB.BASEBOARD_FAB2(SCH_1):GND
   24  GND            VSS<83>  @BASEBOARD_FAB2_LIB.BASEBOARD_FAB2(SCH_1):GND
   26  GND            VSS<82>  @BASEBOARD_FAB2_LIB.BASEBOARD_FAB2(SCH_1):GND
   28  GND            VSS<81>  @BASEBOARD_FAB2_LIB.BASEBOARD_FAB2(SCH_1):GND
   31  GND            VSS<80>  @BASEBOARD_FAB2_LIB.BASEBOARD_FAB2(SCH_1):GND
   33  GND            VSS<79>  @BASEBOARD_FAB2_LIB.BASEBOARD_FAB2(SCH_1):GND
   35  GND            VSS<78>  @BASEBOARD_FAB2_LIB.BASEBOARD_FAB2(SCH_1):GND
   37  GND            VSS<77>  @BASEBOARD_FAB2_LIB.BASEBOARD_FAB2(SCH_1):GND
   39  GND            VSS<76>  @BASEBOARD_FAB2_LIB.BASEBOARD_FAB2(SCH_1):GND
   42  GND            VSS<75>  @BASEBOARD_FAB2_LIB.BASEBOARD_FAB2(SCH_1):GND
   44  GND            VSS<74>  @BASEBOARD_FAB2_LIB.BASEBOARD_FAB2(SCH_1):GND
   46  GND            VSS<73>  @BASEBOARD_FAB2_LIB.BASEBOARD_FAB2(SCH_1):GND
   48  GND            VSS<72>  @BASEBOARD_FAB2_LIB.BASEBOARD_FAB2(SCH_1):GND
   50  GND            VSS<71>  @BASEBOARD_FAB2_LIB.BASEBOARD_FAB2(SCH_1):GND
   53  GND            VSS<70>  @BASEBOARD_FAB2_LIB.BASEBOARD_FAB2(SCH_1):GND
   55  GND            VSS<69>  @BASEBOARD_FAB2_LIB.BASEBOARD_FAB2(SCH_1):GND
   57  GND            VSS<68>  @BASEBOARD_FAB2_LIB.BASEBOARD_FAB2(SCH_1):GND
   94  GND            VSS<67>  @BASEBOARD_FAB2_LIB.BASEBOARD_FAB2(SCH_1):GND
   96  GND            VSS<66>  @BASEBOARD_FAB2_LIB.BASEBOARD_FAB2(SCH_1):GND
   98  GND            VSS<65>  @BASEBOARD_FAB2_LIB.BASEBOARD_FAB2(SCH_1):GND
  101  GND            VSS<64>  @BASEBOARD_FAB2_LIB.BASEBOARD_FAB2(SCH_1):GND
  103  GND            VSS<63>  @BASEBOARD_FAB2_LIB.BASEBOARD_FAB2(SCH_1):GND
  105  GND            VSS<62>  @BASEBOARD_FAB2_LIB.BASEBOARD_FAB2(SCH_1):GND
  107  GND            VSS<61>  @BASEBOARD_FAB2_LIB.BASEBOARD_FAB2(SCH_1):GND
  109  GND            VSS<60>  @BASEBOARD_FAB2_LIB.BASEBOARD_FAB2(SCH_1):GND
  112  GND            VSS<59>  @BASEBOARD_FAB2_LIB.BASEBOARD_FAB2(SCH_1):GND
  114  GND            VSS<58>  @BASEBOARD_FAB2_LIB.BASEBOARD_FAB2(SCH_1):GND
  116  GND            VSS<57>  @BASEBOARD_FAB2_LIB.BASEBOARD_FAB2(SCH_1):GND
  118  GND            VSS<56>  @BASEBOARD_FAB2_LIB.BASEBOARD_FAB2(SCH_1):GND
  120  GND            VSS<55>  @BASEBOARD_FAB2_LIB.BASEBOARD_FAB2(SCH_1):GND
  123  GND            VSS<54>  @BASEBOARD_FAB2_LIB.BASEBOARD_FAB2(SCH_1):GND
  125  GND            VSS<53>  @BASEBOARD_FAB2_LIB.BASEBOARD_FAB2(SCH_1):GND
  127  GND            VSS<52>  @BASEBOARD_FAB2_LIB.BASEBOARD_FAB2(SCH_1):GND
  129  GND            VSS<51>  @BASEBOARD_FAB2_LIB.BASEBOARD_FAB2(SCH_1):GND
  131  GND            VSS<50>  @BASEBOARD_FAB2_LIB.BASEBOARD_FAB2(SCH_1):GND
  134  GND            VSS<49>  @BASEBOARD_FAB2_LIB.BASEBOARD_FAB2(SCH_1):GND
  136  GND            VSS<48>  @BASEBOARD_FAB2_LIB.BASEBOARD_FAB2(SCH_1):GND
  138  GND            VSS<47>  @BASEBOARD_FAB2_LIB.BASEBOARD_FAB2(SCH_1):GND
  147  GND            VSS<46>  @BASEBOARD_FAB2_LIB.BASEBOARD_FAB2(SCH_1):GND
  149  GND            VSS<45>  @BASEBOARD_FAB2_LIB.BASEBOARD_FAB2(SCH_1):GND
  151  GND            VSS<44>  @BASEBOARD_FAB2_LIB.BASEBOARD_FAB2(SCH_1):GND
  154  GND            VSS<43>  @BASEBOARD_FAB2_LIB.BASEBOARD_FAB2(SCH_1):GND
  156  GND            VSS<42>  @BASEBOARD_FAB2_LIB.BASEBOARD_FAB2(SCH_1):GND
  158  GND            VSS<41>  @BASEBOARD_FAB2_LIB.BASEBOARD_FAB2(SCH_1):GND
  160  GND            VSS<40>  @BASEBOARD_FAB2_LIB.BASEBOARD_FAB2(SCH_1):GND
  162  GND            VSS<39>  @BASEBOARD_FAB2_LIB.BASEBOARD_FAB2(SCH_1):GND
  165  GND            VSS<38>  @BASEBOARD_FAB2_LIB.BASEBOARD_FAB2(SCH_1):GND
  167  GND            VSS<37>  @BASEBOARD_FAB2_LIB.BASEBOARD_FAB2(SCH_1):GND
  169  GND            VSS<36>  @BASEBOARD_FAB2_LIB.BASEBOARD_FAB2(SCH_1):GND
  171  GND            VSS<35>  @BASEBOARD_FAB2_LIB.BASEBOARD_FAB2(SCH_1):GND
  173  GND            VSS<34>  @BASEBOARD_FAB2_LIB.BASEBOARD_FAB2(SCH_1):GND
  176  GND            VSS<33>  @BASEBOARD_FAB2_LIB.BASEBOARD_FAB2(SCH_1):GND
  178  GND            VSS<32>  @BASEBOARD_FAB2_LIB.BASEBOARD_FAB2(SCH_1):GND
  180  GND            VSS<31>  @BASEBOARD_FAB2_LIB.BASEBOARD_FAB2(SCH_1):GND
  182  GND            VSS<30>  @BASEBOARD_FAB2_LIB.BASEBOARD_FAB2(SCH_1):GND
  184  GND            VSS<29>  @BASEBOARD_FAB2_LIB.BASEBOARD_FAB2(SCH_1):GND
  187  GND            VSS<28>  @BASEBOARD_FAB2_LIB.BASEBOARD_FAB2(SCH_1):GND
  189  GND            VSS<27>  @BASEBOARD_FAB2_LIB.BASEBOARD_FAB2(SCH_1):GND
  191  GND            VSS<26>  @BASEBOARD_FAB2_LIB.BASEBOARD_FAB2(SCH_1):GND
  193  GND            VSS<25>  @BASEBOARD_FAB2_LIB.BASEBOARD_FAB2(SCH_1):GND
  195  GND            VSS<24>  @BASEBOARD_FAB2_LIB.BASEBOARD_FAB2(SCH_1):GND
  198  GND            VSS<23>  @BASEBOARD_FAB2_LIB.BASEBOARD_FAB2(SCH_1):GND
  200  GND            VSS<22>  @BASEBOARD_FAB2_LIB.BASEBOARD_FAB2(SCH_1):GND
  202  GND            VSS<21>  @BASEBOARD_FAB2_LIB.BASEBOARD_FAB2(SCH_1):GND
  239  GND            VSS<20>  @BASEBOARD_FAB2_LIB.BASEBOARD_FAB2(SCH_1):GND
  241  GND            VSS<19>  @BASEBOARD_FAB2_LIB.BASEBOARD_FAB2(SCH_1):GND
  243  GND            VSS<18>  @BASEBOARD_FAB2_LIB.BASEBOARD_FAB2(SCH_1):GND
  246  GND            VSS<17>  @BASEBOARD_FAB2_LIB.BASEBOARD_FAB2(SCH_1):GND
  248  GND            VSS<16>  @BASEBOARD_FAB2_LIB.BASEBOARD_FAB2(SCH_1):GND
  250  GND            VSS<15>  @BASEBOARD_FAB2_LIB.BASEBOARD_FAB2(SCH_1):GND
  252  GND            VSS<14>  @BASEBOARD_FAB2_LIB.BASEBOARD_FAB2(SCH_1):GND
  254  GND            VSS<13>  @BASEBOARD_FAB2_LIB.BASEBOARD_FAB2(SCH_1):GND
  257  GND            VSS<12>  @BASEBOARD_FAB2_LIB.BASEBOARD_FAB2(SCH_1):GND
  259  GND            VSS<11>  @BASEBOARD_FAB2_LIB.BASEBOARD_FAB2(SCH_1):GND
  261  GND            VSS<10>  @BASEBOARD_FAB2_LIB.BASEBOARD_FAB2(SCH_1):GND
  263  GND            VSS<9>  @BASEBOARD_FAB2_LIB.BASEBOARD_FAB2(SCH_1):GND
  265  GND            VSS<8>  @BASEBOARD_FAB2_LIB.BASEBOARD_FAB2(SCH_1):GND
  268  GND            VSS<7>  @BASEBOARD_FAB2_LIB.BASEBOARD_FAB2(SCH_1):GND
  270  GND            VSS<6>  @BASEBOARD_FAB2_LIB.BASEBOARD_FAB2(SCH_1):GND
  272  GND            VSS<5>  @BASEBOARD_FAB2_LIB.BASEBOARD_FAB2(SCH_1):GND
  274  GND            VSS<4>  @BASEBOARD_FAB2_LIB.BASEBOARD_FAB2(SCH_1):GND
  276  GND            VSS<3>  @BASEBOARD_FAB2_LIB.BASEBOARD_FAB2(SCH_1):GND
  279  GND            VSS<2>  @BASEBOARD_FAB2_LIB.BASEBOARD_FAB2(SCH_1):GND
  281  GND            VSS<1>  @BASEBOARD_FAB2_LIB.BASEBOARD_FAB2(SCH_1):GND
  283  GND            VSS<0>  @BASEBOARD_FAB2_LIB.BASEBOARD_FAB2(SCH_1):GND

SCONN288_H44441004_PIP  I61  J4G2   [SCONN288_H44441004_PIP-SCONN,HA]
    7  M_B_DQS_DP<9>  DQS9P  @BASEBOARD_FAB2_LIB.BASEBOARD_FAB2(SCH_1):M_B_DQS_DP<9>
  197  M_B_DQS_DP<8>  DQS8P  @BASEBOARD_FAB2_LIB.BASEBOARD_FAB2(SCH_1):M_B_DQS_DP<8>
  278  M_B_DQS_DP<7>  DQS7P  @BASEBOARD_FAB2_LIB.BASEBOARD_FAB2(SCH_1):M_B_DQS_DP<7>
  267  M_B_DQS_DP<6>  DQS6P  @BASEBOARD_FAB2_LIB.BASEBOARD_FAB2(SCH_1):M_B_DQS_DP<6>
  256  M_B_DQS_DP<5>  DQS5P  @BASEBOARD_FAB2_LIB.BASEBOARD_FAB2(SCH_1):M_B_DQS_DP<5>
  245  M_B_DQS_DP<4>  DQS4P  @BASEBOARD_FAB2_LIB.BASEBOARD_FAB2(SCH_1):M_B_DQS_DP<4>
  186  M_B_DQS_DP<3>  DQS3P  @BASEBOARD_FAB2_LIB.BASEBOARD_FAB2(SCH_1):M_B_DQS_DP<3>
  175  M_B_DQS_DP<2>  DQS2P  @BASEBOARD_FAB2_LIB.BASEBOARD_FAB2(SCH_1):M_B_DQS_DP<2>
  164  M_B_DQS_DP<1>  DQS1P  @BASEBOARD_FAB2_LIB.BASEBOARD_FAB2(SCH_1):M_B_DQS_DP<1>
   51  M_B_DQS_DP<17>  DQS17P  @BASEBOARD_FAB2_LIB.BASEBOARD_FAB2(SCH_1):M_B_DQS_DP<17>
  132  M_B_DQS_DP<16>  DQS16P  @BASEBOARD_FAB2_LIB.BASEBOARD_FAB2(SCH_1):M_B_DQS_DP<16>
  121  M_B_DQS_DP<15>  DQS15P  @BASEBOARD_FAB2_LIB.BASEBOARD_FAB2(SCH_1):M_B_DQS_DP<15>
  110  M_B_DQS_DP<14>  DQS14P  @BASEBOARD_FAB2_LIB.BASEBOARD_FAB2(SCH_1):M_B_DQS_DP<14>
   99  M_B_DQS_DP<13>  DQS13P  @BASEBOARD_FAB2_LIB.BASEBOARD_FAB2(SCH_1):M_B_DQS_DP<13>
   40  M_B_DQS_DP<12>  DQS12P  @BASEBOARD_FAB2_LIB.BASEBOARD_FAB2(SCH_1):M_B_DQS_DP<12>
   29  M_B_DQS_DP<11>  DQS11P  @BASEBOARD_FAB2_LIB.BASEBOARD_FAB2(SCH_1):M_B_DQS_DP<11>
   18  M_B_DQS_DP<10>  DQS10P  @BASEBOARD_FAB2_LIB.BASEBOARD_FAB2(SCH_1):M_B_DQS_DP<10>
  153  M_B_DQS_DP<0>  DQS0P  @BASEBOARD_FAB2_LIB.BASEBOARD_FAB2(SCH_1):M_B_DQS_DP<0>
    8  M_B_DQS_DN<9>  DQS9N  @BASEBOARD_FAB2_LIB.BASEBOARD_FAB2(SCH_1):M_B_DQS_DN<9>
  196  M_B_DQS_DN<8>  DQS8N  @BASEBOARD_FAB2_LIB.BASEBOARD_FAB2(SCH_1):M_B_DQS_DN<8>
  277  M_B_DQS_DN<7>  DQS7N  @BASEBOARD_FAB2_LIB.BASEBOARD_FAB2(SCH_1):M_B_DQS_DN<7>
  266  M_B_DQS_DN<6>  DQS6N  @BASEBOARD_FAB2_LIB.BASEBOARD_FAB2(SCH_1):M_B_DQS_DN<6>
  255  M_B_DQS_DN<5>  DQS5N  @BASEBOARD_FAB2_LIB.BASEBOARD_FAB2(SCH_1):M_B_DQS_DN<5>
  244  M_B_DQS_DN<4>  DQS4N  @BASEBOARD_FAB2_LIB.BASEBOARD_FAB2(SCH_1):M_B_DQS_DN<4>
  185  M_B_DQS_DN<3>  DQS3N  @BASEBOARD_FAB2_LIB.BASEBOARD_FAB2(SCH_1):M_B_DQS_DN<3>
  174  M_B_DQS_DN<2>  DQS2N  @BASEBOARD_FAB2_LIB.BASEBOARD_FAB2(SCH_1):M_B_DQS_DN<2>
  163  M_B_DQS_DN<1>  DQS1N  @BASEBOARD_FAB2_LIB.BASEBOARD_FAB2(SCH_1):M_B_DQS_DN<1>
   52  M_B_DQS_DN<17>  DQS17N  @BASEBOARD_FAB2_LIB.BASEBOARD_FAB2(SCH_1):M_B_DQS_DN<17>
  133  M_B_DQS_DN<16>  DQS16N  @BASEBOARD_FAB2_LIB.BASEBOARD_FAB2(SCH_1):M_B_DQS_DN<16>
  122  M_B_DQS_DN<15>  DQS15N  @BASEBOARD_FAB2_LIB.BASEBOARD_FAB2(SCH_1):M_B_DQS_DN<15>
  111  M_B_DQS_DN<14>  DQS14N  @BASEBOARD_FAB2_LIB.BASEBOARD_FAB2(SCH_1):M_B_DQS_DN<14>
  100  M_B_DQS_DN<13>  DQS13N  @BASEBOARD_FAB2_LIB.BASEBOARD_FAB2(SCH_1):M_B_DQS_DN<13>
   41  M_B_DQS_DN<12>  DQS12N  @BASEBOARD_FAB2_LIB.BASEBOARD_FAB2(SCH_1):M_B_DQS_DN<12>
   30  M_B_DQS_DN<11>  DQS11N  @BASEBOARD_FAB2_LIB.BASEBOARD_FAB2(SCH_1):M_B_DQS_DN<11>
   19  M_B_DQS_DN<10>  DQS10N  @BASEBOARD_FAB2_LIB.BASEBOARD_FAB2(SCH_1):M_B_DQS_DN<10>
  152  M_B_DQS_DN<0>  DQS0N  @BASEBOARD_FAB2_LIB.BASEBOARD_FAB2(SCH_1):M_B_DQS_DN<0>

SCONN288_H44441004_PIP  I111  J4G2   [SCONN288_H44441004_PIP-SCONN,HA]
  144  TP_CH_B_DIMM_B0_RFU_2  RFU<2>  @BASEBOARD_FAB2_LIB.BASEBOARD_FAB2(SCH_1):TP_CH_B_DIMM_B0_RFU_2
  227  TP_CH_B_DIMM_B0_RFU_1  RFU<1>  @BASEBOARD_FAB2_LIB.BASEBOARD_FAB2(SCH_1):TP_CH_B_DIMM_B0_RFU_1
  205  TP_CH_B_DIMM_B0_RFU_0  RFU<0>  @BASEBOARD_FAB2_LIB.BASEBOARD_FAB2(SCH_1):TP_CH_B_DIMM_B0_RFU_0
  285  SMB_DDR_ABC_VPP_SDA    SDA  @BASEBOARD_FAB2_LIB.BASEBOARD_FAB2(SCH_1):SMB_DDR_ABC_VPP_SDA
  141  SMB_DDR_ABC_VPP_SCL    SCL  @BASEBOARD_FAB2_LIB.BASEBOARD_FAB2(SCH_1):SMB_DDR_ABC_VPP_SCL
  284  PVPP_ABC       VDDSPD  @BASEBOARD_FAB2_LIB.BASEBOARD_FAB2(SCH_1):PVPP_ABC
  140  PVPP_ABC       SA<1>  @BASEBOARD_FAB2_LIB.BASEBOARD_FAB2(SCH_1):PVPP_ABC
  146  M_B_VREF       VREFCA  @BASEBOARD_FAB2_LIB.BASEBOARD_FAB2(SCH_1):M_B_VREF
  222  M_B_PAR          PAR  @BASEBOARD_FAB2_LIB.BASEBOARD_FAB2(SCH_1):M_B_PAR
   91  M_B_ODT<1>     ODT<1>  @BASEBOARD_FAB2_LIB.BASEBOARD_FAB2(SCH_1):M_B_ODT<1>
   87  M_B_ODT<0>     ODT<0>  @BASEBOARD_FAB2_LIB.BASEBOARD_FAB2(SCH_1):M_B_ODT<0>
   66  M_B_MA<9>         A9  @BASEBOARD_FAB2_LIB.BASEBOARD_FAB2(SCH_1):M_B_MA<9>
   68  M_B_MA<8>         A8  @BASEBOARD_FAB2_LIB.BASEBOARD_FAB2(SCH_1):M_B_MA<8>
  211  M_B_MA<7>         A7  @BASEBOARD_FAB2_LIB.BASEBOARD_FAB2(SCH_1):M_B_MA<7>
   69  M_B_MA<6>         A6  @BASEBOARD_FAB2_LIB.BASEBOARD_FAB2(SCH_1):M_B_MA<6>
  213  M_B_MA<5>         A5  @BASEBOARD_FAB2_LIB.BASEBOARD_FAB2(SCH_1):M_B_MA<5>
  214  M_B_MA<4>         A4  @BASEBOARD_FAB2_LIB.BASEBOARD_FAB2(SCH_1):M_B_MA<4>
   71  M_B_MA<3>         A3  @BASEBOARD_FAB2_LIB.BASEBOARD_FAB2(SCH_1):M_B_MA<3>
  216  M_B_MA<2>         A2  @BASEBOARD_FAB2_LIB.BASEBOARD_FAB2(SCH_1):M_B_MA<2>
   72  M_B_MA<1>         A1  @BASEBOARD_FAB2_LIB.BASEBOARD_FAB2(SCH_1):M_B_MA<1>
  234  M_B_MA<17>       A17  @BASEBOARD_FAB2_LIB.BASEBOARD_FAB2(SCH_1):M_B_MA<17>
   82  M_B_MA<16>     A16_RAS_N  @BASEBOARD_FAB2_LIB.BASEBOARD_FAB2(SCH_1):M_B_MA<16>
   86  M_B_MA<15>     A15_CAS_N  @BASEBOARD_FAB2_LIB.BASEBOARD_FAB2(SCH_1):M_B_MA<15>
  228  M_B_MA<14>     A14_WE_N  @BASEBOARD_FAB2_LIB.BASEBOARD_FAB2(SCH_1):M_B_MA<14>
  232  M_B_MA<13>       A13  @BASEBOARD_FAB2_LIB.BASEBOARD_FAB2(SCH_1):M_B_MA<13>
   65  M_B_MA<12>       A12  @BASEBOARD_FAB2_LIB.BASEBOARD_FAB2(SCH_1):M_B_MA<12>
  210  M_B_MA<11>       A11  @BASEBOARD_FAB2_LIB.BASEBOARD_FAB2(SCH_1):M_B_MA<11>
  225  M_B_MA<10>       A10  @BASEBOARD_FAB2_LIB.BASEBOARD_FAB2(SCH_1):M_B_MA<10>
   79  M_B_MA<0>         A0  @BASEBOARD_FAB2_LIB.BASEBOARD_FAB2(SCH_1):M_B_MA<0>
   54  M_B_ECC<7>     CB<6>  @BASEBOARD_FAB2_LIB.BASEBOARD_FAB2(SCH_1):M_B_ECC<7>
  199  M_B_ECC<6>     CB<7>  @BASEBOARD_FAB2_LIB.BASEBOARD_FAB2(SCH_1):M_B_ECC<6>
   47  M_B_ECC<5>     CB<4>  @BASEBOARD_FAB2_LIB.BASEBOARD_FAB2(SCH_1):M_B_ECC<5>
  192  M_B_ECC<4>     CB<5>  @BASEBOARD_FAB2_LIB.BASEBOARD_FAB2(SCH_1):M_B_ECC<4>
   56  M_B_ECC<3>     CB<2>  @BASEBOARD_FAB2_LIB.BASEBOARD_FAB2(SCH_1):M_B_ECC<3>
  201  M_B_ECC<2>     CB<3>  @BASEBOARD_FAB2_LIB.BASEBOARD_FAB2(SCH_1):M_B_ECC<2>
   49  M_B_ECC<1>     CB<0>  @BASEBOARD_FAB2_LIB.BASEBOARD_FAB2(SCH_1):M_B_ECC<1>
  194  M_B_ECC<0>     CB<1>  @BASEBOARD_FAB2_LIB.BASEBOARD_FAB2(SCH_1):M_B_ECC<0>
   16  M_B_DQ<9>      DQ<8>  @BASEBOARD_FAB2_LIB.BASEBOARD_FAB2(SCH_1):M_B_DQ<9>
  161  M_B_DQ<8>      DQ<9>  @BASEBOARD_FAB2_LIB.BASEBOARD_FAB2(SCH_1):M_B_DQ<8>
   10  M_B_DQ<7>      DQ<6>  @BASEBOARD_FAB2_LIB.BASEBOARD_FAB2(SCH_1):M_B_DQ<7>
  155  M_B_DQ<6>      DQ<7>  @BASEBOARD_FAB2_LIB.BASEBOARD_FAB2(SCH_1):M_B_DQ<6>
  135  M_B_DQ<63>     DQ<62>  @BASEBOARD_FAB2_LIB.BASEBOARD_FAB2(SCH_1):M_B_DQ<63>
  280  M_B_DQ<62>     DQ<63>  @BASEBOARD_FAB2_LIB.BASEBOARD_FAB2(SCH_1):M_B_DQ<62>
  128  M_B_DQ<61>     DQ<60>  @BASEBOARD_FAB2_LIB.BASEBOARD_FAB2(SCH_1):M_B_DQ<61>
  273  M_B_DQ<60>     DQ<61>  @BASEBOARD_FAB2_LIB.BASEBOARD_FAB2(SCH_1):M_B_DQ<60>
    3  M_B_DQ<5>      DQ<4>  @BASEBOARD_FAB2_LIB.BASEBOARD_FAB2(SCH_1):M_B_DQ<5>
  137  M_B_DQ<59>     DQ<58>  @BASEBOARD_FAB2_LIB.BASEBOARD_FAB2(SCH_1):M_B_DQ<59>
  282  M_B_DQ<58>     DQ<59>  @BASEBOARD_FAB2_LIB.BASEBOARD_FAB2(SCH_1):M_B_DQ<58>
  130  M_B_DQ<57>     DQ<56>  @BASEBOARD_FAB2_LIB.BASEBOARD_FAB2(SCH_1):M_B_DQ<57>
  275  M_B_DQ<56>     DQ<57>  @BASEBOARD_FAB2_LIB.BASEBOARD_FAB2(SCH_1):M_B_DQ<56>
  124  M_B_DQ<55>     DQ<54>  @BASEBOARD_FAB2_LIB.BASEBOARD_FAB2(SCH_1):M_B_DQ<55>
  269  M_B_DQ<54>     DQ<55>  @BASEBOARD_FAB2_LIB.BASEBOARD_FAB2(SCH_1):M_B_DQ<54>
  117  M_B_DQ<53>     DQ<52>  @BASEBOARD_FAB2_LIB.BASEBOARD_FAB2(SCH_1):M_B_DQ<53>
  262  M_B_DQ<52>     DQ<53>  @BASEBOARD_FAB2_LIB.BASEBOARD_FAB2(SCH_1):M_B_DQ<52>
  126  M_B_DQ<51>     DQ<50>  @BASEBOARD_FAB2_LIB.BASEBOARD_FAB2(SCH_1):M_B_DQ<51>
  271  M_B_DQ<50>     DQ<51>  @BASEBOARD_FAB2_LIB.BASEBOARD_FAB2(SCH_1):M_B_DQ<50>
  148  M_B_DQ<4>      DQ<5>  @BASEBOARD_FAB2_LIB.BASEBOARD_FAB2(SCH_1):M_B_DQ<4>
  119  M_B_DQ<49>     DQ<48>  @BASEBOARD_FAB2_LIB.BASEBOARD_FAB2(SCH_1):M_B_DQ<49>
  264  M_B_DQ<48>     DQ<49>  @BASEBOARD_FAB2_LIB.BASEBOARD_FAB2(SCH_1):M_B_DQ<48>
  113  M_B_DQ<47>     DQ<46>  @BASEBOARD_FAB2_LIB.BASEBOARD_FAB2(SCH_1):M_B_DQ<47>
  258  M_B_DQ<46>     DQ<47>  @BASEBOARD_FAB2_LIB.BASEBOARD_FAB2(SCH_1):M_B_DQ<46>
  106  M_B_DQ<45>     DQ<44>  @BASEBOARD_FAB2_LIB.BASEBOARD_FAB2(SCH_1):M_B_DQ<45>
  251  M_B_DQ<44>     DQ<45>  @BASEBOARD_FAB2_LIB.BASEBOARD_FAB2(SCH_1):M_B_DQ<44>
  115  M_B_DQ<43>     DQ<42>  @BASEBOARD_FAB2_LIB.BASEBOARD_FAB2(SCH_1):M_B_DQ<43>
  260  M_B_DQ<42>     DQ<43>  @BASEBOARD_FAB2_LIB.BASEBOARD_FAB2(SCH_1):M_B_DQ<42>
  108  M_B_DQ<41>     DQ<40>  @BASEBOARD_FAB2_LIB.BASEBOARD_FAB2(SCH_1):M_B_DQ<41>
  253  M_B_DQ<40>     DQ<41>  @BASEBOARD_FAB2_LIB.BASEBOARD_FAB2(SCH_1):M_B_DQ<40>
   12  M_B_DQ<3>      DQ<2>  @BASEBOARD_FAB2_LIB.BASEBOARD_FAB2(SCH_1):M_B_DQ<3>
  102  M_B_DQ<39>     DQ<38>  @BASEBOARD_FAB2_LIB.BASEBOARD_FAB2(SCH_1):M_B_DQ<39>
  247  M_B_DQ<38>     DQ<39>  @BASEBOARD_FAB2_LIB.BASEBOARD_FAB2(SCH_1):M_B_DQ<38>
   95  M_B_DQ<37>     DQ<36>  @BASEBOARD_FAB2_LIB.BASEBOARD_FAB2(SCH_1):M_B_DQ<37>
  240  M_B_DQ<36>     DQ<37>  @BASEBOARD_FAB2_LIB.BASEBOARD_FAB2(SCH_1):M_B_DQ<36>
  104  M_B_DQ<35>     DQ<34>  @BASEBOARD_FAB2_LIB.BASEBOARD_FAB2(SCH_1):M_B_DQ<35>
  249  M_B_DQ<34>     DQ<35>  @BASEBOARD_FAB2_LIB.BASEBOARD_FAB2(SCH_1):M_B_DQ<34>
   97  M_B_DQ<33>     DQ<32>  @BASEBOARD_FAB2_LIB.BASEBOARD_FAB2(SCH_1):M_B_DQ<33>
  242  M_B_DQ<32>     DQ<33>  @BASEBOARD_FAB2_LIB.BASEBOARD_FAB2(SCH_1):M_B_DQ<32>
   43  M_B_DQ<31>     DQ<30>  @BASEBOARD_FAB2_LIB.BASEBOARD_FAB2(SCH_1):M_B_DQ<31>
  188  M_B_DQ<30>     DQ<31>  @BASEBOARD_FAB2_LIB.BASEBOARD_FAB2(SCH_1):M_B_DQ<30>
  157  M_B_DQ<2>      DQ<3>  @BASEBOARD_FAB2_LIB.BASEBOARD_FAB2(SCH_1):M_B_DQ<2>
   36  M_B_DQ<29>     DQ<28>  @BASEBOARD_FAB2_LIB.BASEBOARD_FAB2(SCH_1):M_B_DQ<29>
  181  M_B_DQ<28>     DQ<29>  @BASEBOARD_FAB2_LIB.BASEBOARD_FAB2(SCH_1):M_B_DQ<28>
   45  M_B_DQ<27>     DQ<26>  @BASEBOARD_FAB2_LIB.BASEBOARD_FAB2(SCH_1):M_B_DQ<27>
  190  M_B_DQ<26>     DQ<27>  @BASEBOARD_FAB2_LIB.BASEBOARD_FAB2(SCH_1):M_B_DQ<26>
   38  M_B_DQ<25>     DQ<24>  @BASEBOARD_FAB2_LIB.BASEBOARD_FAB2(SCH_1):M_B_DQ<25>
  183  M_B_DQ<24>     DQ<25>  @BASEBOARD_FAB2_LIB.BASEBOARD_FAB2(SCH_1):M_B_DQ<24>
   32  M_B_DQ<23>     DQ<22>  @BASEBOARD_FAB2_LIB.BASEBOARD_FAB2(SCH_1):M_B_DQ<23>
  177  M_B_DQ<22>     DQ<23>  @BASEBOARD_FAB2_LIB.BASEBOARD_FAB2(SCH_1):M_B_DQ<22>
   25  M_B_DQ<21>     DQ<20>  @BASEBOARD_FAB2_LIB.BASEBOARD_FAB2(SCH_1):M_B_DQ<21>
  170  M_B_DQ<20>     DQ<21>  @BASEBOARD_FAB2_LIB.BASEBOARD_FAB2(SCH_1):M_B_DQ<20>
    5  M_B_DQ<1>      DQ<0>  @BASEBOARD_FAB2_LIB.BASEBOARD_FAB2(SCH_1):M_B_DQ<1>
   34  M_B_DQ<19>     DQ<18>  @BASEBOARD_FAB2_LIB.BASEBOARD_FAB2(SCH_1):M_B_DQ<19>
  179  M_B_DQ<18>     DQ<19>  @BASEBOARD_FAB2_LIB.BASEBOARD_FAB2(SCH_1):M_B_DQ<18>
   27  M_B_DQ<17>     DQ<16>  @BASEBOARD_FAB2_LIB.BASEBOARD_FAB2(SCH_1):M_B_DQ<17>
  172  M_B_DQ<16>     DQ<17>  @BASEBOARD_FAB2_LIB.BASEBOARD_FAB2(SCH_1):M_B_DQ<16>
   21  M_B_DQ<15>     DQ<14>  @BASEBOARD_FAB2_LIB.BASEBOARD_FAB2(SCH_1):M_B_DQ<15>
  166  M_B_DQ<14>     DQ<15>  @BASEBOARD_FAB2_LIB.BASEBOARD_FAB2(SCH_1):M_B_DQ<14>
   14  M_B_DQ<13>     DQ<12>  @BASEBOARD_FAB2_LIB.BASEBOARD_FAB2(SCH_1):M_B_DQ<13>
  159  M_B_DQ<12>     DQ<13>  @BASEBOARD_FAB2_LIB.BASEBOARD_FAB2(SCH_1):M_B_DQ<12>
   23  M_B_DQ<11>     DQ<10>  @BASEBOARD_FAB2_LIB.BASEBOARD_FAB2(SCH_1):M_B_DQ<11>
  168  M_B_DQ<10>     DQ<11>  @BASEBOARD_FAB2_LIB.BASEBOARD_FAB2(SCH_1):M_B_DQ<10>
  150  M_B_DQ<0>      DQ<1>  @BASEBOARD_FAB2_LIB.BASEBOARD_FAB2(SCH_1):M_B_DQ<0>
  237  M_B_CS_N<3>    S3_N_C<1>  @BASEBOARD_FAB2_LIB.BASEBOARD_FAB2(SCH_1):M_B_CS_N<3>
   93  M_B_CS_N<2>    S2_N_C<0>  @BASEBOARD_FAB2_LIB.BASEBOARD_FAB2(SCH_1):M_B_CS_N<2>
   89  M_B_CS_N<1>     S1_N  @BASEBOARD_FAB2_LIB.BASEBOARD_FAB2(SCH_1):M_B_CS_N<1>
   84  M_B_CS_N<0>     S0_N  @BASEBOARD_FAB2_LIB.BASEBOARD_FAB2(SCH_1):M_B_CS_N<0>
  218  M_B_CLK_DP<1>   CK1P  @BASEBOARD_FAB2_LIB.BASEBOARD_FAB2(SCH_1):M_B_CLK_DP<1>
   74  M_B_CLK_DP<0>   CK0P  @BASEBOARD_FAB2_LIB.BASEBOARD_FAB2(SCH_1):M_B_CLK_DP<0>
  219  M_B_CLK_DN<1>   CK1N  @BASEBOARD_FAB2_LIB.BASEBOARD_FAB2(SCH_1):M_B_CLK_DN<1>
   75  M_B_CLK_DN<0>   CK0N  @BASEBOARD_FAB2_LIB.BASEBOARD_FAB2(SCH_1):M_B_CLK_DN<0>
  203  M_B_CKE<1>     CKE<1>  @BASEBOARD_FAB2_LIB.BASEBOARD_FAB2(SCH_1):M_B_CKE<1>
   60  M_B_CKE<0>     CKE<0>  @BASEBOARD_FAB2_LIB.BASEBOARD_FAB2(SCH_1):M_B_CKE<0>
  235  M_B_C<2>        C<2>  @BASEBOARD_FAB2_LIB.BASEBOARD_FAB2(SCH_1):M_B_C<2>
  207  M_B_BG<1>      BG<1>  @BASEBOARD_FAB2_LIB.BASEBOARD_FAB2(SCH_1):M_B_BG<1>
   63  M_B_BG<0>      BG<0>  @BASEBOARD_FAB2_LIB.BASEBOARD_FAB2(SCH_1):M_B_BG<0>
  224  M_B_BA<1>      BA<1>  @BASEBOARD_FAB2_LIB.BASEBOARD_FAB2(SCH_1):M_B_BA<1>
   81  M_B_BA<0>      BA<0>  @BASEBOARD_FAB2_LIB.BASEBOARD_FAB2(SCH_1):M_B_BA<0>
  208  M_B_ALERT_N    ALERT_N  @BASEBOARD_FAB2_LIB.BASEBOARD_FAB2(SCH_1):M_B_ALERT_N
   62  M_B_ACT_N      ACT_N  @BASEBOARD_FAB2_LIB.BASEBOARD_FAB2(SCH_1):M_B_ACT_N
   58  M_ABC_RST_N    RESET_N  @BASEBOARD_FAB2_LIB.BASEBOARD_FAB2(SCH_1):M_ABC_RST_N
  238  GND            SA<2>  @BASEBOARD_FAB2_LIB.BASEBOARD_FAB2(SCH_1):GND
  139  GND            SA<0>  @BASEBOARD_FAB2_LIB.BASEBOARD_FAB2(SCH_1):GND
   78  FM_DIMM_EVENT_COD_N  EVENT_N  @BASEBOARD_FAB2_LIB.BASEBOARD_FAB2(SCH_1):FM_DIMM_EVENT_COD_N
  230  FM_ADR_COMPLETE_ABC_N  SAVE_N_NC  @BASEBOARD_FAB2_LIB.BASEBOARD_FAB2(SCH_1):FM_ADR_COMPLETE_ABC_N

SCONN288_H44441004_PIP  I179  J4G3   [SCONN288_H44441004_PIP-SCONN,HA]
   77  PVTT_ABC       VTT<1>  @BASEBOARD_FAB2_LIB.BASEBOARD_FAB2(SCH_1):PVTT_ABC
  221  PVTT_ABC       VTT<0>  @BASEBOARD_FAB2_LIB.BASEBOARD_FAB2(SCH_1):PVTT_ABC
  142  PVPP_ABC       VPP<4>  @BASEBOARD_FAB2_LIB.BASEBOARD_FAB2(SCH_1):PVPP_ABC
  143  PVPP_ABC       VPP<3>  @BASEBOARD_FAB2_LIB.BASEBOARD_FAB2(SCH_1):PVPP_ABC
  288  PVPP_ABC       VPP<2>  @BASEBOARD_FAB2_LIB.BASEBOARD_FAB2(SCH_1):PVPP_ABC
  286  PVPP_ABC       VPP<1>  @BASEBOARD_FAB2_LIB.BASEBOARD_FAB2(SCH_1):PVPP_ABC
  287  PVPP_ABC       VPP<0>  @BASEBOARD_FAB2_LIB.BASEBOARD_FAB2(SCH_1):PVPP_ABC
   59  PVDDQ_ABC      VDD<25>  @BASEBOARD_FAB2_LIB.BASEBOARD_FAB2(SCH_1):PVDDQ_ABC
   61  PVDDQ_ABC      VDD<24>  @BASEBOARD_FAB2_LIB.BASEBOARD_FAB2(SCH_1):PVDDQ_ABC
   64  PVDDQ_ABC      VDD<23>  @BASEBOARD_FAB2_LIB.BASEBOARD_FAB2(SCH_1):PVDDQ_ABC
   67  PVDDQ_ABC      VDD<22>  @BASEBOARD_FAB2_LIB.BASEBOARD_FAB2(SCH_1):PVDDQ_ABC
   70  PVDDQ_ABC      VDD<21>  @BASEBOARD_FAB2_LIB.BASEBOARD_FAB2(SCH_1):PVDDQ_ABC
   73  PVDDQ_ABC      VDD<20>  @BASEBOARD_FAB2_LIB.BASEBOARD_FAB2(SCH_1):PVDDQ_ABC
   76  PVDDQ_ABC      VDD<19>  @BASEBOARD_FAB2_LIB.BASEBOARD_FAB2(SCH_1):PVDDQ_ABC
   80  PVDDQ_ABC      VDD<18>  @BASEBOARD_FAB2_LIB.BASEBOARD_FAB2(SCH_1):PVDDQ_ABC
   83  PVDDQ_ABC      VDD<17>  @BASEBOARD_FAB2_LIB.BASEBOARD_FAB2(SCH_1):PVDDQ_ABC
   85  PVDDQ_ABC      VDD<16>  @BASEBOARD_FAB2_LIB.BASEBOARD_FAB2(SCH_1):PVDDQ_ABC
   88  PVDDQ_ABC      VDD<15>  @BASEBOARD_FAB2_LIB.BASEBOARD_FAB2(SCH_1):PVDDQ_ABC
   90  PVDDQ_ABC      VDD<14>  @BASEBOARD_FAB2_LIB.BASEBOARD_FAB2(SCH_1):PVDDQ_ABC
   92  PVDDQ_ABC      VDD<13>  @BASEBOARD_FAB2_LIB.BASEBOARD_FAB2(SCH_1):PVDDQ_ABC
  204  PVDDQ_ABC      VDD<12>  @BASEBOARD_FAB2_LIB.BASEBOARD_FAB2(SCH_1):PVDDQ_ABC
  206  PVDDQ_ABC      VDD<11>  @BASEBOARD_FAB2_LIB.BASEBOARD_FAB2(SCH_1):PVDDQ_ABC
  209  PVDDQ_ABC      VDD<10>  @BASEBOARD_FAB2_LIB.BASEBOARD_FAB2(SCH_1):PVDDQ_ABC
  212  PVDDQ_ABC      VDD<9>  @BASEBOARD_FAB2_LIB.BASEBOARD_FAB2(SCH_1):PVDDQ_ABC
  215  PVDDQ_ABC      VDD<8>  @BASEBOARD_FAB2_LIB.BASEBOARD_FAB2(SCH_1):PVDDQ_ABC
  217  PVDDQ_ABC      VDD<7>  @BASEBOARD_FAB2_LIB.BASEBOARD_FAB2(SCH_1):PVDDQ_ABC
  220  PVDDQ_ABC      VDD<6>  @BASEBOARD_FAB2_LIB.BASEBOARD_FAB2(SCH_1):PVDDQ_ABC
  223  PVDDQ_ABC      VDD<5>  @BASEBOARD_FAB2_LIB.BASEBOARD_FAB2(SCH_1):PVDDQ_ABC
  226  PVDDQ_ABC      VDD<4>  @BASEBOARD_FAB2_LIB.BASEBOARD_FAB2(SCH_1):PVDDQ_ABC
  229  PVDDQ_ABC      VDD<3>  @BASEBOARD_FAB2_LIB.BASEBOARD_FAB2(SCH_1):PVDDQ_ABC
  231  PVDDQ_ABC      VDD<2>  @BASEBOARD_FAB2_LIB.BASEBOARD_FAB2(SCH_1):PVDDQ_ABC
  233  PVDDQ_ABC      VDD<1>  @BASEBOARD_FAB2_LIB.BASEBOARD_FAB2(SCH_1):PVDDQ_ABC
  236  PVDDQ_ABC      VDD<0>  @BASEBOARD_FAB2_LIB.BASEBOARD_FAB2(SCH_1):PVDDQ_ABC
    1  P12V_NVDIMM_ABC  12V<1>  @BASEBOARD_FAB2_LIB.BASEBOARD_FAB2(SCH_1):P12V_NVDIMM_ABC
  145  P12V_NVDIMM_ABC  12V<0>  @BASEBOARD_FAB2_LIB.BASEBOARD_FAB2(SCH_1):P12V_NVDIMM_ABC

SCONN288_H44441004_PIP  I43  J4G3   [SCONN288_H44441004_PIP-SCONN,HA]
    2  GND            VSS<93>  @BASEBOARD_FAB2_LIB.BASEBOARD_FAB2(SCH_1):GND
    4  GND            VSS<92>  @BASEBOARD_FAB2_LIB.BASEBOARD_FAB2(SCH_1):GND
    6  GND            VSS<91>  @BASEBOARD_FAB2_LIB.BASEBOARD_FAB2(SCH_1):GND
    9  GND            VSS<90>  @BASEBOARD_FAB2_LIB.BASEBOARD_FAB2(SCH_1):GND
   11  GND            VSS<89>  @BASEBOARD_FAB2_LIB.BASEBOARD_FAB2(SCH_1):GND
   13  GND            VSS<88>  @BASEBOARD_FAB2_LIB.BASEBOARD_FAB2(SCH_1):GND
   15  GND            VSS<87>  @BASEBOARD_FAB2_LIB.BASEBOARD_FAB2(SCH_1):GND
   17  GND            VSS<86>  @BASEBOARD_FAB2_LIB.BASEBOARD_FAB2(SCH_1):GND
   20  GND            VSS<85>  @BASEBOARD_FAB2_LIB.BASEBOARD_FAB2(SCH_1):GND
   22  GND            VSS<84>  @BASEBOARD_FAB2_LIB.BASEBOARD_FAB2(SCH_1):GND
   24  GND            VSS<83>  @BASEBOARD_FAB2_LIB.BASEBOARD_FAB2(SCH_1):GND
   26  GND            VSS<82>  @BASEBOARD_FAB2_LIB.BASEBOARD_FAB2(SCH_1):GND
   28  GND            VSS<81>  @BASEBOARD_FAB2_LIB.BASEBOARD_FAB2(SCH_1):GND
   31  GND            VSS<80>  @BASEBOARD_FAB2_LIB.BASEBOARD_FAB2(SCH_1):GND
   33  GND            VSS<79>  @BASEBOARD_FAB2_LIB.BASEBOARD_FAB2(SCH_1):GND
   35  GND            VSS<78>  @BASEBOARD_FAB2_LIB.BASEBOARD_FAB2(SCH_1):GND
   37  GND            VSS<77>  @BASEBOARD_FAB2_LIB.BASEBOARD_FAB2(SCH_1):GND
   39  GND            VSS<76>  @BASEBOARD_FAB2_LIB.BASEBOARD_FAB2(SCH_1):GND
   42  GND            VSS<75>  @BASEBOARD_FAB2_LIB.BASEBOARD_FAB2(SCH_1):GND
   44  GND            VSS<74>  @BASEBOARD_FAB2_LIB.BASEBOARD_FAB2(SCH_1):GND
   46  GND            VSS<73>  @BASEBOARD_FAB2_LIB.BASEBOARD_FAB2(SCH_1):GND
   48  GND            VSS<72>  @BASEBOARD_FAB2_LIB.BASEBOARD_FAB2(SCH_1):GND
   50  GND            VSS<71>  @BASEBOARD_FAB2_LIB.BASEBOARD_FAB2(SCH_1):GND
   53  GND            VSS<70>  @BASEBOARD_FAB2_LIB.BASEBOARD_FAB2(SCH_1):GND
   55  GND            VSS<69>  @BASEBOARD_FAB2_LIB.BASEBOARD_FAB2(SCH_1):GND
   57  GND            VSS<68>  @BASEBOARD_FAB2_LIB.BASEBOARD_FAB2(SCH_1):GND
   94  GND            VSS<67>  @BASEBOARD_FAB2_LIB.BASEBOARD_FAB2(SCH_1):GND
   96  GND            VSS<66>  @BASEBOARD_FAB2_LIB.BASEBOARD_FAB2(SCH_1):GND
   98  GND            VSS<65>  @BASEBOARD_FAB2_LIB.BASEBOARD_FAB2(SCH_1):GND
  101  GND            VSS<64>  @BASEBOARD_FAB2_LIB.BASEBOARD_FAB2(SCH_1):GND
  103  GND            VSS<63>  @BASEBOARD_FAB2_LIB.BASEBOARD_FAB2(SCH_1):GND
  105  GND            VSS<62>  @BASEBOARD_FAB2_LIB.BASEBOARD_FAB2(SCH_1):GND
  107  GND            VSS<61>  @BASEBOARD_FAB2_LIB.BASEBOARD_FAB2(SCH_1):GND
  109  GND            VSS<60>  @BASEBOARD_FAB2_LIB.BASEBOARD_FAB2(SCH_1):GND
  112  GND            VSS<59>  @BASEBOARD_FAB2_LIB.BASEBOARD_FAB2(SCH_1):GND
  114  GND            VSS<58>  @BASEBOARD_FAB2_LIB.BASEBOARD_FAB2(SCH_1):GND
  116  GND            VSS<57>  @BASEBOARD_FAB2_LIB.BASEBOARD_FAB2(SCH_1):GND
  118  GND            VSS<56>  @BASEBOARD_FAB2_LIB.BASEBOARD_FAB2(SCH_1):GND
  120  GND            VSS<55>  @BASEBOARD_FAB2_LIB.BASEBOARD_FAB2(SCH_1):GND
  123  GND            VSS<54>  @BASEBOARD_FAB2_LIB.BASEBOARD_FAB2(SCH_1):GND
  125  GND            VSS<53>  @BASEBOARD_FAB2_LIB.BASEBOARD_FAB2(SCH_1):GND
  127  GND            VSS<52>  @BASEBOARD_FAB2_LIB.BASEBOARD_FAB2(SCH_1):GND
  129  GND            VSS<51>  @BASEBOARD_FAB2_LIB.BASEBOARD_FAB2(SCH_1):GND
  131  GND            VSS<50>  @BASEBOARD_FAB2_LIB.BASEBOARD_FAB2(SCH_1):GND
  134  GND            VSS<49>  @BASEBOARD_FAB2_LIB.BASEBOARD_FAB2(SCH_1):GND
  136  GND            VSS<48>  @BASEBOARD_FAB2_LIB.BASEBOARD_FAB2(SCH_1):GND
  138  GND            VSS<47>  @BASEBOARD_FAB2_LIB.BASEBOARD_FAB2(SCH_1):GND
  147  GND            VSS<46>  @BASEBOARD_FAB2_LIB.BASEBOARD_FAB2(SCH_1):GND
  149  GND            VSS<45>  @BASEBOARD_FAB2_LIB.BASEBOARD_FAB2(SCH_1):GND
  151  GND            VSS<44>  @BASEBOARD_FAB2_LIB.BASEBOARD_FAB2(SCH_1):GND
  154  GND            VSS<43>  @BASEBOARD_FAB2_LIB.BASEBOARD_FAB2(SCH_1):GND
  156  GND            VSS<42>  @BASEBOARD_FAB2_LIB.BASEBOARD_FAB2(SCH_1):GND
  158  GND            VSS<41>  @BASEBOARD_FAB2_LIB.BASEBOARD_FAB2(SCH_1):GND
  160  GND            VSS<40>  @BASEBOARD_FAB2_LIB.BASEBOARD_FAB2(SCH_1):GND
  162  GND            VSS<39>  @BASEBOARD_FAB2_LIB.BASEBOARD_FAB2(SCH_1):GND
  165  GND            VSS<38>  @BASEBOARD_FAB2_LIB.BASEBOARD_FAB2(SCH_1):GND
  167  GND            VSS<37>  @BASEBOARD_FAB2_LIB.BASEBOARD_FAB2(SCH_1):GND
  169  GND            VSS<36>  @BASEBOARD_FAB2_LIB.BASEBOARD_FAB2(SCH_1):GND
  171  GND            VSS<35>  @BASEBOARD_FAB2_LIB.BASEBOARD_FAB2(SCH_1):GND
  173  GND            VSS<34>  @BASEBOARD_FAB2_LIB.BASEBOARD_FAB2(SCH_1):GND
  176  GND            VSS<33>  @BASEBOARD_FAB2_LIB.BASEBOARD_FAB2(SCH_1):GND
  178  GND            VSS<32>  @BASEBOARD_FAB2_LIB.BASEBOARD_FAB2(SCH_1):GND
  180  GND            VSS<31>  @BASEBOARD_FAB2_LIB.BASEBOARD_FAB2(SCH_1):GND
  182  GND            VSS<30>  @BASEBOARD_FAB2_LIB.BASEBOARD_FAB2(SCH_1):GND
  184  GND            VSS<29>  @BASEBOARD_FAB2_LIB.BASEBOARD_FAB2(SCH_1):GND
  187  GND            VSS<28>  @BASEBOARD_FAB2_LIB.BASEBOARD_FAB2(SCH_1):GND
  189  GND            VSS<27>  @BASEBOARD_FAB2_LIB.BASEBOARD_FAB2(SCH_1):GND
  191  GND            VSS<26>  @BASEBOARD_FAB2_LIB.BASEBOARD_FAB2(SCH_1):GND
  193  GND            VSS<25>  @BASEBOARD_FAB2_LIB.BASEBOARD_FAB2(SCH_1):GND
  195  GND            VSS<24>  @BASEBOARD_FAB2_LIB.BASEBOARD_FAB2(SCH_1):GND
  198  GND            VSS<23>  @BASEBOARD_FAB2_LIB.BASEBOARD_FAB2(SCH_1):GND
  200  GND            VSS<22>  @BASEBOARD_FAB2_LIB.BASEBOARD_FAB2(SCH_1):GND
  202  GND            VSS<21>  @BASEBOARD_FAB2_LIB.BASEBOARD_FAB2(SCH_1):GND
  239  GND            VSS<20>  @BASEBOARD_FAB2_LIB.BASEBOARD_FAB2(SCH_1):GND
  241  GND            VSS<19>  @BASEBOARD_FAB2_LIB.BASEBOARD_FAB2(SCH_1):GND
  243  GND            VSS<18>  @BASEBOARD_FAB2_LIB.BASEBOARD_FAB2(SCH_1):GND
  246  GND            VSS<17>  @BASEBOARD_FAB2_LIB.BASEBOARD_FAB2(SCH_1):GND
  248  GND            VSS<16>  @BASEBOARD_FAB2_LIB.BASEBOARD_FAB2(SCH_1):GND
  250  GND            VSS<15>  @BASEBOARD_FAB2_LIB.BASEBOARD_FAB2(SCH_1):GND
  252  GND            VSS<14>  @BASEBOARD_FAB2_LIB.BASEBOARD_FAB2(SCH_1):GND
  254  GND            VSS<13>  @BASEBOARD_FAB2_LIB.BASEBOARD_FAB2(SCH_1):GND
  257  GND            VSS<12>  @BASEBOARD_FAB2_LIB.BASEBOARD_FAB2(SCH_1):GND
  259  GND            VSS<11>  @BASEBOARD_FAB2_LIB.BASEBOARD_FAB2(SCH_1):GND
  261  GND            VSS<10>  @BASEBOARD_FAB2_LIB.BASEBOARD_FAB2(SCH_1):GND
  263  GND            VSS<9>  @BASEBOARD_FAB2_LIB.BASEBOARD_FAB2(SCH_1):GND
  265  GND            VSS<8>  @BASEBOARD_FAB2_LIB.BASEBOARD_FAB2(SCH_1):GND
  268  GND            VSS<7>  @BASEBOARD_FAB2_LIB.BASEBOARD_FAB2(SCH_1):GND
  270  GND            VSS<6>  @BASEBOARD_FAB2_LIB.BASEBOARD_FAB2(SCH_1):GND
  272  GND            VSS<5>  @BASEBOARD_FAB2_LIB.BASEBOARD_FAB2(SCH_1):GND
  274  GND            VSS<4>  @BASEBOARD_FAB2_LIB.BASEBOARD_FAB2(SCH_1):GND
  276  GND            VSS<3>  @BASEBOARD_FAB2_LIB.BASEBOARD_FAB2(SCH_1):GND
  279  GND            VSS<2>  @BASEBOARD_FAB2_LIB.BASEBOARD_FAB2(SCH_1):GND
  281  GND            VSS<1>  @BASEBOARD_FAB2_LIB.BASEBOARD_FAB2(SCH_1):GND
  283  GND            VSS<0>  @BASEBOARD_FAB2_LIB.BASEBOARD_FAB2(SCH_1):GND

SCONN288_H44441004_PIP  I61  J4G3   [SCONN288_H44441004_PIP-SCONN,HA]
    7  M_C_DQS_DP<9>  DQS9P  @BASEBOARD_FAB2_LIB.BASEBOARD_FAB2(SCH_1):M_C_DQS_DP<9>
  197  M_C_DQS_DP<8>  DQS8P  @BASEBOARD_FAB2_LIB.BASEBOARD_FAB2(SCH_1):M_C_DQS_DP<8>
  278  M_C_DQS_DP<7>  DQS7P  @BASEBOARD_FAB2_LIB.BASEBOARD_FAB2(SCH_1):M_C_DQS_DP<7>
  267  M_C_DQS_DP<6>  DQS6P  @BASEBOARD_FAB2_LIB.BASEBOARD_FAB2(SCH_1):M_C_DQS_DP<6>
  256  M_C_DQS_DP<5>  DQS5P  @BASEBOARD_FAB2_LIB.BASEBOARD_FAB2(SCH_1):M_C_DQS_DP<5>
  245  M_C_DQS_DP<4>  DQS4P  @BASEBOARD_FAB2_LIB.BASEBOARD_FAB2(SCH_1):M_C_DQS_DP<4>
  186  M_C_DQS_DP<3>  DQS3P  @BASEBOARD_FAB2_LIB.BASEBOARD_FAB2(SCH_1):M_C_DQS_DP<3>
  175  M_C_DQS_DP<2>  DQS2P  @BASEBOARD_FAB2_LIB.BASEBOARD_FAB2(SCH_1):M_C_DQS_DP<2>
  164  M_C_DQS_DP<1>  DQS1P  @BASEBOARD_FAB2_LIB.BASEBOARD_FAB2(SCH_1):M_C_DQS_DP<1>
   51  M_C_DQS_DP<17>  DQS17P  @BASEBOARD_FAB2_LIB.BASEBOARD_FAB2(SCH_1):M_C_DQS_DP<17>
  132  M_C_DQS_DP<16>  DQS16P  @BASEBOARD_FAB2_LIB.BASEBOARD_FAB2(SCH_1):M_C_DQS_DP<16>
  121  M_C_DQS_DP<15>  DQS15P  @BASEBOARD_FAB2_LIB.BASEBOARD_FAB2(SCH_1):M_C_DQS_DP<15>
  110  M_C_DQS_DP<14>  DQS14P  @BASEBOARD_FAB2_LIB.BASEBOARD_FAB2(SCH_1):M_C_DQS_DP<14>
   99  M_C_DQS_DP<13>  DQS13P  @BASEBOARD_FAB2_LIB.BASEBOARD_FAB2(SCH_1):M_C_DQS_DP<13>
   40  M_C_DQS_DP<12>  DQS12P  @BASEBOARD_FAB2_LIB.BASEBOARD_FAB2(SCH_1):M_C_DQS_DP<12>
   29  M_C_DQS_DP<11>  DQS11P  @BASEBOARD_FAB2_LIB.BASEBOARD_FAB2(SCH_1):M_C_DQS_DP<11>
   18  M_C_DQS_DP<10>  DQS10P  @BASEBOARD_FAB2_LIB.BASEBOARD_FAB2(SCH_1):M_C_DQS_DP<10>
  153  M_C_DQS_DP<0>  DQS0P  @BASEBOARD_FAB2_LIB.BASEBOARD_FAB2(SCH_1):M_C_DQS_DP<0>
    8  M_C_DQS_DN<9>  DQS9N  @BASEBOARD_FAB2_LIB.BASEBOARD_FAB2(SCH_1):M_C_DQS_DN<9>
  196  M_C_DQS_DN<8>  DQS8N  @BASEBOARD_FAB2_LIB.BASEBOARD_FAB2(SCH_1):M_C_DQS_DN<8>
  277  M_C_DQS_DN<7>  DQS7N  @BASEBOARD_FAB2_LIB.BASEBOARD_FAB2(SCH_1):M_C_DQS_DN<7>
  266  M_C_DQS_DN<6>  DQS6N  @BASEBOARD_FAB2_LIB.BASEBOARD_FAB2(SCH_1):M_C_DQS_DN<6>
  255  M_C_DQS_DN<5>  DQS5N  @BASEBOARD_FAB2_LIB.BASEBOARD_FAB2(SCH_1):M_C_DQS_DN<5>
  244  M_C_DQS_DN<4>  DQS4N  @BASEBOARD_FAB2_LIB.BASEBOARD_FAB2(SCH_1):M_C_DQS_DN<4>
  185  M_C_DQS_DN<3>  DQS3N  @BASEBOARD_FAB2_LIB.BASEBOARD_FAB2(SCH_1):M_C_DQS_DN<3>
  174  M_C_DQS_DN<2>  DQS2N  @BASEBOARD_FAB2_LIB.BASEBOARD_FAB2(SCH_1):M_C_DQS_DN<2>
  163  M_C_DQS_DN<1>  DQS1N  @BASEBOARD_FAB2_LIB.BASEBOARD_FAB2(SCH_1):M_C_DQS_DN<1>
   52  M_C_DQS_DN<17>  DQS17N  @BASEBOARD_FAB2_LIB.BASEBOARD_FAB2(SCH_1):M_C_DQS_DN<17>
  133  M_C_DQS_DN<16>  DQS16N  @BASEBOARD_FAB2_LIB.BASEBOARD_FAB2(SCH_1):M_C_DQS_DN<16>
  122  M_C_DQS_DN<15>  DQS15N  @BASEBOARD_FAB2_LIB.BASEBOARD_FAB2(SCH_1):M_C_DQS_DN<15>
  111  M_C_DQS_DN<14>  DQS14N  @BASEBOARD_FAB2_LIB.BASEBOARD_FAB2(SCH_1):M_C_DQS_DN<14>
  100  M_C_DQS_DN<13>  DQS13N  @BASEBOARD_FAB2_LIB.BASEBOARD_FAB2(SCH_1):M_C_DQS_DN<13>
   41  M_C_DQS_DN<12>  DQS12N  @BASEBOARD_FAB2_LIB.BASEBOARD_FAB2(SCH_1):M_C_DQS_DN<12>
   30  M_C_DQS_DN<11>  DQS11N  @BASEBOARD_FAB2_LIB.BASEBOARD_FAB2(SCH_1):M_C_DQS_DN<11>
   19  M_C_DQS_DN<10>  DQS10N  @BASEBOARD_FAB2_LIB.BASEBOARD_FAB2(SCH_1):M_C_DQS_DN<10>
  152  M_C_DQS_DN<0>  DQS0N  @BASEBOARD_FAB2_LIB.BASEBOARD_FAB2(SCH_1):M_C_DQS_DN<0>

SCONN288_H44441004_PIP  I111  J4G3   [SCONN288_H44441004_PIP-SCONN,HA]
  144  TP_CH_C_DIMM_C0_RFU_2  RFU<2>  @BASEBOARD_FAB2_LIB.BASEBOARD_FAB2(SCH_1):TP_CH_C_DIMM_C0_RFU_2
  227  TP_CH_C_DIMM_C0_RFU_1  RFU<1>  @BASEBOARD_FAB2_LIB.BASEBOARD_FAB2(SCH_1):TP_CH_C_DIMM_C0_RFU_1
  205  TP_CH_C_DIMM_C0_RFU_0  RFU<0>  @BASEBOARD_FAB2_LIB.BASEBOARD_FAB2(SCH_1):TP_CH_C_DIMM_C0_RFU_0
  285  SMB_DDR_ABC_VPP_SDA    SDA  @BASEBOARD_FAB2_LIB.BASEBOARD_FAB2(SCH_1):SMB_DDR_ABC_VPP_SDA
  141  SMB_DDR_ABC_VPP_SCL    SCL  @BASEBOARD_FAB2_LIB.BASEBOARD_FAB2(SCH_1):SMB_DDR_ABC_VPP_SCL
  284  PVPP_ABC       VDDSPD  @BASEBOARD_FAB2_LIB.BASEBOARD_FAB2(SCH_1):PVPP_ABC
  238  PVPP_ABC       SA<2>  @BASEBOARD_FAB2_LIB.BASEBOARD_FAB2(SCH_1):PVPP_ABC
  146  M_C_VREF       VREFCA  @BASEBOARD_FAB2_LIB.BASEBOARD_FAB2(SCH_1):M_C_VREF
  222  M_C_PAR          PAR  @BASEBOARD_FAB2_LIB.BASEBOARD_FAB2(SCH_1):M_C_PAR
   91  M_C_ODT<1>     ODT<1>  @BASEBOARD_FAB2_LIB.BASEBOARD_FAB2(SCH_1):M_C_ODT<1>
   87  M_C_ODT<0>     ODT<0>  @BASEBOARD_FAB2_LIB.BASEBOARD_FAB2(SCH_1):M_C_ODT<0>
   66  M_C_MA<9>         A9  @BASEBOARD_FAB2_LIB.BASEBOARD_FAB2(SCH_1):M_C_MA<9>
   68  M_C_MA<8>         A8  @BASEBOARD_FAB2_LIB.BASEBOARD_FAB2(SCH_1):M_C_MA<8>
  211  M_C_MA<7>         A7  @BASEBOARD_FAB2_LIB.BASEBOARD_FAB2(SCH_1):M_C_MA<7>
   69  M_C_MA<6>         A6  @BASEBOARD_FAB2_LIB.BASEBOARD_FAB2(SCH_1):M_C_MA<6>
  213  M_C_MA<5>         A5  @BASEBOARD_FAB2_LIB.BASEBOARD_FAB2(SCH_1):M_C_MA<5>
  214  M_C_MA<4>         A4  @BASEBOARD_FAB2_LIB.BASEBOARD_FAB2(SCH_1):M_C_MA<4>
   71  M_C_MA<3>         A3  @BASEBOARD_FAB2_LIB.BASEBOARD_FAB2(SCH_1):M_C_MA<3>
  216  M_C_MA<2>         A2  @BASEBOARD_FAB2_LIB.BASEBOARD_FAB2(SCH_1):M_C_MA<2>
   72  M_C_MA<1>         A1  @BASEBOARD_FAB2_LIB.BASEBOARD_FAB2(SCH_1):M_C_MA<1>
  234  M_C_MA<17>       A17  @BASEBOARD_FAB2_LIB.BASEBOARD_FAB2(SCH_1):M_C_MA<17>
   82  M_C_MA<16>     A16_RAS_N  @BASEBOARD_FAB2_LIB.BASEBOARD_FAB2(SCH_1):M_C_MA<16>
   86  M_C_MA<15>     A15_CAS_N  @BASEBOARD_FAB2_LIB.BASEBOARD_FAB2(SCH_1):M_C_MA<15>
  228  M_C_MA<14>     A14_WE_N  @BASEBOARD_FAB2_LIB.BASEBOARD_FAB2(SCH_1):M_C_MA<14>
  232  M_C_MA<13>       A13  @BASEBOARD_FAB2_LIB.BASEBOARD_FAB2(SCH_1):M_C_MA<13>
   65  M_C_MA<12>       A12  @BASEBOARD_FAB2_LIB.BASEBOARD_FAB2(SCH_1):M_C_MA<12>
  210  M_C_MA<11>       A11  @BASEBOARD_FAB2_LIB.BASEBOARD_FAB2(SCH_1):M_C_MA<11>
  225  M_C_MA<10>       A10  @BASEBOARD_FAB2_LIB.BASEBOARD_FAB2(SCH_1):M_C_MA<10>
   79  M_C_MA<0>         A0  @BASEBOARD_FAB2_LIB.BASEBOARD_FAB2(SCH_1):M_C_MA<0>
   54  M_C_ECC<7>     CB<6>  @BASEBOARD_FAB2_LIB.BASEBOARD_FAB2(SCH_1):M_C_ECC<7>
  199  M_C_ECC<6>     CB<7>  @BASEBOARD_FAB2_LIB.BASEBOARD_FAB2(SCH_1):M_C_ECC<6>
   47  M_C_ECC<5>     CB<4>  @BASEBOARD_FAB2_LIB.BASEBOARD_FAB2(SCH_1):M_C_ECC<5>
  192  M_C_ECC<4>     CB<5>  @BASEBOARD_FAB2_LIB.BASEBOARD_FAB2(SCH_1):M_C_ECC<4>
   56  M_C_ECC<3>     CB<2>  @BASEBOARD_FAB2_LIB.BASEBOARD_FAB2(SCH_1):M_C_ECC<3>
  201  M_C_ECC<2>     CB<3>  @BASEBOARD_FAB2_LIB.BASEBOARD_FAB2(SCH_1):M_C_ECC<2>
   49  M_C_ECC<1>     CB<0>  @BASEBOARD_FAB2_LIB.BASEBOARD_FAB2(SCH_1):M_C_ECC<1>
  194  M_C_ECC<0>     CB<1>  @BASEBOARD_FAB2_LIB.BASEBOARD_FAB2(SCH_1):M_C_ECC<0>
   16  M_C_DQ<9>      DQ<8>  @BASEBOARD_FAB2_LIB.BASEBOARD_FAB2(SCH_1):M_C_DQ<9>
  161  M_C_DQ<8>      DQ<9>  @BASEBOARD_FAB2_LIB.BASEBOARD_FAB2(SCH_1):M_C_DQ<8>
   10  M_C_DQ<7>      DQ<6>  @BASEBOARD_FAB2_LIB.BASEBOARD_FAB2(SCH_1):M_C_DQ<7>
  155  M_C_DQ<6>      DQ<7>  @BASEBOARD_FAB2_LIB.BASEBOARD_FAB2(SCH_1):M_C_DQ<6>
  135  M_C_DQ<63>     DQ<62>  @BASEBOARD_FAB2_LIB.BASEBOARD_FAB2(SCH_1):M_C_DQ<63>
  280  M_C_DQ<62>     DQ<63>  @BASEBOARD_FAB2_LIB.BASEBOARD_FAB2(SCH_1):M_C_DQ<62>
  128  M_C_DQ<61>     DQ<60>  @BASEBOARD_FAB2_LIB.BASEBOARD_FAB2(SCH_1):M_C_DQ<61>
  273  M_C_DQ<60>     DQ<61>  @BASEBOARD_FAB2_LIB.BASEBOARD_FAB2(SCH_1):M_C_DQ<60>
    3  M_C_DQ<5>      DQ<4>  @BASEBOARD_FAB2_LIB.BASEBOARD_FAB2(SCH_1):M_C_DQ<5>
  137  M_C_DQ<59>     DQ<58>  @BASEBOARD_FAB2_LIB.BASEBOARD_FAB2(SCH_1):M_C_DQ<59>
  282  M_C_DQ<58>     DQ<59>  @BASEBOARD_FAB2_LIB.BASEBOARD_FAB2(SCH_1):M_C_DQ<58>
  130  M_C_DQ<57>     DQ<56>  @BASEBOARD_FAB2_LIB.BASEBOARD_FAB2(SCH_1):M_C_DQ<57>
  275  M_C_DQ<56>     DQ<57>  @BASEBOARD_FAB2_LIB.BASEBOARD_FAB2(SCH_1):M_C_DQ<56>
  124  M_C_DQ<55>     DQ<54>  @BASEBOARD_FAB2_LIB.BASEBOARD_FAB2(SCH_1):M_C_DQ<55>
  269  M_C_DQ<54>     DQ<55>  @BASEBOARD_FAB2_LIB.BASEBOARD_FAB2(SCH_1):M_C_DQ<54>
  117  M_C_DQ<53>     DQ<52>  @BASEBOARD_FAB2_LIB.BASEBOARD_FAB2(SCH_1):M_C_DQ<53>
  262  M_C_DQ<52>     DQ<53>  @BASEBOARD_FAB2_LIB.BASEBOARD_FAB2(SCH_1):M_C_DQ<52>
  126  M_C_DQ<51>     DQ<50>  @BASEBOARD_FAB2_LIB.BASEBOARD_FAB2(SCH_1):M_C_DQ<51>
  271  M_C_DQ<50>     DQ<51>  @BASEBOARD_FAB2_LIB.BASEBOARD_FAB2(SCH_1):M_C_DQ<50>
  148  M_C_DQ<4>      DQ<5>  @BASEBOARD_FAB2_LIB.BASEBOARD_FAB2(SCH_1):M_C_DQ<4>
  119  M_C_DQ<49>     DQ<48>  @BASEBOARD_FAB2_LIB.BASEBOARD_FAB2(SCH_1):M_C_DQ<49>
  264  M_C_DQ<48>     DQ<49>  @BASEBOARD_FAB2_LIB.BASEBOARD_FAB2(SCH_1):M_C_DQ<48>
  113  M_C_DQ<47>     DQ<46>  @BASEBOARD_FAB2_LIB.BASEBOARD_FAB2(SCH_1):M_C_DQ<47>
  258  M_C_DQ<46>     DQ<47>  @BASEBOARD_FAB2_LIB.BASEBOARD_FAB2(SCH_1):M_C_DQ<46>
  106  M_C_DQ<45>     DQ<44>  @BASEBOARD_FAB2_LIB.BASEBOARD_FAB2(SCH_1):M_C_DQ<45>
  251  M_C_DQ<44>     DQ<45>  @BASEBOARD_FAB2_LIB.BASEBOARD_FAB2(SCH_1):M_C_DQ<44>
  115  M_C_DQ<43>     DQ<42>  @BASEBOARD_FAB2_LIB.BASEBOARD_FAB2(SCH_1):M_C_DQ<43>
  260  M_C_DQ<42>     DQ<43>  @BASEBOARD_FAB2_LIB.BASEBOARD_FAB2(SCH_1):M_C_DQ<42>
  108  M_C_DQ<41>     DQ<40>  @BASEBOARD_FAB2_LIB.BASEBOARD_FAB2(SCH_1):M_C_DQ<41>
  253  M_C_DQ<40>     DQ<41>  @BASEBOARD_FAB2_LIB.BASEBOARD_FAB2(SCH_1):M_C_DQ<40>
   12  M_C_DQ<3>      DQ<2>  @BASEBOARD_FAB2_LIB.BASEBOARD_FAB2(SCH_1):M_C_DQ<3>
  102  M_C_DQ<39>     DQ<38>  @BASEBOARD_FAB2_LIB.BASEBOARD_FAB2(SCH_1):M_C_DQ<39>
  247  M_C_DQ<38>     DQ<39>  @BASEBOARD_FAB2_LIB.BASEBOARD_FAB2(SCH_1):M_C_DQ<38>
   95  M_C_DQ<37>     DQ<36>  @BASEBOARD_FAB2_LIB.BASEBOARD_FAB2(SCH_1):M_C_DQ<37>
  240  M_C_DQ<36>     DQ<37>  @BASEBOARD_FAB2_LIB.BASEBOARD_FAB2(SCH_1):M_C_DQ<36>
  104  M_C_DQ<35>     DQ<34>  @BASEBOARD_FAB2_LIB.BASEBOARD_FAB2(SCH_1):M_C_DQ<35>
  249  M_C_DQ<34>     DQ<35>  @BASEBOARD_FAB2_LIB.BASEBOARD_FAB2(SCH_1):M_C_DQ<34>
   97  M_C_DQ<33>     DQ<32>  @BASEBOARD_FAB2_LIB.BASEBOARD_FAB2(SCH_1):M_C_DQ<33>
  242  M_C_DQ<32>     DQ<33>  @BASEBOARD_FAB2_LIB.BASEBOARD_FAB2(SCH_1):M_C_DQ<32>
   43  M_C_DQ<31>     DQ<30>  @BASEBOARD_FAB2_LIB.BASEBOARD_FAB2(SCH_1):M_C_DQ<31>
  188  M_C_DQ<30>     DQ<31>  @BASEBOARD_FAB2_LIB.BASEBOARD_FAB2(SCH_1):M_C_DQ<30>
  157  M_C_DQ<2>      DQ<3>  @BASEBOARD_FAB2_LIB.BASEBOARD_FAB2(SCH_1):M_C_DQ<2>
   36  M_C_DQ<29>     DQ<28>  @BASEBOARD_FAB2_LIB.BASEBOARD_FAB2(SCH_1):M_C_DQ<29>
  181  M_C_DQ<28>     DQ<29>  @BASEBOARD_FAB2_LIB.BASEBOARD_FAB2(SCH_1):M_C_DQ<28>
   45  M_C_DQ<27>     DQ<26>  @BASEBOARD_FAB2_LIB.BASEBOARD_FAB2(SCH_1):M_C_DQ<27>
  190  M_C_DQ<26>     DQ<27>  @BASEBOARD_FAB2_LIB.BASEBOARD_FAB2(SCH_1):M_C_DQ<26>
   38  M_C_DQ<25>     DQ<24>  @BASEBOARD_FAB2_LIB.BASEBOARD_FAB2(SCH_1):M_C_DQ<25>
  183  M_C_DQ<24>     DQ<25>  @BASEBOARD_FAB2_LIB.BASEBOARD_FAB2(SCH_1):M_C_DQ<24>
   32  M_C_DQ<23>     DQ<22>  @BASEBOARD_FAB2_LIB.BASEBOARD_FAB2(SCH_1):M_C_DQ<23>
  177  M_C_DQ<22>     DQ<23>  @BASEBOARD_FAB2_LIB.BASEBOARD_FAB2(SCH_1):M_C_DQ<22>
   25  M_C_DQ<21>     DQ<20>  @BASEBOARD_FAB2_LIB.BASEBOARD_FAB2(SCH_1):M_C_DQ<21>
  170  M_C_DQ<20>     DQ<21>  @BASEBOARD_FAB2_LIB.BASEBOARD_FAB2(SCH_1):M_C_DQ<20>
    5  M_C_DQ<1>      DQ<0>  @BASEBOARD_FAB2_LIB.BASEBOARD_FAB2(SCH_1):M_C_DQ<1>
   34  M_C_DQ<19>     DQ<18>  @BASEBOARD_FAB2_LIB.BASEBOARD_FAB2(SCH_1):M_C_DQ<19>
  179  M_C_DQ<18>     DQ<19>  @BASEBOARD_FAB2_LIB.BASEBOARD_FAB2(SCH_1):M_C_DQ<18>
   27  M_C_DQ<17>     DQ<16>  @BASEBOARD_FAB2_LIB.BASEBOARD_FAB2(SCH_1):M_C_DQ<17>
  172  M_C_DQ<16>     DQ<17>  @BASEBOARD_FAB2_LIB.BASEBOARD_FAB2(SCH_1):M_C_DQ<16>
   21  M_C_DQ<15>     DQ<14>  @BASEBOARD_FAB2_LIB.BASEBOARD_FAB2(SCH_1):M_C_DQ<15>
  166  M_C_DQ<14>     DQ<15>  @BASEBOARD_FAB2_LIB.BASEBOARD_FAB2(SCH_1):M_C_DQ<14>
   14  M_C_DQ<13>     DQ<12>  @BASEBOARD_FAB2_LIB.BASEBOARD_FAB2(SCH_1):M_C_DQ<13>
  159  M_C_DQ<12>     DQ<13>  @BASEBOARD_FAB2_LIB.BASEBOARD_FAB2(SCH_1):M_C_DQ<12>
   23  M_C_DQ<11>     DQ<10>  @BASEBOARD_FAB2_LIB.BASEBOARD_FAB2(SCH_1):M_C_DQ<11>
  168  M_C_DQ<10>     DQ<11>  @BASEBOARD_FAB2_LIB.BASEBOARD_FAB2(SCH_1):M_C_DQ<10>
  150  M_C_DQ<0>      DQ<1>  @BASEBOARD_FAB2_LIB.BASEBOARD_FAB2(SCH_1):M_C_DQ<0>
  237  M_C_CS_N<3>    S3_N_C<1>  @BASEBOARD_FAB2_LIB.BASEBOARD_FAB2(SCH_1):M_C_CS_N<3>
   93  M_C_CS_N<2>    S2_N_C<0>  @BASEBOARD_FAB2_LIB.BASEBOARD_FAB2(SCH_1):M_C_CS_N<2>
   89  M_C_CS_N<1>     S1_N  @BASEBOARD_FAB2_LIB.BASEBOARD_FAB2(SCH_1):M_C_CS_N<1>
   84  M_C_CS_N<0>     S0_N  @BASEBOARD_FAB2_LIB.BASEBOARD_FAB2(SCH_1):M_C_CS_N<0>
  218  M_C_CLK_DP<1>   CK1P  @BASEBOARD_FAB2_LIB.BASEBOARD_FAB2(SCH_1):M_C_CLK_DP<1>
   74  M_C_CLK_DP<0>   CK0P  @BASEBOARD_FAB2_LIB.BASEBOARD_FAB2(SCH_1):M_C_CLK_DP<0>
  219  M_C_CLK_DN<1>   CK1N  @BASEBOARD_FAB2_LIB.BASEBOARD_FAB2(SCH_1):M_C_CLK_DN<1>
   75  M_C_CLK_DN<0>   CK0N  @BASEBOARD_FAB2_LIB.BASEBOARD_FAB2(SCH_1):M_C_CLK_DN<0>
  203  M_C_CKE<1>     CKE<1>  @BASEBOARD_FAB2_LIB.BASEBOARD_FAB2(SCH_1):M_C_CKE<1>
   60  M_C_CKE<0>     CKE<0>  @BASEBOARD_FAB2_LIB.BASEBOARD_FAB2(SCH_1):M_C_CKE<0>
  235  M_C_C<2>        C<2>  @BASEBOARD_FAB2_LIB.BASEBOARD_FAB2(SCH_1):M_C_C<2>
  207  M_C_BG<1>      BG<1>  @BASEBOARD_FAB2_LIB.BASEBOARD_FAB2(SCH_1):M_C_BG<1>
   63  M_C_BG<0>      BG<0>  @BASEBOARD_FAB2_LIB.BASEBOARD_FAB2(SCH_1):M_C_BG<0>
  224  M_C_BA<1>      BA<1>  @BASEBOARD_FAB2_LIB.BASEBOARD_FAB2(SCH_1):M_C_BA<1>
   81  M_C_BA<0>      BA<0>  @BASEBOARD_FAB2_LIB.BASEBOARD_FAB2(SCH_1):M_C_BA<0>
  208  M_C_ALERT_N    ALERT_N  @BASEBOARD_FAB2_LIB.BASEBOARD_FAB2(SCH_1):M_C_ALERT_N
   62  M_C_ACT_N      ACT_N  @BASEBOARD_FAB2_LIB.BASEBOARD_FAB2(SCH_1):M_C_ACT_N
   58  M_ABC_RST_N    RESET_N  @BASEBOARD_FAB2_LIB.BASEBOARD_FAB2(SCH_1):M_ABC_RST_N
  140  GND            SA<1>  @BASEBOARD_FAB2_LIB.BASEBOARD_FAB2(SCH_1):GND
  139  GND            SA<0>  @BASEBOARD_FAB2_LIB.BASEBOARD_FAB2(SCH_1):GND
   78  FM_DIMM_EVENT_COD_N  EVENT_N  @BASEBOARD_FAB2_LIB.BASEBOARD_FAB2(SCH_1):FM_DIMM_EVENT_COD_N
  230  FM_ADR_COMPLETE_ABC_N  SAVE_N_NC  @BASEBOARD_FAB2_LIB.BASEBOARD_FAB2(SCH_1):FM_ADR_COMPLETE_ABC_N

SCONN120_H61426002_SM  I56  J6B1   [SCONN120_H61426002_SM-CONN,H61A]
   E8  VSENSE_PVCCIOMCP_CPU0_SKT_VSEN   IOE8  @BASEBOARD_FAB2_LIB.BASEBOARD_FAB2(SCH_1):VSENSE_PVCCIOMCP_CPU0_SKT_VSEN
   F8  VSENSE_PVCCIOMCP_CPU0_SKT_VRTN   IOF8  @BASEBOARD_FAB2_LIB.BASEBOARD_FAB2(SCH_1):VSENSE_PVCCIOMCP_CPU0_SKT_VRTN
  F10  VR_PVCCMCP_CPU0_XADDR2  IOF10  @BASEBOARD_FAB2_LIB.BASEBOARD_FAB2(SCH_1):VR_PVCCMCP_CPU0_XADDR2
  E10  VR_PVCCIOMCP_CPU0_XADDR1  IOE10  @BASEBOARD_FAB2_LIB.BASEBOARD_FAB2(SCH_1):VR_PVCCIOMCP_CPU0_XADDR1
  F20  SVID_DIO1_CPU0_R  IOF20  @BASEBOARD_FAB2_LIB.BASEBOARD_FAB2(SCH_1):SVID_DIO1_CPU0_R
  B20  SVID_DIO0_CPU0_R  IOB20  @BASEBOARD_FAB2_LIB.BASEBOARD_FAB2(SCH_1):SVID_DIO0_CPU0_R
  E20  SVID_CLK1_CPU0_R  IOE20  @BASEBOARD_FAB2_LIB.BASEBOARD_FAB2(SCH_1):SVID_CLK1_CPU0_R
  A20  SVID_CLK0_CPU0_R  IOA20  @BASEBOARD_FAB2_LIB.BASEBOARD_FAB2(SCH_1):SVID_CLK0_CPU0_R
  B19  SVID_ALERT1_CPU0_R_N  IOB19  @BASEBOARD_FAB2_LIB.BASEBOARD_FAB2(SCH_1):SVID_ALERT1_CPU0_R_N
  A19  SVID_ALERT0_CPU0_R_N  IOA19  @BASEBOARD_FAB2_LIB.BASEBOARD_FAB2(SCH_1):SVID_ALERT0_CPU0_R_N
  B18  SMB_VR_STBY_LVC3_SDA  IOB18  @BASEBOARD_FAB2_LIB.BASEBOARD_FAB2(SCH_1):SMB_VR_STBY_LVC3_SDA
  A18  SMB_VR_STBY_LVC3_SCL  IOA18  @BASEBOARD_FAB2_LIB.BASEBOARD_FAB2(SCH_1):SMB_VR_STBY_LVC3_SCL
  D20  PWRGD_PVCCMCP_CPU0  IOD20  @BASEBOARD_FAB2_LIB.BASEBOARD_FAB2(SCH_1):PWRGD_PVCCMCP_CPU0
  B16  PWRGD_PVCCIOMCP_CPU0  IOB16  @BASEBOARD_FAB2_LIB.BASEBOARD_FAB2(SCH_1):PWRGD_PVCCIOMCP_CPU0
  B15  PWRGD_P1V8MCP_CPU0  IOB15  @BASEBOARD_FAB2_LIB.BASEBOARD_FAB2(SCH_1):PWRGD_P1V8MCP_CPU0
   F1  PVCCIO_CPU0     IOF1  @BASEBOARD_FAB2_LIB.BASEBOARD_FAB2(SCH_1):PVCCIO_CPU0
  F19  PVCCIOMCP_CPU0  IOF19  @BASEBOARD_FAB2_LIB.BASEBOARD_FAB2(SCH_1):PVCCIOMCP_CPU0
  F18  PVCCIOMCP_CPU0  IOF18  @BASEBOARD_FAB2_LIB.BASEBOARD_FAB2(SCH_1):PVCCIOMCP_CPU0
  F17  PVCCIOMCP_CPU0  IOF17  @BASEBOARD_FAB2_LIB.BASEBOARD_FAB2(SCH_1):PVCCIOMCP_CPU0
  F16  PVCCIOMCP_CPU0  IOF16  @BASEBOARD_FAB2_LIB.BASEBOARD_FAB2(SCH_1):PVCCIOMCP_CPU0
  F15  PVCCIOMCP_CPU0  IOF15  @BASEBOARD_FAB2_LIB.BASEBOARD_FAB2(SCH_1):PVCCIOMCP_CPU0
  E19  PVCCIOMCP_CPU0  IOE19  @BASEBOARD_FAB2_LIB.BASEBOARD_FAB2(SCH_1):PVCCIOMCP_CPU0
  E18  PVCCIOMCP_CPU0  IOE18  @BASEBOARD_FAB2_LIB.BASEBOARD_FAB2(SCH_1):PVCCIOMCP_CPU0
  E17  PVCCIOMCP_CPU0  IOE17  @BASEBOARD_FAB2_LIB.BASEBOARD_FAB2(SCH_1):PVCCIOMCP_CPU0
  E16  PVCCIOMCP_CPU0  IOE16  @BASEBOARD_FAB2_LIB.BASEBOARD_FAB2(SCH_1):PVCCIOMCP_CPU0
  E15  PVCCIOMCP_CPU0  IOE15  @BASEBOARD_FAB2_LIB.BASEBOARD_FAB2(SCH_1):PVCCIOMCP_CPU0
  D19  PVCCIOMCP_CPU0  IOD19  @BASEBOARD_FAB2_LIB.BASEBOARD_FAB2(SCH_1):PVCCIOMCP_CPU0
  D18  PVCCIOMCP_CPU0  IOD18  @BASEBOARD_FAB2_LIB.BASEBOARD_FAB2(SCH_1):PVCCIOMCP_CPU0
  D17  PVCCIOMCP_CPU0  IOD17  @BASEBOARD_FAB2_LIB.BASEBOARD_FAB2(SCH_1):PVCCIOMCP_CPU0
  D16  PVCCIOMCP_CPU0  IOD16  @BASEBOARD_FAB2_LIB.BASEBOARD_FAB2(SCH_1):PVCCIOMCP_CPU0
  D15  PVCCIOMCP_CPU0  IOD15  @BASEBOARD_FAB2_LIB.BASEBOARD_FAB2(SCH_1):PVCCIOMCP_CPU0
  C19  PVCCIOMCP_CPU0  IOC19  @BASEBOARD_FAB2_LIB.BASEBOARD_FAB2(SCH_1):PVCCIOMCP_CPU0
  C18  PVCCIOMCP_CPU0  IOC18  @BASEBOARD_FAB2_LIB.BASEBOARD_FAB2(SCH_1):PVCCIOMCP_CPU0
  C17  PVCCIOMCP_CPU0  IOC17  @BASEBOARD_FAB2_LIB.BASEBOARD_FAB2(SCH_1):PVCCIOMCP_CPU0
  C13  P5V_STBY       IOC13  @BASEBOARD_FAB2_LIB.BASEBOARD_FAB2(SCH_1):P5V_STBY
  B13  P5V_STBY       IOB13  @BASEBOARD_FAB2_LIB.BASEBOARD_FAB2(SCH_1):P5V_STBY
  A13  P5V_STBY       IOA13  @BASEBOARD_FAB2_LIB.BASEBOARD_FAB2(SCH_1):P5V_STBY
  C11  P3V3_STBY      IOC11  @BASEBOARD_FAB2_LIB.BASEBOARD_FAB2(SCH_1):P3V3_STBY
  B11  P3V3_STBY      IOB11  @BASEBOARD_FAB2_LIB.BASEBOARD_FAB2(SCH_1):P3V3_STBY
  A11  P3V3_STBY      IOA11  @BASEBOARD_FAB2_LIB.BASEBOARD_FAB2(SCH_1):P3V3_STBY
   D1  P3V3            IOD1  @BASEBOARD_FAB2_LIB.BASEBOARD_FAB2(SCH_1):P3V3
   B8  P12V_STBY       IOB8  @BASEBOARD_FAB2_LIB.BASEBOARD_FAB2(SCH_1):P12V_STBY
   B7  P12V_STBY       IOB7  @BASEBOARD_FAB2_LIB.BASEBOARD_FAB2(SCH_1):P12V_STBY
   B6  P12V_STBY       IOB6  @BASEBOARD_FAB2_LIB.BASEBOARD_FAB2(SCH_1):P12V_STBY
   B5  P12V_STBY       IOB5  @BASEBOARD_FAB2_LIB.BASEBOARD_FAB2(SCH_1):P12V_STBY
   B4  P12V_STBY       IOB4  @BASEBOARD_FAB2_LIB.BASEBOARD_FAB2(SCH_1):P12V_STBY
   B3  P12V_STBY       IOB3  @BASEBOARD_FAB2_LIB.BASEBOARD_FAB2(SCH_1):P12V_STBY
   B2  P12V_STBY       IOB2  @BASEBOARD_FAB2_LIB.BASEBOARD_FAB2(SCH_1):P12V_STBY
   B1  P12V_STBY       IOB1  @BASEBOARD_FAB2_LIB.BASEBOARD_FAB2(SCH_1):P12V_STBY
   A8  P12V_STBY       IOA8  @BASEBOARD_FAB2_LIB.BASEBOARD_FAB2(SCH_1):P12V_STBY
   A7  P12V_STBY       IOA7  @BASEBOARD_FAB2_LIB.BASEBOARD_FAB2(SCH_1):P12V_STBY
   A6  P12V_STBY       IOA6  @BASEBOARD_FAB2_LIB.BASEBOARD_FAB2(SCH_1):P12V_STBY
   A5  P12V_STBY       IOA5  @BASEBOARD_FAB2_LIB.BASEBOARD_FAB2(SCH_1):P12V_STBY
   A4  P12V_STBY       IOA4  @BASEBOARD_FAB2_LIB.BASEBOARD_FAB2(SCH_1):P12V_STBY
   A3  P12V_STBY       IOA3  @BASEBOARD_FAB2_LIB.BASEBOARD_FAB2(SCH_1):P12V_STBY
   A2  P12V_STBY       IOA2  @BASEBOARD_FAB2_LIB.BASEBOARD_FAB2(SCH_1):P12V_STBY
   A1  P12V_STBY       IOA1  @BASEBOARD_FAB2_LIB.BASEBOARD_FAB2(SCH_1):P12V_STBY
  F14  GND            IOF14  @BASEBOARD_FAB2_LIB.BASEBOARD_FAB2(SCH_1):GND
  F13  GND            IOF13  @BASEBOARD_FAB2_LIB.BASEBOARD_FAB2(SCH_1):GND
  F12  GND            IOF12  @BASEBOARD_FAB2_LIB.BASEBOARD_FAB2(SCH_1):GND
  F11  GND            IOF11  @BASEBOARD_FAB2_LIB.BASEBOARD_FAB2(SCH_1):GND
   F9  GND             IOF9  @BASEBOARD_FAB2_LIB.BASEBOARD_FAB2(SCH_1):GND
   F7  GND             IOF7  @BASEBOARD_FAB2_LIB.BASEBOARD_FAB2(SCH_1):GND
   F6  GND             IOF6  @BASEBOARD_FAB2_LIB.BASEBOARD_FAB2(SCH_1):GND
   F5  GND             IOF5  @BASEBOARD_FAB2_LIB.BASEBOARD_FAB2(SCH_1):GND
   F4  GND             IOF4  @BASEBOARD_FAB2_LIB.BASEBOARD_FAB2(SCH_1):GND
   F3  GND             IOF3  @BASEBOARD_FAB2_LIB.BASEBOARD_FAB2(SCH_1):GND
   F2  GND             IOF2  @BASEBOARD_FAB2_LIB.BASEBOARD_FAB2(SCH_1):GND
  E14  GND            IOE14  @BASEBOARD_FAB2_LIB.BASEBOARD_FAB2(SCH_1):GND
  E13  GND            IOE13  @BASEBOARD_FAB2_LIB.BASEBOARD_FAB2(SCH_1):GND
  E12  GND            IOE12  @BASEBOARD_FAB2_LIB.BASEBOARD_FAB2(SCH_1):GND
  E11  GND            IOE11  @BASEBOARD_FAB2_LIB.BASEBOARD_FAB2(SCH_1):GND
   E9  GND             IOE9  @BASEBOARD_FAB2_LIB.BASEBOARD_FAB2(SCH_1):GND
   E7  GND             IOE7  @BASEBOARD_FAB2_LIB.BASEBOARD_FAB2(SCH_1):GND
   E6  GND             IOE6  @BASEBOARD_FAB2_LIB.BASEBOARD_FAB2(SCH_1):GND
   E5  GND             IOE5  @BASEBOARD_FAB2_LIB.BASEBOARD_FAB2(SCH_1):GND
   E4  GND             IOE4  @BASEBOARD_FAB2_LIB.BASEBOARD_FAB2(SCH_1):GND
   E3  GND             IOE3  @BASEBOARD_FAB2_LIB.BASEBOARD_FAB2(SCH_1):GND
   E2  GND             IOE2  @BASEBOARD_FAB2_LIB.BASEBOARD_FAB2(SCH_1):GND
  D14  GND            IOD14  @BASEBOARD_FAB2_LIB.BASEBOARD_FAB2(SCH_1):GND
  D13  GND            IOD13  @BASEBOARD_FAB2_LIB.BASEBOARD_FAB2(SCH_1):GND
  D12  GND            IOD12  @BASEBOARD_FAB2_LIB.BASEBOARD_FAB2(SCH_1):GND
  D11  GND            IOD11  @BASEBOARD_FAB2_LIB.BASEBOARD_FAB2(SCH_1):GND
  D10  GND            IOD10  @BASEBOARD_FAB2_LIB.BASEBOARD_FAB2(SCH_1):GND
   D9  GND             IOD9  @BASEBOARD_FAB2_LIB.BASEBOARD_FAB2(SCH_1):GND
   D8  GND             IOD8  @BASEBOARD_FAB2_LIB.BASEBOARD_FAB2(SCH_1):GND
   D7  GND             IOD7  @BASEBOARD_FAB2_LIB.BASEBOARD_FAB2(SCH_1):GND
   D6  GND             IOD6  @BASEBOARD_FAB2_LIB.BASEBOARD_FAB2(SCH_1):GND
   D5  GND             IOD5  @BASEBOARD_FAB2_LIB.BASEBOARD_FAB2(SCH_1):GND
   D4  GND             IOD4  @BASEBOARD_FAB2_LIB.BASEBOARD_FAB2(SCH_1):GND
   D3  GND             IOD3  @BASEBOARD_FAB2_LIB.BASEBOARD_FAB2(SCH_1):GND
   D2  GND             IOD2  @BASEBOARD_FAB2_LIB.BASEBOARD_FAB2(SCH_1):GND
  C16  GND            IOC16  @BASEBOARD_FAB2_LIB.BASEBOARD_FAB2(SCH_1):GND
  C15  GND            IOC15  @BASEBOARD_FAB2_LIB.BASEBOARD_FAB2(SCH_1):GND
  C14  GND            IOC14  @BASEBOARD_FAB2_LIB.BASEBOARD_FAB2(SCH_1):GND
  C12  GND            IOC12  @BASEBOARD_FAB2_LIB.BASEBOARD_FAB2(SCH_1):GND
  C10  GND            IOC10  @BASEBOARD_FAB2_LIB.BASEBOARD_FAB2(SCH_1):GND
   C9  GND             IOC9  @BASEBOARD_FAB2_LIB.BASEBOARD_FAB2(SCH_1):GND
   C8  GND             IOC8  @BASEBOARD_FAB2_LIB.BASEBOARD_FAB2(SCH_1):GND
   C7  GND             IOC7  @BASEBOARD_FAB2_LIB.BASEBOARD_FAB2(SCH_1):GND
   C6  GND             IOC6  @BASEBOARD_FAB2_LIB.BASEBOARD_FAB2(SCH_1):GND
   C5  GND             IOC5  @BASEBOARD_FAB2_LIB.BASEBOARD_FAB2(SCH_1):GND
   C4  GND             IOC4  @BASEBOARD_FAB2_LIB.BASEBOARD_FAB2(SCH_1):GND
   C3  GND             IOC3  @BASEBOARD_FAB2_LIB.BASEBOARD_FAB2(SCH_1):GND
   C2  GND             IOC2  @BASEBOARD_FAB2_LIB.BASEBOARD_FAB2(SCH_1):GND
   C1  GND             IOC1  @BASEBOARD_FAB2_LIB.BASEBOARD_FAB2(SCH_1):GND
  B17  GND            IOB17  @BASEBOARD_FAB2_LIB.BASEBOARD_FAB2(SCH_1):GND
  B14  GND            IOB14  @BASEBOARD_FAB2_LIB.BASEBOARD_FAB2(SCH_1):GND
  B12  GND            IOB12  @BASEBOARD_FAB2_LIB.BASEBOARD_FAB2(SCH_1):GND
  B10  GND            IOB10  @BASEBOARD_FAB2_LIB.BASEBOARD_FAB2(SCH_1):GND
   B9  GND             IOB9  @BASEBOARD_FAB2_LIB.BASEBOARD_FAB2(SCH_1):GND
  A17  GND            IOA17  @BASEBOARD_FAB2_LIB.BASEBOARD_FAB2(SCH_1):GND
  A14  GND            IOA14  @BASEBOARD_FAB2_LIB.BASEBOARD_FAB2(SCH_1):GND
  A12  GND            IOA12  @BASEBOARD_FAB2_LIB.BASEBOARD_FAB2(SCH_1):GND
  A10  GND            IOA10  @BASEBOARD_FAB2_LIB.BASEBOARD_FAB2(SCH_1):GND
   A9  GND             IOA9  @BASEBOARD_FAB2_LIB.BASEBOARD_FAB2(SCH_1):GND
  C20  FM_PVCCMCP_CPU0_EN  IOC20  @BASEBOARD_FAB2_LIB.BASEBOARD_FAB2(SCH_1):FM_PVCCMCP_CPU0_EN
  A16  FM_PVCCIOMCP_CPU0_EN  IOA16  @BASEBOARD_FAB2_LIB.BASEBOARD_FAB2(SCH_1):FM_PVCCIOMCP_CPU0_EN
  A15  FM_P1V8MCP_CPU0_EN  IOA15  @BASEBOARD_FAB2_LIB.BASEBOARD_FAB2(SCH_1):FM_P1V8MCP_CPU0_EN
   E1  FM_CPU0_VRM_322M_156M_OSC_EN   IOE1  @BASEBOARD_FAB2_LIB.BASEBOARD_FAB2(SCH_1):FM_CPU0_VRM_322M_156M_OSC_EN

SCONN120_H61426002_SM  I55  J6E1   [SCONN120_H61426002_SM-CONN,H61A]
   A4  VSENSE_PVCCMCP_CPU0_SKT_VSEN   IOA4  @BASEBOARD_FAB2_LIB.BASEBOARD_FAB2(SCH_1):VSENSE_PVCCMCP_CPU0_SKT_VSEN
   B4  VSENSE_PVCCMCP_CPU0_SKT_VRTN   IOB4  @BASEBOARD_FAB2_LIB.BASEBOARD_FAB2(SCH_1):VSENSE_PVCCMCP_CPU0_SKT_VRTN
   D1  VSENSE_P1V8MCP_CPU0_SKT_VSEN   IOD1  @BASEBOARD_FAB2_LIB.BASEBOARD_FAB2(SCH_1):VSENSE_P1V8MCP_CPU0_SKT_VSEN
   D2  VSENSE_P1V8MCP_CPU0_SKT_VRTN   IOD2  @BASEBOARD_FAB2_LIB.BASEBOARD_FAB2(SCH_1):VSENSE_P1V8MCP_CPU0_SKT_VRTN
  C18  PVCCMCP_CPU0   IOC18  @BASEBOARD_FAB2_LIB.BASEBOARD_FAB2(SCH_1):PVCCMCP_CPU0
  C17  PVCCMCP_CPU0   IOC17  @BASEBOARD_FAB2_LIB.BASEBOARD_FAB2(SCH_1):PVCCMCP_CPU0
  C16  PVCCMCP_CPU0   IOC16  @BASEBOARD_FAB2_LIB.BASEBOARD_FAB2(SCH_1):PVCCMCP_CPU0
  C15  PVCCMCP_CPU0   IOC15  @BASEBOARD_FAB2_LIB.BASEBOARD_FAB2(SCH_1):PVCCMCP_CPU0
  C14  PVCCMCP_CPU0   IOC14  @BASEBOARD_FAB2_LIB.BASEBOARD_FAB2(SCH_1):PVCCMCP_CPU0
  C13  PVCCMCP_CPU0   IOC13  @BASEBOARD_FAB2_LIB.BASEBOARD_FAB2(SCH_1):PVCCMCP_CPU0
  C12  PVCCMCP_CPU0   IOC12  @BASEBOARD_FAB2_LIB.BASEBOARD_FAB2(SCH_1):PVCCMCP_CPU0
  C11  PVCCMCP_CPU0   IOC11  @BASEBOARD_FAB2_LIB.BASEBOARD_FAB2(SCH_1):PVCCMCP_CPU0
  C10  PVCCMCP_CPU0   IOC10  @BASEBOARD_FAB2_LIB.BASEBOARD_FAB2(SCH_1):PVCCMCP_CPU0
   C9  PVCCMCP_CPU0    IOC9  @BASEBOARD_FAB2_LIB.BASEBOARD_FAB2(SCH_1):PVCCMCP_CPU0
   C8  PVCCMCP_CPU0    IOC8  @BASEBOARD_FAB2_LIB.BASEBOARD_FAB2(SCH_1):PVCCMCP_CPU0
   C7  PVCCMCP_CPU0    IOC7  @BASEBOARD_FAB2_LIB.BASEBOARD_FAB2(SCH_1):PVCCMCP_CPU0
   C6  PVCCMCP_CPU0    IOC6  @BASEBOARD_FAB2_LIB.BASEBOARD_FAB2(SCH_1):PVCCMCP_CPU0
   C5  PVCCMCP_CPU0    IOC5  @BASEBOARD_FAB2_LIB.BASEBOARD_FAB2(SCH_1):PVCCMCP_CPU0
   C4  PVCCMCP_CPU0    IOC4  @BASEBOARD_FAB2_LIB.BASEBOARD_FAB2(SCH_1):PVCCMCP_CPU0
   C3  PVCCMCP_CPU0    IOC3  @BASEBOARD_FAB2_LIB.BASEBOARD_FAB2(SCH_1):PVCCMCP_CPU0
   C2  PVCCMCP_CPU0    IOC2  @BASEBOARD_FAB2_LIB.BASEBOARD_FAB2(SCH_1):PVCCMCP_CPU0
   C1  PVCCMCP_CPU0    IOC1  @BASEBOARD_FAB2_LIB.BASEBOARD_FAB2(SCH_1):PVCCMCP_CPU0
  B18  PVCCMCP_CPU0   IOB18  @BASEBOARD_FAB2_LIB.BASEBOARD_FAB2(SCH_1):PVCCMCP_CPU0
  B17  PVCCMCP_CPU0   IOB17  @BASEBOARD_FAB2_LIB.BASEBOARD_FAB2(SCH_1):PVCCMCP_CPU0
  B16  PVCCMCP_CPU0   IOB16  @BASEBOARD_FAB2_LIB.BASEBOARD_FAB2(SCH_1):PVCCMCP_CPU0
  B15  PVCCMCP_CPU0   IOB15  @BASEBOARD_FAB2_LIB.BASEBOARD_FAB2(SCH_1):PVCCMCP_CPU0
  B14  PVCCMCP_CPU0   IOB14  @BASEBOARD_FAB2_LIB.BASEBOARD_FAB2(SCH_1):PVCCMCP_CPU0
  B13  PVCCMCP_CPU0   IOB13  @BASEBOARD_FAB2_LIB.BASEBOARD_FAB2(SCH_1):PVCCMCP_CPU0
  B12  PVCCMCP_CPU0   IOB12  @BASEBOARD_FAB2_LIB.BASEBOARD_FAB2(SCH_1):PVCCMCP_CPU0
  B11  PVCCMCP_CPU0   IOB11  @BASEBOARD_FAB2_LIB.BASEBOARD_FAB2(SCH_1):PVCCMCP_CPU0
  B10  PVCCMCP_CPU0   IOB10  @BASEBOARD_FAB2_LIB.BASEBOARD_FAB2(SCH_1):PVCCMCP_CPU0
   B9  PVCCMCP_CPU0    IOB9  @BASEBOARD_FAB2_LIB.BASEBOARD_FAB2(SCH_1):PVCCMCP_CPU0
   B8  PVCCMCP_CPU0    IOB8  @BASEBOARD_FAB2_LIB.BASEBOARD_FAB2(SCH_1):PVCCMCP_CPU0
   B7  PVCCMCP_CPU0    IOB7  @BASEBOARD_FAB2_LIB.BASEBOARD_FAB2(SCH_1):PVCCMCP_CPU0
   B6  PVCCMCP_CPU0    IOB6  @BASEBOARD_FAB2_LIB.BASEBOARD_FAB2(SCH_1):PVCCMCP_CPU0
   B5  PVCCMCP_CPU0    IOB5  @BASEBOARD_FAB2_LIB.BASEBOARD_FAB2(SCH_1):PVCCMCP_CPU0
   B3  PVCCMCP_CPU0    IOB3  @BASEBOARD_FAB2_LIB.BASEBOARD_FAB2(SCH_1):PVCCMCP_CPU0
   B2  PVCCMCP_CPU0    IOB2  @BASEBOARD_FAB2_LIB.BASEBOARD_FAB2(SCH_1):PVCCMCP_CPU0
   B1  PVCCMCP_CPU0    IOB1  @BASEBOARD_FAB2_LIB.BASEBOARD_FAB2(SCH_1):PVCCMCP_CPU0
  A18  PVCCMCP_CPU0   IOA18  @BASEBOARD_FAB2_LIB.BASEBOARD_FAB2(SCH_1):PVCCMCP_CPU0
  A17  PVCCMCP_CPU0   IOA17  @BASEBOARD_FAB2_LIB.BASEBOARD_FAB2(SCH_1):PVCCMCP_CPU0
  A16  PVCCMCP_CPU0   IOA16  @BASEBOARD_FAB2_LIB.BASEBOARD_FAB2(SCH_1):PVCCMCP_CPU0
  A15  PVCCMCP_CPU0   IOA15  @BASEBOARD_FAB2_LIB.BASEBOARD_FAB2(SCH_1):PVCCMCP_CPU0
  A14  PVCCMCP_CPU0   IOA14  @BASEBOARD_FAB2_LIB.BASEBOARD_FAB2(SCH_1):PVCCMCP_CPU0
  A13  PVCCMCP_CPU0   IOA13  @BASEBOARD_FAB2_LIB.BASEBOARD_FAB2(SCH_1):PVCCMCP_CPU0
  A12  PVCCMCP_CPU0   IOA12  @BASEBOARD_FAB2_LIB.BASEBOARD_FAB2(SCH_1):PVCCMCP_CPU0
  A11  PVCCMCP_CPU0   IOA11  @BASEBOARD_FAB2_LIB.BASEBOARD_FAB2(SCH_1):PVCCMCP_CPU0
  A10  PVCCMCP_CPU0   IOA10  @BASEBOARD_FAB2_LIB.BASEBOARD_FAB2(SCH_1):PVCCMCP_CPU0
   A9  PVCCMCP_CPU0    IOA9  @BASEBOARD_FAB2_LIB.BASEBOARD_FAB2(SCH_1):PVCCMCP_CPU0
   A8  PVCCMCP_CPU0    IOA8  @BASEBOARD_FAB2_LIB.BASEBOARD_FAB2(SCH_1):PVCCMCP_CPU0
   A7  PVCCMCP_CPU0    IOA7  @BASEBOARD_FAB2_LIB.BASEBOARD_FAB2(SCH_1):PVCCMCP_CPU0
   A6  PVCCMCP_CPU0    IOA6  @BASEBOARD_FAB2_LIB.BASEBOARD_FAB2(SCH_1):PVCCMCP_CPU0
   A5  PVCCMCP_CPU0    IOA5  @BASEBOARD_FAB2_LIB.BASEBOARD_FAB2(SCH_1):PVCCMCP_CPU0
   A3  PVCCMCP_CPU0    IOA3  @BASEBOARD_FAB2_LIB.BASEBOARD_FAB2(SCH_1):PVCCMCP_CPU0
   A2  PVCCMCP_CPU0    IOA2  @BASEBOARD_FAB2_LIB.BASEBOARD_FAB2(SCH_1):PVCCMCP_CPU0
   A1  PVCCMCP_CPU0    IOA1  @BASEBOARD_FAB2_LIB.BASEBOARD_FAB2(SCH_1):PVCCMCP_CPU0
   F2  P1V8_MCP_CPU0   IOF2  @BASEBOARD_FAB2_LIB.BASEBOARD_FAB2(SCH_1):P1V8_MCP_CPU0
   F1  P1V8_MCP_CPU0   IOF1  @BASEBOARD_FAB2_LIB.BASEBOARD_FAB2(SCH_1):P1V8_MCP_CPU0
   E2  P1V8_MCP_CPU0   IOE2  @BASEBOARD_FAB2_LIB.BASEBOARD_FAB2(SCH_1):P1V8_MCP_CPU0
   E1  P1V8_MCP_CPU0   IOE1  @BASEBOARD_FAB2_LIB.BASEBOARD_FAB2(SCH_1):P1V8_MCP_CPU0
  F20  GND            IOF20  @BASEBOARD_FAB2_LIB.BASEBOARD_FAB2(SCH_1):GND
  F19  GND            IOF19  @BASEBOARD_FAB2_LIB.BASEBOARD_FAB2(SCH_1):GND
  F18  GND            IOF18  @BASEBOARD_FAB2_LIB.BASEBOARD_FAB2(SCH_1):GND
  F17  GND            IOF17  @BASEBOARD_FAB2_LIB.BASEBOARD_FAB2(SCH_1):GND
  F16  GND            IOF16  @BASEBOARD_FAB2_LIB.BASEBOARD_FAB2(SCH_1):GND
  F15  GND            IOF15  @BASEBOARD_FAB2_LIB.BASEBOARD_FAB2(SCH_1):GND
  F14  GND            IOF14  @BASEBOARD_FAB2_LIB.BASEBOARD_FAB2(SCH_1):GND
  F13  GND            IOF13  @BASEBOARD_FAB2_LIB.BASEBOARD_FAB2(SCH_1):GND
  F12  GND            IOF12  @BASEBOARD_FAB2_LIB.BASEBOARD_FAB2(SCH_1):GND
  F11  GND            IOF11  @BASEBOARD_FAB2_LIB.BASEBOARD_FAB2(SCH_1):GND
  F10  GND            IOF10  @BASEBOARD_FAB2_LIB.BASEBOARD_FAB2(SCH_1):GND
   F9  GND             IOF9  @BASEBOARD_FAB2_LIB.BASEBOARD_FAB2(SCH_1):GND
   F8  GND             IOF8  @BASEBOARD_FAB2_LIB.BASEBOARD_FAB2(SCH_1):GND
   F7  GND             IOF7  @BASEBOARD_FAB2_LIB.BASEBOARD_FAB2(SCH_1):GND
   F6  GND             IOF6  @BASEBOARD_FAB2_LIB.BASEBOARD_FAB2(SCH_1):GND
   F4  GND             IOF4  @BASEBOARD_FAB2_LIB.BASEBOARD_FAB2(SCH_1):GND
   F3  GND             IOF3  @BASEBOARD_FAB2_LIB.BASEBOARD_FAB2(SCH_1):GND
  E20  GND            IOE20  @BASEBOARD_FAB2_LIB.BASEBOARD_FAB2(SCH_1):GND
  E19  GND            IOE19  @BASEBOARD_FAB2_LIB.BASEBOARD_FAB2(SCH_1):GND
  E18  GND            IOE18  @BASEBOARD_FAB2_LIB.BASEBOARD_FAB2(SCH_1):GND
  E17  GND            IOE17  @BASEBOARD_FAB2_LIB.BASEBOARD_FAB2(SCH_1):GND
  E16  GND            IOE16  @BASEBOARD_FAB2_LIB.BASEBOARD_FAB2(SCH_1):GND
  E15  GND            IOE15  @BASEBOARD_FAB2_LIB.BASEBOARD_FAB2(SCH_1):GND
  E14  GND            IOE14  @BASEBOARD_FAB2_LIB.BASEBOARD_FAB2(SCH_1):GND
  E13  GND            IOE13  @BASEBOARD_FAB2_LIB.BASEBOARD_FAB2(SCH_1):GND
  E12  GND            IOE12  @BASEBOARD_FAB2_LIB.BASEBOARD_FAB2(SCH_1):GND
  E11  GND            IOE11  @BASEBOARD_FAB2_LIB.BASEBOARD_FAB2(SCH_1):GND
  E10  GND            IOE10  @BASEBOARD_FAB2_LIB.BASEBOARD_FAB2(SCH_1):GND
   E9  GND             IOE9  @BASEBOARD_FAB2_LIB.BASEBOARD_FAB2(SCH_1):GND
   E8  GND             IOE8  @BASEBOARD_FAB2_LIB.BASEBOARD_FAB2(SCH_1):GND
   E7  GND             IOE7  @BASEBOARD_FAB2_LIB.BASEBOARD_FAB2(SCH_1):GND
   E6  GND             IOE6  @BASEBOARD_FAB2_LIB.BASEBOARD_FAB2(SCH_1):GND
   E4  GND             IOE4  @BASEBOARD_FAB2_LIB.BASEBOARD_FAB2(SCH_1):GND
   E3  GND             IOE3  @BASEBOARD_FAB2_LIB.BASEBOARD_FAB2(SCH_1):GND
  D20  GND            IOD20  @BASEBOARD_FAB2_LIB.BASEBOARD_FAB2(SCH_1):GND
  D19  GND            IOD19  @BASEBOARD_FAB2_LIB.BASEBOARD_FAB2(SCH_1):GND
  D18  GND            IOD18  @BASEBOARD_FAB2_LIB.BASEBOARD_FAB2(SCH_1):GND
  D17  GND            IOD17  @BASEBOARD_FAB2_LIB.BASEBOARD_FAB2(SCH_1):GND
  D16  GND            IOD16  @BASEBOARD_FAB2_LIB.BASEBOARD_FAB2(SCH_1):GND
  D15  GND            IOD15  @BASEBOARD_FAB2_LIB.BASEBOARD_FAB2(SCH_1):GND
  D14  GND            IOD14  @BASEBOARD_FAB2_LIB.BASEBOARD_FAB2(SCH_1):GND
  D13  GND            IOD13  @BASEBOARD_FAB2_LIB.BASEBOARD_FAB2(SCH_1):GND
  D12  GND            IOD12  @BASEBOARD_FAB2_LIB.BASEBOARD_FAB2(SCH_1):GND
  D11  GND            IOD11  @BASEBOARD_FAB2_LIB.BASEBOARD_FAB2(SCH_1):GND
  D10  GND            IOD10  @BASEBOARD_FAB2_LIB.BASEBOARD_FAB2(SCH_1):GND
   D9  GND             IOD9  @BASEBOARD_FAB2_LIB.BASEBOARD_FAB2(SCH_1):GND
   D8  GND             IOD8  @BASEBOARD_FAB2_LIB.BASEBOARD_FAB2(SCH_1):GND
   D7  GND             IOD7  @BASEBOARD_FAB2_LIB.BASEBOARD_FAB2(SCH_1):GND
   D6  GND             IOD6  @BASEBOARD_FAB2_LIB.BASEBOARD_FAB2(SCH_1):GND
   D5  GND             IOD5  @BASEBOARD_FAB2_LIB.BASEBOARD_FAB2(SCH_1):GND
   D4  GND             IOD4  @BASEBOARD_FAB2_LIB.BASEBOARD_FAB2(SCH_1):GND
   D3  GND             IOD3  @BASEBOARD_FAB2_LIB.BASEBOARD_FAB2(SCH_1):GND
  C20  GND            IOC20  @BASEBOARD_FAB2_LIB.BASEBOARD_FAB2(SCH_1):GND
  C19  GND            IOC19  @BASEBOARD_FAB2_LIB.BASEBOARD_FAB2(SCH_1):GND
  B20  GND            IOB20  @BASEBOARD_FAB2_LIB.BASEBOARD_FAB2(SCH_1):GND
  B19  GND            IOB19  @BASEBOARD_FAB2_LIB.BASEBOARD_FAB2(SCH_1):GND
  A20  GND            IOA20  @BASEBOARD_FAB2_LIB.BASEBOARD_FAB2(SCH_1):GND
  A19  GND            IOA19  @BASEBOARD_FAB2_LIB.BASEBOARD_FAB2(SCH_1):GND
   E5  CLK_322M_156M_CPU0_OSC_VRM_DP   IOE5  @BASEBOARD_FAB2_LIB.BASEBOARD_FAB2(SCH_1):CLK_322M_156M_CPU0_OSC_VRM_DP
   F5  CLK_322M_156M_CPU0_OSC_VRM_DN   IOF5  @BASEBOARD_FAB2_LIB.BASEBOARD_FAB2(SCH_1):CLK_322M_156M_CPU0_OSC_VRM_DN

SCONN288_H44441003_PIP  I170  J6L1   [SCONN288_H44441003_PIP-SCONN,HA]
   77  PVTT_DEF       VTT<1>  @BASEBOARD_FAB2_LIB.BASEBOARD_FAB2(SCH_1):PVTT_DEF
  221  PVTT_DEF       VTT<0>  @BASEBOARD_FAB2_LIB.BASEBOARD_FAB2(SCH_1):PVTT_DEF
  142  PVPP_DEF       VPP<4>  @BASEBOARD_FAB2_LIB.BASEBOARD_FAB2(SCH_1):PVPP_DEF
  143  PVPP_DEF       VPP<3>  @BASEBOARD_FAB2_LIB.BASEBOARD_FAB2(SCH_1):PVPP_DEF
  288  PVPP_DEF       VPP<2>  @BASEBOARD_FAB2_LIB.BASEBOARD_FAB2(SCH_1):PVPP_DEF
  286  PVPP_DEF       VPP<1>  @BASEBOARD_FAB2_LIB.BASEBOARD_FAB2(SCH_1):PVPP_DEF
  287  PVPP_DEF       VPP<0>  @BASEBOARD_FAB2_LIB.BASEBOARD_FAB2(SCH_1):PVPP_DEF
   59  PVDDQ_DEF      VDD<25>  @BASEBOARD_FAB2_LIB.BASEBOARD_FAB2(SCH_1):PVDDQ_DEF
   61  PVDDQ_DEF      VDD<24>  @BASEBOARD_FAB2_LIB.BASEBOARD_FAB2(SCH_1):PVDDQ_DEF
   64  PVDDQ_DEF      VDD<23>  @BASEBOARD_FAB2_LIB.BASEBOARD_FAB2(SCH_1):PVDDQ_DEF
   67  PVDDQ_DEF      VDD<22>  @BASEBOARD_FAB2_LIB.BASEBOARD_FAB2(SCH_1):PVDDQ_DEF
   70  PVDDQ_DEF      VDD<21>  @BASEBOARD_FAB2_LIB.BASEBOARD_FAB2(SCH_1):PVDDQ_DEF
   73  PVDDQ_DEF      VDD<20>  @BASEBOARD_FAB2_LIB.BASEBOARD_FAB2(SCH_1):PVDDQ_DEF
   76  PVDDQ_DEF      VDD<19>  @BASEBOARD_FAB2_LIB.BASEBOARD_FAB2(SCH_1):PVDDQ_DEF
   80  PVDDQ_DEF      VDD<18>  @BASEBOARD_FAB2_LIB.BASEBOARD_FAB2(SCH_1):PVDDQ_DEF
   83  PVDDQ_DEF      VDD<17>  @BASEBOARD_FAB2_LIB.BASEBOARD_FAB2(SCH_1):PVDDQ_DEF
   85  PVDDQ_DEF      VDD<16>  @BASEBOARD_FAB2_LIB.BASEBOARD_FAB2(SCH_1):PVDDQ_DEF
   88  PVDDQ_DEF      VDD<15>  @BASEBOARD_FAB2_LIB.BASEBOARD_FAB2(SCH_1):PVDDQ_DEF
   90  PVDDQ_DEF      VDD<14>  @BASEBOARD_FAB2_LIB.BASEBOARD_FAB2(SCH_1):PVDDQ_DEF
   92  PVDDQ_DEF      VDD<13>  @BASEBOARD_FAB2_LIB.BASEBOARD_FAB2(SCH_1):PVDDQ_DEF
  204  PVDDQ_DEF      VDD<12>  @BASEBOARD_FAB2_LIB.BASEBOARD_FAB2(SCH_1):PVDDQ_DEF
  206  PVDDQ_DEF      VDD<11>  @BASEBOARD_FAB2_LIB.BASEBOARD_FAB2(SCH_1):PVDDQ_DEF
  209  PVDDQ_DEF      VDD<10>  @BASEBOARD_FAB2_LIB.BASEBOARD_FAB2(SCH_1):PVDDQ_DEF
  212  PVDDQ_DEF      VDD<9>  @BASEBOARD_FAB2_LIB.BASEBOARD_FAB2(SCH_1):PVDDQ_DEF
  215  PVDDQ_DEF      VDD<8>  @BASEBOARD_FAB2_LIB.BASEBOARD_FAB2(SCH_1):PVDDQ_DEF
  217  PVDDQ_DEF      VDD<7>  @BASEBOARD_FAB2_LIB.BASEBOARD_FAB2(SCH_1):PVDDQ_DEF
  220  PVDDQ_DEF      VDD<6>  @BASEBOARD_FAB2_LIB.BASEBOARD_FAB2(SCH_1):PVDDQ_DEF
  223  PVDDQ_DEF      VDD<5>  @BASEBOARD_FAB2_LIB.BASEBOARD_FAB2(SCH_1):PVDDQ_DEF
  226  PVDDQ_DEF      VDD<4>  @BASEBOARD_FAB2_LIB.BASEBOARD_FAB2(SCH_1):PVDDQ_DEF
  229  PVDDQ_DEF      VDD<3>  @BASEBOARD_FAB2_LIB.BASEBOARD_FAB2(SCH_1):PVDDQ_DEF
  231  PVDDQ_DEF      VDD<2>  @BASEBOARD_FAB2_LIB.BASEBOARD_FAB2(SCH_1):PVDDQ_DEF
  233  PVDDQ_DEF      VDD<1>  @BASEBOARD_FAB2_LIB.BASEBOARD_FAB2(SCH_1):PVDDQ_DEF
  236  PVDDQ_DEF      VDD<0>  @BASEBOARD_FAB2_LIB.BASEBOARD_FAB2(SCH_1):PVDDQ_DEF
    1  P12V_NVDIMM_DEF  12V<1>  @BASEBOARD_FAB2_LIB.BASEBOARD_FAB2(SCH_1):P12V_NVDIMM_DEF
  145  P12V_NVDIMM_DEF  12V<0>  @BASEBOARD_FAB2_LIB.BASEBOARD_FAB2(SCH_1):P12V_NVDIMM_DEF

SCONN288_H44441003_PIP  I43  J6L1   [SCONN288_H44441003_PIP-SCONN,HA]
    2  GND            VSS<93>  @BASEBOARD_FAB2_LIB.BASEBOARD_FAB2(SCH_1):GND
    4  GND            VSS<92>  @BASEBOARD_FAB2_LIB.BASEBOARD_FAB2(SCH_1):GND
    6  GND            VSS<91>  @BASEBOARD_FAB2_LIB.BASEBOARD_FAB2(SCH_1):GND
    9  GND            VSS<90>  @BASEBOARD_FAB2_LIB.BASEBOARD_FAB2(SCH_1):GND
   11  GND            VSS<89>  @BASEBOARD_FAB2_LIB.BASEBOARD_FAB2(SCH_1):GND
   13  GND            VSS<88>  @BASEBOARD_FAB2_LIB.BASEBOARD_FAB2(SCH_1):GND
   15  GND            VSS<87>  @BASEBOARD_FAB2_LIB.BASEBOARD_FAB2(SCH_1):GND
   17  GND            VSS<86>  @BASEBOARD_FAB2_LIB.BASEBOARD_FAB2(SCH_1):GND
   20  GND            VSS<85>  @BASEBOARD_FAB2_LIB.BASEBOARD_FAB2(SCH_1):GND
   22  GND            VSS<84>  @BASEBOARD_FAB2_LIB.BASEBOARD_FAB2(SCH_1):GND
   24  GND            VSS<83>  @BASEBOARD_FAB2_LIB.BASEBOARD_FAB2(SCH_1):GND
   26  GND            VSS<82>  @BASEBOARD_FAB2_LIB.BASEBOARD_FAB2(SCH_1):GND
   28  GND            VSS<81>  @BASEBOARD_FAB2_LIB.BASEBOARD_FAB2(SCH_1):GND
   31  GND            VSS<80>  @BASEBOARD_FAB2_LIB.BASEBOARD_FAB2(SCH_1):GND
   33  GND            VSS<79>  @BASEBOARD_FAB2_LIB.BASEBOARD_FAB2(SCH_1):GND
   35  GND            VSS<78>  @BASEBOARD_FAB2_LIB.BASEBOARD_FAB2(SCH_1):GND
   37  GND            VSS<77>  @BASEBOARD_FAB2_LIB.BASEBOARD_FAB2(SCH_1):GND
   39  GND            VSS<76>  @BASEBOARD_FAB2_LIB.BASEBOARD_FAB2(SCH_1):GND
   42  GND            VSS<75>  @BASEBOARD_FAB2_LIB.BASEBOARD_FAB2(SCH_1):GND
   44  GND            VSS<74>  @BASEBOARD_FAB2_LIB.BASEBOARD_FAB2(SCH_1):GND
   46  GND            VSS<73>  @BASEBOARD_FAB2_LIB.BASEBOARD_FAB2(SCH_1):GND
   48  GND            VSS<72>  @BASEBOARD_FAB2_LIB.BASEBOARD_FAB2(SCH_1):GND
   50  GND            VSS<71>  @BASEBOARD_FAB2_LIB.BASEBOARD_FAB2(SCH_1):GND
   53  GND            VSS<70>  @BASEBOARD_FAB2_LIB.BASEBOARD_FAB2(SCH_1):GND
   55  GND            VSS<69>  @BASEBOARD_FAB2_LIB.BASEBOARD_FAB2(SCH_1):GND
   57  GND            VSS<68>  @BASEBOARD_FAB2_LIB.BASEBOARD_FAB2(SCH_1):GND
   94  GND            VSS<67>  @BASEBOARD_FAB2_LIB.BASEBOARD_FAB2(SCH_1):GND
   96  GND            VSS<66>  @BASEBOARD_FAB2_LIB.BASEBOARD_FAB2(SCH_1):GND
   98  GND            VSS<65>  @BASEBOARD_FAB2_LIB.BASEBOARD_FAB2(SCH_1):GND
  101  GND            VSS<64>  @BASEBOARD_FAB2_LIB.BASEBOARD_FAB2(SCH_1):GND
  103  GND            VSS<63>  @BASEBOARD_FAB2_LIB.BASEBOARD_FAB2(SCH_1):GND
  105  GND            VSS<62>  @BASEBOARD_FAB2_LIB.BASEBOARD_FAB2(SCH_1):GND
  107  GND            VSS<61>  @BASEBOARD_FAB2_LIB.BASEBOARD_FAB2(SCH_1):GND
  109  GND            VSS<60>  @BASEBOARD_FAB2_LIB.BASEBOARD_FAB2(SCH_1):GND
  112  GND            VSS<59>  @BASEBOARD_FAB2_LIB.BASEBOARD_FAB2(SCH_1):GND
  114  GND            VSS<58>  @BASEBOARD_FAB2_LIB.BASEBOARD_FAB2(SCH_1):GND
  116  GND            VSS<57>  @BASEBOARD_FAB2_LIB.BASEBOARD_FAB2(SCH_1):GND
  118  GND            VSS<56>  @BASEBOARD_FAB2_LIB.BASEBOARD_FAB2(SCH_1):GND
  120  GND            VSS<55>  @BASEBOARD_FAB2_LIB.BASEBOARD_FAB2(SCH_1):GND
  123  GND            VSS<54>  @BASEBOARD_FAB2_LIB.BASEBOARD_FAB2(SCH_1):GND
  125  GND            VSS<53>  @BASEBOARD_FAB2_LIB.BASEBOARD_FAB2(SCH_1):GND
  127  GND            VSS<52>  @BASEBOARD_FAB2_LIB.BASEBOARD_FAB2(SCH_1):GND
  129  GND            VSS<51>  @BASEBOARD_FAB2_LIB.BASEBOARD_FAB2(SCH_1):GND
  131  GND            VSS<50>  @BASEBOARD_FAB2_LIB.BASEBOARD_FAB2(SCH_1):GND
  134  GND            VSS<49>  @BASEBOARD_FAB2_LIB.BASEBOARD_FAB2(SCH_1):GND
  136  GND            VSS<48>  @BASEBOARD_FAB2_LIB.BASEBOARD_FAB2(SCH_1):GND
  138  GND            VSS<47>  @BASEBOARD_FAB2_LIB.BASEBOARD_FAB2(SCH_1):GND
  147  GND            VSS<46>  @BASEBOARD_FAB2_LIB.BASEBOARD_FAB2(SCH_1):GND
  149  GND            VSS<45>  @BASEBOARD_FAB2_LIB.BASEBOARD_FAB2(SCH_1):GND
  151  GND            VSS<44>  @BASEBOARD_FAB2_LIB.BASEBOARD_FAB2(SCH_1):GND
  154  GND            VSS<43>  @BASEBOARD_FAB2_LIB.BASEBOARD_FAB2(SCH_1):GND
  156  GND            VSS<42>  @BASEBOARD_FAB2_LIB.BASEBOARD_FAB2(SCH_1):GND
  158  GND            VSS<41>  @BASEBOARD_FAB2_LIB.BASEBOARD_FAB2(SCH_1):GND
  160  GND            VSS<40>  @BASEBOARD_FAB2_LIB.BASEBOARD_FAB2(SCH_1):GND
  162  GND            VSS<39>  @BASEBOARD_FAB2_LIB.BASEBOARD_FAB2(SCH_1):GND
  165  GND            VSS<38>  @BASEBOARD_FAB2_LIB.BASEBOARD_FAB2(SCH_1):GND
  167  GND            VSS<37>  @BASEBOARD_FAB2_LIB.BASEBOARD_FAB2(SCH_1):GND
  169  GND            VSS<36>  @BASEBOARD_FAB2_LIB.BASEBOARD_FAB2(SCH_1):GND
  171  GND            VSS<35>  @BASEBOARD_FAB2_LIB.BASEBOARD_FAB2(SCH_1):GND
  173  GND            VSS<34>  @BASEBOARD_FAB2_LIB.BASEBOARD_FAB2(SCH_1):GND
  176  GND            VSS<33>  @BASEBOARD_FAB2_LIB.BASEBOARD_FAB2(SCH_1):GND
  178  GND            VSS<32>  @BASEBOARD_FAB2_LIB.BASEBOARD_FAB2(SCH_1):GND
  180  GND            VSS<31>  @BASEBOARD_FAB2_LIB.BASEBOARD_FAB2(SCH_1):GND
  182  GND            VSS<30>  @BASEBOARD_FAB2_LIB.BASEBOARD_FAB2(SCH_1):GND
  184  GND            VSS<29>  @BASEBOARD_FAB2_LIB.BASEBOARD_FAB2(SCH_1):GND
  187  GND            VSS<28>  @BASEBOARD_FAB2_LIB.BASEBOARD_FAB2(SCH_1):GND
  189  GND            VSS<27>  @BASEBOARD_FAB2_LIB.BASEBOARD_FAB2(SCH_1):GND
  191  GND            VSS<26>  @BASEBOARD_FAB2_LIB.BASEBOARD_FAB2(SCH_1):GND
  193  GND            VSS<25>  @BASEBOARD_FAB2_LIB.BASEBOARD_FAB2(SCH_1):GND
  195  GND            VSS<24>  @BASEBOARD_FAB2_LIB.BASEBOARD_FAB2(SCH_1):GND
  198  GND            VSS<23>  @BASEBOARD_FAB2_LIB.BASEBOARD_FAB2(SCH_1):GND
  200  GND            VSS<22>  @BASEBOARD_FAB2_LIB.BASEBOARD_FAB2(SCH_1):GND
  202  GND            VSS<21>  @BASEBOARD_FAB2_LIB.BASEBOARD_FAB2(SCH_1):GND
  239  GND            VSS<20>  @BASEBOARD_FAB2_LIB.BASEBOARD_FAB2(SCH_1):GND
  241  GND            VSS<19>  @BASEBOARD_FAB2_LIB.BASEBOARD_FAB2(SCH_1):GND
  243  GND            VSS<18>  @BASEBOARD_FAB2_LIB.BASEBOARD_FAB2(SCH_1):GND
  246  GND            VSS<17>  @BASEBOARD_FAB2_LIB.BASEBOARD_FAB2(SCH_1):GND
  248  GND            VSS<16>  @BASEBOARD_FAB2_LIB.BASEBOARD_FAB2(SCH_1):GND
  250  GND            VSS<15>  @BASEBOARD_FAB2_LIB.BASEBOARD_FAB2(SCH_1):GND
  252  GND            VSS<14>  @BASEBOARD_FAB2_LIB.BASEBOARD_FAB2(SCH_1):GND
  254  GND            VSS<13>  @BASEBOARD_FAB2_LIB.BASEBOARD_FAB2(SCH_1):GND
  257  GND            VSS<12>  @BASEBOARD_FAB2_LIB.BASEBOARD_FAB2(SCH_1):GND
  259  GND            VSS<11>  @BASEBOARD_FAB2_LIB.BASEBOARD_FAB2(SCH_1):GND
  261  GND            VSS<10>  @BASEBOARD_FAB2_LIB.BASEBOARD_FAB2(SCH_1):GND
  263  GND            VSS<9>  @BASEBOARD_FAB2_LIB.BASEBOARD_FAB2(SCH_1):GND
  265  GND            VSS<8>  @BASEBOARD_FAB2_LIB.BASEBOARD_FAB2(SCH_1):GND
  268  GND            VSS<7>  @BASEBOARD_FAB2_LIB.BASEBOARD_FAB2(SCH_1):GND
  270  GND            VSS<6>  @BASEBOARD_FAB2_LIB.BASEBOARD_FAB2(SCH_1):GND
  272  GND            VSS<5>  @BASEBOARD_FAB2_LIB.BASEBOARD_FAB2(SCH_1):GND
  274  GND            VSS<4>  @BASEBOARD_FAB2_LIB.BASEBOARD_FAB2(SCH_1):GND
  276  GND            VSS<3>  @BASEBOARD_FAB2_LIB.BASEBOARD_FAB2(SCH_1):GND
  279  GND            VSS<2>  @BASEBOARD_FAB2_LIB.BASEBOARD_FAB2(SCH_1):GND
  281  GND            VSS<1>  @BASEBOARD_FAB2_LIB.BASEBOARD_FAB2(SCH_1):GND
  283  GND            VSS<0>  @BASEBOARD_FAB2_LIB.BASEBOARD_FAB2(SCH_1):GND

SCONN288_H44441003_PIP  I66  J6L1   [SCONN288_H44441003_PIP-SCONN,HA]
    7  M_F_DQS_DP<9>  DQS9P  @BASEBOARD_FAB2_LIB.BASEBOARD_FAB2(SCH_1):M_F_DQS_DP<9>
  197  M_F_DQS_DP<8>  DQS8P  @BASEBOARD_FAB2_LIB.BASEBOARD_FAB2(SCH_1):M_F_DQS_DP<8>
  278  M_F_DQS_DP<7>  DQS7P  @BASEBOARD_FAB2_LIB.BASEBOARD_FAB2(SCH_1):M_F_DQS_DP<7>
  267  M_F_DQS_DP<6>  DQS6P  @BASEBOARD_FAB2_LIB.BASEBOARD_FAB2(SCH_1):M_F_DQS_DP<6>
  256  M_F_DQS_DP<5>  DQS5P  @BASEBOARD_FAB2_LIB.BASEBOARD_FAB2(SCH_1):M_F_DQS_DP<5>
  245  M_F_DQS_DP<4>  DQS4P  @BASEBOARD_FAB2_LIB.BASEBOARD_FAB2(SCH_1):M_F_DQS_DP<4>
  186  M_F_DQS_DP<3>  DQS3P  @BASEBOARD_FAB2_LIB.BASEBOARD_FAB2(SCH_1):M_F_DQS_DP<3>
  175  M_F_DQS_DP<2>  DQS2P  @BASEBOARD_FAB2_LIB.BASEBOARD_FAB2(SCH_1):M_F_DQS_DP<2>
  164  M_F_DQS_DP<1>  DQS1P  @BASEBOARD_FAB2_LIB.BASEBOARD_FAB2(SCH_1):M_F_DQS_DP<1>
   51  M_F_DQS_DP<17>  DQS17P  @BASEBOARD_FAB2_LIB.BASEBOARD_FAB2(SCH_1):M_F_DQS_DP<17>
  132  M_F_DQS_DP<16>  DQS16P  @BASEBOARD_FAB2_LIB.BASEBOARD_FAB2(SCH_1):M_F_DQS_DP<16>
  121  M_F_DQS_DP<15>  DQS15P  @BASEBOARD_FAB2_LIB.BASEBOARD_FAB2(SCH_1):M_F_DQS_DP<15>
  110  M_F_DQS_DP<14>  DQS14P  @BASEBOARD_FAB2_LIB.BASEBOARD_FAB2(SCH_1):M_F_DQS_DP<14>
   99  M_F_DQS_DP<13>  DQS13P  @BASEBOARD_FAB2_LIB.BASEBOARD_FAB2(SCH_1):M_F_DQS_DP<13>
   40  M_F_DQS_DP<12>  DQS12P  @BASEBOARD_FAB2_LIB.BASEBOARD_FAB2(SCH_1):M_F_DQS_DP<12>
   29  M_F_DQS_DP<11>  DQS11P  @BASEBOARD_FAB2_LIB.BASEBOARD_FAB2(SCH_1):M_F_DQS_DP<11>
   18  M_F_DQS_DP<10>  DQS10P  @BASEBOARD_FAB2_LIB.BASEBOARD_FAB2(SCH_1):M_F_DQS_DP<10>
  153  M_F_DQS_DP<0>  DQS0P  @BASEBOARD_FAB2_LIB.BASEBOARD_FAB2(SCH_1):M_F_DQS_DP<0>
    8  M_F_DQS_DN<9>  DQS9N  @BASEBOARD_FAB2_LIB.BASEBOARD_FAB2(SCH_1):M_F_DQS_DN<9>
  196  M_F_DQS_DN<8>  DQS8N  @BASEBOARD_FAB2_LIB.BASEBOARD_FAB2(SCH_1):M_F_DQS_DN<8>
  277  M_F_DQS_DN<7>  DQS7N  @BASEBOARD_FAB2_LIB.BASEBOARD_FAB2(SCH_1):M_F_DQS_DN<7>
  266  M_F_DQS_DN<6>  DQS6N  @BASEBOARD_FAB2_LIB.BASEBOARD_FAB2(SCH_1):M_F_DQS_DN<6>
  255  M_F_DQS_DN<5>  DQS5N  @BASEBOARD_FAB2_LIB.BASEBOARD_FAB2(SCH_1):M_F_DQS_DN<5>
  244  M_F_DQS_DN<4>  DQS4N  @BASEBOARD_FAB2_LIB.BASEBOARD_FAB2(SCH_1):M_F_DQS_DN<4>
  185  M_F_DQS_DN<3>  DQS3N  @BASEBOARD_FAB2_LIB.BASEBOARD_FAB2(SCH_1):M_F_DQS_DN<3>
  174  M_F_DQS_DN<2>  DQS2N  @BASEBOARD_FAB2_LIB.BASEBOARD_FAB2(SCH_1):M_F_DQS_DN<2>
  163  M_F_DQS_DN<1>  DQS1N  @BASEBOARD_FAB2_LIB.BASEBOARD_FAB2(SCH_1):M_F_DQS_DN<1>
   52  M_F_DQS_DN<17>  DQS17N  @BASEBOARD_FAB2_LIB.BASEBOARD_FAB2(SCH_1):M_F_DQS_DN<17>
  133  M_F_DQS_DN<16>  DQS16N  @BASEBOARD_FAB2_LIB.BASEBOARD_FAB2(SCH_1):M_F_DQS_DN<16>
  122  M_F_DQS_DN<15>  DQS15N  @BASEBOARD_FAB2_LIB.BASEBOARD_FAB2(SCH_1):M_F_DQS_DN<15>
  111  M_F_DQS_DN<14>  DQS14N  @BASEBOARD_FAB2_LIB.BASEBOARD_FAB2(SCH_1):M_F_DQS_DN<14>
  100  M_F_DQS_DN<13>  DQS13N  @BASEBOARD_FAB2_LIB.BASEBOARD_FAB2(SCH_1):M_F_DQS_DN<13>
   41  M_F_DQS_DN<12>  DQS12N  @BASEBOARD_FAB2_LIB.BASEBOARD_FAB2(SCH_1):M_F_DQS_DN<12>
   30  M_F_DQS_DN<11>  DQS11N  @BASEBOARD_FAB2_LIB.BASEBOARD_FAB2(SCH_1):M_F_DQS_DN<11>
   19  M_F_DQS_DN<10>  DQS10N  @BASEBOARD_FAB2_LIB.BASEBOARD_FAB2(SCH_1):M_F_DQS_DN<10>
  152  M_F_DQS_DN<0>  DQS0N  @BASEBOARD_FAB2_LIB.BASEBOARD_FAB2(SCH_1):M_F_DQS_DN<0>

SCONN288_H44441003_PIP  I111  J6L1   [SCONN288_H44441003_PIP-SCONN,HA]
  144  TP_CH_F_DIMM_F1_RFU_2  RFU<2>  @BASEBOARD_FAB2_LIB.BASEBOARD_FAB2(SCH_1):TP_CH_F_DIMM_F1_RFU_2
  227  TP_CH_F_DIMM_F1_RFU_1  RFU<1>  @BASEBOARD_FAB2_LIB.BASEBOARD_FAB2(SCH_1):TP_CH_F_DIMM_F1_RFU_1
  205  TP_CH_F_DIMM_F1_RFU_0  RFU<0>  @BASEBOARD_FAB2_LIB.BASEBOARD_FAB2(SCH_1):TP_CH_F_DIMM_F1_RFU_0
  285  SMB_DDR_DEF_VPP_SDA    SDA  @BASEBOARD_FAB2_LIB.BASEBOARD_FAB2(SCH_1):SMB_DDR_DEF_VPP_SDA
  141  SMB_DDR_DEF_VPP_SCL    SCL  @BASEBOARD_FAB2_LIB.BASEBOARD_FAB2(SCH_1):SMB_DDR_DEF_VPP_SCL
  284  PVPP_DEF       VDDSPD  @BASEBOARD_FAB2_LIB.BASEBOARD_FAB2(SCH_1):PVPP_DEF
  238  PVPP_DEF       SA<2>  @BASEBOARD_FAB2_LIB.BASEBOARD_FAB2(SCH_1):PVPP_DEF
  139  PVPP_DEF       SA<0>  @BASEBOARD_FAB2_LIB.BASEBOARD_FAB2(SCH_1):PVPP_DEF
  146  M_F_VREF       VREFCA  @BASEBOARD_FAB2_LIB.BASEBOARD_FAB2(SCH_1):M_F_VREF
  222  M_F_PAR          PAR  @BASEBOARD_FAB2_LIB.BASEBOARD_FAB2(SCH_1):M_F_PAR
   91  M_F_ODT<3>     ODT<1>  @BASEBOARD_FAB2_LIB.BASEBOARD_FAB2(SCH_1):M_F_ODT<3>
   87  M_F_ODT<2>     ODT<0>  @BASEBOARD_FAB2_LIB.BASEBOARD_FAB2(SCH_1):M_F_ODT<2>
   66  M_F_MA<9>         A9  @BASEBOARD_FAB2_LIB.BASEBOARD_FAB2(SCH_1):M_F_MA<9>
   68  M_F_MA<8>         A8  @BASEBOARD_FAB2_LIB.BASEBOARD_FAB2(SCH_1):M_F_MA<8>
  211  M_F_MA<7>         A7  @BASEBOARD_FAB2_LIB.BASEBOARD_FAB2(SCH_1):M_F_MA<7>
   69  M_F_MA<6>         A6  @BASEBOARD_FAB2_LIB.BASEBOARD_FAB2(SCH_1):M_F_MA<6>
  213  M_F_MA<5>         A5  @BASEBOARD_FAB2_LIB.BASEBOARD_FAB2(SCH_1):M_F_MA<5>
  214  M_F_MA<4>         A4  @BASEBOARD_FAB2_LIB.BASEBOARD_FAB2(SCH_1):M_F_MA<4>
   71  M_F_MA<3>         A3  @BASEBOARD_FAB2_LIB.BASEBOARD_FAB2(SCH_1):M_F_MA<3>
  216  M_F_MA<2>         A2  @BASEBOARD_FAB2_LIB.BASEBOARD_FAB2(SCH_1):M_F_MA<2>
   72  M_F_MA<1>         A1  @BASEBOARD_FAB2_LIB.BASEBOARD_FAB2(SCH_1):M_F_MA<1>
  234  M_F_MA<17>       A17  @BASEBOARD_FAB2_LIB.BASEBOARD_FAB2(SCH_1):M_F_MA<17>
   82  M_F_MA<16>     A16_RAS_N  @BASEBOARD_FAB2_LIB.BASEBOARD_FAB2(SCH_1):M_F_MA<16>
   86  M_F_MA<15>     A15_CAS_N  @BASEBOARD_FAB2_LIB.BASEBOARD_FAB2(SCH_1):M_F_MA<15>
  228  M_F_MA<14>     A14_WE_N  @BASEBOARD_FAB2_LIB.BASEBOARD_FAB2(SCH_1):M_F_MA<14>
  232  M_F_MA<13>       A13  @BASEBOARD_FAB2_LIB.BASEBOARD_FAB2(SCH_1):M_F_MA<13>
   65  M_F_MA<12>       A12  @BASEBOARD_FAB2_LIB.BASEBOARD_FAB2(SCH_1):M_F_MA<12>
  210  M_F_MA<11>       A11  @BASEBOARD_FAB2_LIB.BASEBOARD_FAB2(SCH_1):M_F_MA<11>
  225  M_F_MA<10>       A10  @BASEBOARD_FAB2_LIB.BASEBOARD_FAB2(SCH_1):M_F_MA<10>
   79  M_F_MA<0>         A0  @BASEBOARD_FAB2_LIB.BASEBOARD_FAB2(SCH_1):M_F_MA<0>
  199  M_F_ECC<7>     CB<7>  @BASEBOARD_FAB2_LIB.BASEBOARD_FAB2(SCH_1):M_F_ECC<7>
   54  M_F_ECC<6>     CB<6>  @BASEBOARD_FAB2_LIB.BASEBOARD_FAB2(SCH_1):M_F_ECC<6>
  192  M_F_ECC<5>     CB<5>  @BASEBOARD_FAB2_LIB.BASEBOARD_FAB2(SCH_1):M_F_ECC<5>
   47  M_F_ECC<4>     CB<4>  @BASEBOARD_FAB2_LIB.BASEBOARD_FAB2(SCH_1):M_F_ECC<4>
  201  M_F_ECC<3>     CB<3>  @BASEBOARD_FAB2_LIB.BASEBOARD_FAB2(SCH_1):M_F_ECC<3>
   56  M_F_ECC<2>     CB<2>  @BASEBOARD_FAB2_LIB.BASEBOARD_FAB2(SCH_1):M_F_ECC<2>
  194  M_F_ECC<1>     CB<1>  @BASEBOARD_FAB2_LIB.BASEBOARD_FAB2(SCH_1):M_F_ECC<1>
   49  M_F_ECC<0>     CB<0>  @BASEBOARD_FAB2_LIB.BASEBOARD_FAB2(SCH_1):M_F_ECC<0>
  161  M_F_DQ<9>      DQ<9>  @BASEBOARD_FAB2_LIB.BASEBOARD_FAB2(SCH_1):M_F_DQ<9>
   16  M_F_DQ<8>      DQ<8>  @BASEBOARD_FAB2_LIB.BASEBOARD_FAB2(SCH_1):M_F_DQ<8>
  155  M_F_DQ<7>      DQ<7>  @BASEBOARD_FAB2_LIB.BASEBOARD_FAB2(SCH_1):M_F_DQ<7>
   10  M_F_DQ<6>      DQ<6>  @BASEBOARD_FAB2_LIB.BASEBOARD_FAB2(SCH_1):M_F_DQ<6>
  280  M_F_DQ<63>     DQ<63>  @BASEBOARD_FAB2_LIB.BASEBOARD_FAB2(SCH_1):M_F_DQ<63>
  135  M_F_DQ<62>     DQ<62>  @BASEBOARD_FAB2_LIB.BASEBOARD_FAB2(SCH_1):M_F_DQ<62>
  273  M_F_DQ<61>     DQ<61>  @BASEBOARD_FAB2_LIB.BASEBOARD_FAB2(SCH_1):M_F_DQ<61>
  128  M_F_DQ<60>     DQ<60>  @BASEBOARD_FAB2_LIB.BASEBOARD_FAB2(SCH_1):M_F_DQ<60>
  148  M_F_DQ<5>      DQ<5>  @BASEBOARD_FAB2_LIB.BASEBOARD_FAB2(SCH_1):M_F_DQ<5>
  282  M_F_DQ<59>     DQ<59>  @BASEBOARD_FAB2_LIB.BASEBOARD_FAB2(SCH_1):M_F_DQ<59>
  137  M_F_DQ<58>     DQ<58>  @BASEBOARD_FAB2_LIB.BASEBOARD_FAB2(SCH_1):M_F_DQ<58>
  275  M_F_DQ<57>     DQ<57>  @BASEBOARD_FAB2_LIB.BASEBOARD_FAB2(SCH_1):M_F_DQ<57>
  130  M_F_DQ<56>     DQ<56>  @BASEBOARD_FAB2_LIB.BASEBOARD_FAB2(SCH_1):M_F_DQ<56>
  269  M_F_DQ<55>     DQ<55>  @BASEBOARD_FAB2_LIB.BASEBOARD_FAB2(SCH_1):M_F_DQ<55>
  124  M_F_DQ<54>     DQ<54>  @BASEBOARD_FAB2_LIB.BASEBOARD_FAB2(SCH_1):M_F_DQ<54>
  262  M_F_DQ<53>     DQ<53>  @BASEBOARD_FAB2_LIB.BASEBOARD_FAB2(SCH_1):M_F_DQ<53>
  117  M_F_DQ<52>     DQ<52>  @BASEBOARD_FAB2_LIB.BASEBOARD_FAB2(SCH_1):M_F_DQ<52>
  271  M_F_DQ<51>     DQ<51>  @BASEBOARD_FAB2_LIB.BASEBOARD_FAB2(SCH_1):M_F_DQ<51>
  126  M_F_DQ<50>     DQ<50>  @BASEBOARD_FAB2_LIB.BASEBOARD_FAB2(SCH_1):M_F_DQ<50>
    3  M_F_DQ<4>      DQ<4>  @BASEBOARD_FAB2_LIB.BASEBOARD_FAB2(SCH_1):M_F_DQ<4>
  264  M_F_DQ<49>     DQ<49>  @BASEBOARD_FAB2_LIB.BASEBOARD_FAB2(SCH_1):M_F_DQ<49>
  119  M_F_DQ<48>     DQ<48>  @BASEBOARD_FAB2_LIB.BASEBOARD_FAB2(SCH_1):M_F_DQ<48>
  258  M_F_DQ<47>     DQ<47>  @BASEBOARD_FAB2_LIB.BASEBOARD_FAB2(SCH_1):M_F_DQ<47>
  113  M_F_DQ<46>     DQ<46>  @BASEBOARD_FAB2_LIB.BASEBOARD_FAB2(SCH_1):M_F_DQ<46>
  251  M_F_DQ<45>     DQ<45>  @BASEBOARD_FAB2_LIB.BASEBOARD_FAB2(SCH_1):M_F_DQ<45>
  106  M_F_DQ<44>     DQ<44>  @BASEBOARD_FAB2_LIB.BASEBOARD_FAB2(SCH_1):M_F_DQ<44>
  260  M_F_DQ<43>     DQ<43>  @BASEBOARD_FAB2_LIB.BASEBOARD_FAB2(SCH_1):M_F_DQ<43>
  115  M_F_DQ<42>     DQ<42>  @BASEBOARD_FAB2_LIB.BASEBOARD_FAB2(SCH_1):M_F_DQ<42>
  253  M_F_DQ<41>     DQ<41>  @BASEBOARD_FAB2_LIB.BASEBOARD_FAB2(SCH_1):M_F_DQ<41>
  108  M_F_DQ<40>     DQ<40>  @BASEBOARD_FAB2_LIB.BASEBOARD_FAB2(SCH_1):M_F_DQ<40>
  157  M_F_DQ<3>      DQ<3>  @BASEBOARD_FAB2_LIB.BASEBOARD_FAB2(SCH_1):M_F_DQ<3>
  247  M_F_DQ<39>     DQ<39>  @BASEBOARD_FAB2_LIB.BASEBOARD_FAB2(SCH_1):M_F_DQ<39>
  102  M_F_DQ<38>     DQ<38>  @BASEBOARD_FAB2_LIB.BASEBOARD_FAB2(SCH_1):M_F_DQ<38>
  240  M_F_DQ<37>     DQ<37>  @BASEBOARD_FAB2_LIB.BASEBOARD_FAB2(SCH_1):M_F_DQ<37>
   95  M_F_DQ<36>     DQ<36>  @BASEBOARD_FAB2_LIB.BASEBOARD_FAB2(SCH_1):M_F_DQ<36>
  249  M_F_DQ<35>     DQ<35>  @BASEBOARD_FAB2_LIB.BASEBOARD_FAB2(SCH_1):M_F_DQ<35>
  104  M_F_DQ<34>     DQ<34>  @BASEBOARD_FAB2_LIB.BASEBOARD_FAB2(SCH_1):M_F_DQ<34>
  242  M_F_DQ<33>     DQ<33>  @BASEBOARD_FAB2_LIB.BASEBOARD_FAB2(SCH_1):M_F_DQ<33>
   97  M_F_DQ<32>     DQ<32>  @BASEBOARD_FAB2_LIB.BASEBOARD_FAB2(SCH_1):M_F_DQ<32>
  188  M_F_DQ<31>     DQ<31>  @BASEBOARD_FAB2_LIB.BASEBOARD_FAB2(SCH_1):M_F_DQ<31>
   43  M_F_DQ<30>     DQ<30>  @BASEBOARD_FAB2_LIB.BASEBOARD_FAB2(SCH_1):M_F_DQ<30>
   12  M_F_DQ<2>      DQ<2>  @BASEBOARD_FAB2_LIB.BASEBOARD_FAB2(SCH_1):M_F_DQ<2>
  181  M_F_DQ<29>     DQ<29>  @BASEBOARD_FAB2_LIB.BASEBOARD_FAB2(SCH_1):M_F_DQ<29>
   36  M_F_DQ<28>     DQ<28>  @BASEBOARD_FAB2_LIB.BASEBOARD_FAB2(SCH_1):M_F_DQ<28>
  190  M_F_DQ<27>     DQ<27>  @BASEBOARD_FAB2_LIB.BASEBOARD_FAB2(SCH_1):M_F_DQ<27>
   45  M_F_DQ<26>     DQ<26>  @BASEBOARD_FAB2_LIB.BASEBOARD_FAB2(SCH_1):M_F_DQ<26>
  183  M_F_DQ<25>     DQ<25>  @BASEBOARD_FAB2_LIB.BASEBOARD_FAB2(SCH_1):M_F_DQ<25>
   38  M_F_DQ<24>     DQ<24>  @BASEBOARD_FAB2_LIB.BASEBOARD_FAB2(SCH_1):M_F_DQ<24>
  177  M_F_DQ<23>     DQ<23>  @BASEBOARD_FAB2_LIB.BASEBOARD_FAB2(SCH_1):M_F_DQ<23>
   32  M_F_DQ<22>     DQ<22>  @BASEBOARD_FAB2_LIB.BASEBOARD_FAB2(SCH_1):M_F_DQ<22>
  170  M_F_DQ<21>     DQ<21>  @BASEBOARD_FAB2_LIB.BASEBOARD_FAB2(SCH_1):M_F_DQ<21>
   25  M_F_DQ<20>     DQ<20>  @BASEBOARD_FAB2_LIB.BASEBOARD_FAB2(SCH_1):M_F_DQ<20>
  150  M_F_DQ<1>      DQ<1>  @BASEBOARD_FAB2_LIB.BASEBOARD_FAB2(SCH_1):M_F_DQ<1>
  179  M_F_DQ<19>     DQ<19>  @BASEBOARD_FAB2_LIB.BASEBOARD_FAB2(SCH_1):M_F_DQ<19>
   34  M_F_DQ<18>     DQ<18>  @BASEBOARD_FAB2_LIB.BASEBOARD_FAB2(SCH_1):M_F_DQ<18>
  172  M_F_DQ<17>     DQ<17>  @BASEBOARD_FAB2_LIB.BASEBOARD_FAB2(SCH_1):M_F_DQ<17>
   27  M_F_DQ<16>     DQ<16>  @BASEBOARD_FAB2_LIB.BASEBOARD_FAB2(SCH_1):M_F_DQ<16>
  166  M_F_DQ<15>     DQ<15>  @BASEBOARD_FAB2_LIB.BASEBOARD_FAB2(SCH_1):M_F_DQ<15>
   21  M_F_DQ<14>     DQ<14>  @BASEBOARD_FAB2_LIB.BASEBOARD_FAB2(SCH_1):M_F_DQ<14>
  159  M_F_DQ<13>     DQ<13>  @BASEBOARD_FAB2_LIB.BASEBOARD_FAB2(SCH_1):M_F_DQ<13>
   14  M_F_DQ<12>     DQ<12>  @BASEBOARD_FAB2_LIB.BASEBOARD_FAB2(SCH_1):M_F_DQ<12>
  168  M_F_DQ<11>     DQ<11>  @BASEBOARD_FAB2_LIB.BASEBOARD_FAB2(SCH_1):M_F_DQ<11>
   23  M_F_DQ<10>     DQ<10>  @BASEBOARD_FAB2_LIB.BASEBOARD_FAB2(SCH_1):M_F_DQ<10>
    5  M_F_DQ<0>      DQ<0>  @BASEBOARD_FAB2_LIB.BASEBOARD_FAB2(SCH_1):M_F_DQ<0>
  237  M_F_CS_N<7>    S3_N_C<1>  @BASEBOARD_FAB2_LIB.BASEBOARD_FAB2(SCH_1):M_F_CS_N<7>
   93  M_F_CS_N<6>    S2_N_C<0>  @BASEBOARD_FAB2_LIB.BASEBOARD_FAB2(SCH_1):M_F_CS_N<6>
   89  M_F_CS_N<5>     S1_N  @BASEBOARD_FAB2_LIB.BASEBOARD_FAB2(SCH_1):M_F_CS_N<5>
   84  M_F_CS_N<4>     S0_N  @BASEBOARD_FAB2_LIB.BASEBOARD_FAB2(SCH_1):M_F_CS_N<4>
  218  M_F_CLK_DP<3>   CK1P  @BASEBOARD_FAB2_LIB.BASEBOARD_FAB2(SCH_1):M_F_CLK_DP<3>
   74  M_F_CLK_DP<2>   CK0P  @BASEBOARD_FAB2_LIB.BASEBOARD_FAB2(SCH_1):M_F_CLK_DP<2>
  219  M_F_CLK_DN<3>   CK1N  @BASEBOARD_FAB2_LIB.BASEBOARD_FAB2(SCH_1):M_F_CLK_DN<3>
   75  M_F_CLK_DN<2>   CK0N  @BASEBOARD_FAB2_LIB.BASEBOARD_FAB2(SCH_1):M_F_CLK_DN<2>
  203  M_F_CKE<3>     CKE<1>  @BASEBOARD_FAB2_LIB.BASEBOARD_FAB2(SCH_1):M_F_CKE<3>
   60  M_F_CKE<2>     CKE<0>  @BASEBOARD_FAB2_LIB.BASEBOARD_FAB2(SCH_1):M_F_CKE<2>
  235  M_F_C<2>        C<2>  @BASEBOARD_FAB2_LIB.BASEBOARD_FAB2(SCH_1):M_F_C<2>
  207  M_F_BG<1>      BG<1>  @BASEBOARD_FAB2_LIB.BASEBOARD_FAB2(SCH_1):M_F_BG<1>
   63  M_F_BG<0>      BG<0>  @BASEBOARD_FAB2_LIB.BASEBOARD_FAB2(SCH_1):M_F_BG<0>
  224  M_F_BA<1>      BA<1>  @BASEBOARD_FAB2_LIB.BASEBOARD_FAB2(SCH_1):M_F_BA<1>
   81  M_F_BA<0>      BA<0>  @BASEBOARD_FAB2_LIB.BASEBOARD_FAB2(SCH_1):M_F_BA<0>
  208  M_F_ALERT_N    ALERT_N  @BASEBOARD_FAB2_LIB.BASEBOARD_FAB2(SCH_1):M_F_ALERT_N
   62  M_F_ACT_N      ACT_N  @BASEBOARD_FAB2_LIB.BASEBOARD_FAB2(SCH_1):M_F_ACT_N
   58  M_DEF_RST_N    RESET_N  @BASEBOARD_FAB2_LIB.BASEBOARD_FAB2(SCH_1):M_DEF_RST_N
  140  GND            SA<1>  @BASEBOARD_FAB2_LIB.BASEBOARD_FAB2(SCH_1):GND
   78  FM_DIMM_EVENT_COD_N  EVENT_N  @BASEBOARD_FAB2_LIB.BASEBOARD_FAB2(SCH_1):FM_DIMM_EVENT_COD_N
  230  FM_ADR_COMPLETE_DEF_N  SAVE_N_NC  @BASEBOARD_FAB2_LIB.BASEBOARD_FAB2(SCH_1):FM_ADR_COMPLETE_DEF_N

SCONN288_H44441003_PIP  I55  J6L2   [SCONN288_H44441003_PIP-SCONN,HA]
   77  PVTT_DEF       VTT<1>  @BASEBOARD_FAB2_LIB.BASEBOARD_FAB2(SCH_1):PVTT_DEF
  221  PVTT_DEF       VTT<0>  @BASEBOARD_FAB2_LIB.BASEBOARD_FAB2(SCH_1):PVTT_DEF
  142  PVPP_DEF       VPP<4>  @BASEBOARD_FAB2_LIB.BASEBOARD_FAB2(SCH_1):PVPP_DEF
  143  PVPP_DEF       VPP<3>  @BASEBOARD_FAB2_LIB.BASEBOARD_FAB2(SCH_1):PVPP_DEF
  288  PVPP_DEF       VPP<2>  @BASEBOARD_FAB2_LIB.BASEBOARD_FAB2(SCH_1):PVPP_DEF
  286  PVPP_DEF       VPP<1>  @BASEBOARD_FAB2_LIB.BASEBOARD_FAB2(SCH_1):PVPP_DEF
  287  PVPP_DEF       VPP<0>  @BASEBOARD_FAB2_LIB.BASEBOARD_FAB2(SCH_1):PVPP_DEF
   59  PVDDQ_DEF      VDD<25>  @BASEBOARD_FAB2_LIB.BASEBOARD_FAB2(SCH_1):PVDDQ_DEF
   61  PVDDQ_DEF      VDD<24>  @BASEBOARD_FAB2_LIB.BASEBOARD_FAB2(SCH_1):PVDDQ_DEF
   64  PVDDQ_DEF      VDD<23>  @BASEBOARD_FAB2_LIB.BASEBOARD_FAB2(SCH_1):PVDDQ_DEF
   67  PVDDQ_DEF      VDD<22>  @BASEBOARD_FAB2_LIB.BASEBOARD_FAB2(SCH_1):PVDDQ_DEF
   70  PVDDQ_DEF      VDD<21>  @BASEBOARD_FAB2_LIB.BASEBOARD_FAB2(SCH_1):PVDDQ_DEF
   73  PVDDQ_DEF      VDD<20>  @BASEBOARD_FAB2_LIB.BASEBOARD_FAB2(SCH_1):PVDDQ_DEF
   76  PVDDQ_DEF      VDD<19>  @BASEBOARD_FAB2_LIB.BASEBOARD_FAB2(SCH_1):PVDDQ_DEF
   80  PVDDQ_DEF      VDD<18>  @BASEBOARD_FAB2_LIB.BASEBOARD_FAB2(SCH_1):PVDDQ_DEF
   83  PVDDQ_DEF      VDD<17>  @BASEBOARD_FAB2_LIB.BASEBOARD_FAB2(SCH_1):PVDDQ_DEF
   85  PVDDQ_DEF      VDD<16>  @BASEBOARD_FAB2_LIB.BASEBOARD_FAB2(SCH_1):PVDDQ_DEF
   88  PVDDQ_DEF      VDD<15>  @BASEBOARD_FAB2_LIB.BASEBOARD_FAB2(SCH_1):PVDDQ_DEF
   90  PVDDQ_DEF      VDD<14>  @BASEBOARD_FAB2_LIB.BASEBOARD_FAB2(SCH_1):PVDDQ_DEF
   92  PVDDQ_DEF      VDD<13>  @BASEBOARD_FAB2_LIB.BASEBOARD_FAB2(SCH_1):PVDDQ_DEF
  204  PVDDQ_DEF      VDD<12>  @BASEBOARD_FAB2_LIB.BASEBOARD_FAB2(SCH_1):PVDDQ_DEF
  206  PVDDQ_DEF      VDD<11>  @BASEBOARD_FAB2_LIB.BASEBOARD_FAB2(SCH_1):PVDDQ_DEF
  209  PVDDQ_DEF      VDD<10>  @BASEBOARD_FAB2_LIB.BASEBOARD_FAB2(SCH_1):PVDDQ_DEF
  212  PVDDQ_DEF      VDD<9>  @BASEBOARD_FAB2_LIB.BASEBOARD_FAB2(SCH_1):PVDDQ_DEF
  215  PVDDQ_DEF      VDD<8>  @BASEBOARD_FAB2_LIB.BASEBOARD_FAB2(SCH_1):PVDDQ_DEF
  217  PVDDQ_DEF      VDD<7>  @BASEBOARD_FAB2_LIB.BASEBOARD_FAB2(SCH_1):PVDDQ_DEF
  220  PVDDQ_DEF      VDD<6>  @BASEBOARD_FAB2_LIB.BASEBOARD_FAB2(SCH_1):PVDDQ_DEF
  223  PVDDQ_DEF      VDD<5>  @BASEBOARD_FAB2_LIB.BASEBOARD_FAB2(SCH_1):PVDDQ_DEF
  226  PVDDQ_DEF      VDD<4>  @BASEBOARD_FAB2_LIB.BASEBOARD_FAB2(SCH_1):PVDDQ_DEF
  229  PVDDQ_DEF      VDD<3>  @BASEBOARD_FAB2_LIB.BASEBOARD_FAB2(SCH_1):PVDDQ_DEF
  231  PVDDQ_DEF      VDD<2>  @BASEBOARD_FAB2_LIB.BASEBOARD_FAB2(SCH_1):PVDDQ_DEF
  233  PVDDQ_DEF      VDD<1>  @BASEBOARD_FAB2_LIB.BASEBOARD_FAB2(SCH_1):PVDDQ_DEF
  236  PVDDQ_DEF      VDD<0>  @BASEBOARD_FAB2_LIB.BASEBOARD_FAB2(SCH_1):PVDDQ_DEF
    1  P12V_NVDIMM_DEF  12V<1>  @BASEBOARD_FAB2_LIB.BASEBOARD_FAB2(SCH_1):P12V_NVDIMM_DEF
  145  P12V_NVDIMM_DEF  12V<0>  @BASEBOARD_FAB2_LIB.BASEBOARD_FAB2(SCH_1):P12V_NVDIMM_DEF

SCONN288_H44441003_PIP  I138  J6L2   [SCONN288_H44441003_PIP-SCONN,HA]
    2  GND            VSS<93>  @BASEBOARD_FAB2_LIB.BASEBOARD_FAB2(SCH_1):GND
    4  GND            VSS<92>  @BASEBOARD_FAB2_LIB.BASEBOARD_FAB2(SCH_1):GND
    6  GND            VSS<91>  @BASEBOARD_FAB2_LIB.BASEBOARD_FAB2(SCH_1):GND
    9  GND            VSS<90>  @BASEBOARD_FAB2_LIB.BASEBOARD_FAB2(SCH_1):GND
   11  GND            VSS<89>  @BASEBOARD_FAB2_LIB.BASEBOARD_FAB2(SCH_1):GND
   13  GND            VSS<88>  @BASEBOARD_FAB2_LIB.BASEBOARD_FAB2(SCH_1):GND
   15  GND            VSS<87>  @BASEBOARD_FAB2_LIB.BASEBOARD_FAB2(SCH_1):GND
   17  GND            VSS<86>  @BASEBOARD_FAB2_LIB.BASEBOARD_FAB2(SCH_1):GND
   20  GND            VSS<85>  @BASEBOARD_FAB2_LIB.BASEBOARD_FAB2(SCH_1):GND
   22  GND            VSS<84>  @BASEBOARD_FAB2_LIB.BASEBOARD_FAB2(SCH_1):GND
   24  GND            VSS<83>  @BASEBOARD_FAB2_LIB.BASEBOARD_FAB2(SCH_1):GND
   26  GND            VSS<82>  @BASEBOARD_FAB2_LIB.BASEBOARD_FAB2(SCH_1):GND
   28  GND            VSS<81>  @BASEBOARD_FAB2_LIB.BASEBOARD_FAB2(SCH_1):GND
   31  GND            VSS<80>  @BASEBOARD_FAB2_LIB.BASEBOARD_FAB2(SCH_1):GND
   33  GND            VSS<79>  @BASEBOARD_FAB2_LIB.BASEBOARD_FAB2(SCH_1):GND
   35  GND            VSS<78>  @BASEBOARD_FAB2_LIB.BASEBOARD_FAB2(SCH_1):GND
   37  GND            VSS<77>  @BASEBOARD_FAB2_LIB.BASEBOARD_FAB2(SCH_1):GND
   39  GND            VSS<76>  @BASEBOARD_FAB2_LIB.BASEBOARD_FAB2(SCH_1):GND
   42  GND            VSS<75>  @BASEBOARD_FAB2_LIB.BASEBOARD_FAB2(SCH_1):GND
   44  GND            VSS<74>  @BASEBOARD_FAB2_LIB.BASEBOARD_FAB2(SCH_1):GND
   46  GND            VSS<73>  @BASEBOARD_FAB2_LIB.BASEBOARD_FAB2(SCH_1):GND
   48  GND            VSS<72>  @BASEBOARD_FAB2_LIB.BASEBOARD_FAB2(SCH_1):GND
   50  GND            VSS<71>  @BASEBOARD_FAB2_LIB.BASEBOARD_FAB2(SCH_1):GND
   53  GND            VSS<70>  @BASEBOARD_FAB2_LIB.BASEBOARD_FAB2(SCH_1):GND
   55  GND            VSS<69>  @BASEBOARD_FAB2_LIB.BASEBOARD_FAB2(SCH_1):GND
   57  GND            VSS<68>  @BASEBOARD_FAB2_LIB.BASEBOARD_FAB2(SCH_1):GND
   94  GND            VSS<67>  @BASEBOARD_FAB2_LIB.BASEBOARD_FAB2(SCH_1):GND
   96  GND            VSS<66>  @BASEBOARD_FAB2_LIB.BASEBOARD_FAB2(SCH_1):GND
   98  GND            VSS<65>  @BASEBOARD_FAB2_LIB.BASEBOARD_FAB2(SCH_1):GND
  101  GND            VSS<64>  @BASEBOARD_FAB2_LIB.BASEBOARD_FAB2(SCH_1):GND
  103  GND            VSS<63>  @BASEBOARD_FAB2_LIB.BASEBOARD_FAB2(SCH_1):GND
  105  GND            VSS<62>  @BASEBOARD_FAB2_LIB.BASEBOARD_FAB2(SCH_1):GND
  107  GND            VSS<61>  @BASEBOARD_FAB2_LIB.BASEBOARD_FAB2(SCH_1):GND
  109  GND            VSS<60>  @BASEBOARD_FAB2_LIB.BASEBOARD_FAB2(SCH_1):GND
  112  GND            VSS<59>  @BASEBOARD_FAB2_LIB.BASEBOARD_FAB2(SCH_1):GND
  114  GND            VSS<58>  @BASEBOARD_FAB2_LIB.BASEBOARD_FAB2(SCH_1):GND
  116  GND            VSS<57>  @BASEBOARD_FAB2_LIB.BASEBOARD_FAB2(SCH_1):GND
  118  GND            VSS<56>  @BASEBOARD_FAB2_LIB.BASEBOARD_FAB2(SCH_1):GND
  120  GND            VSS<55>  @BASEBOARD_FAB2_LIB.BASEBOARD_FAB2(SCH_1):GND
  123  GND            VSS<54>  @BASEBOARD_FAB2_LIB.BASEBOARD_FAB2(SCH_1):GND
  125  GND            VSS<53>  @BASEBOARD_FAB2_LIB.BASEBOARD_FAB2(SCH_1):GND
  127  GND            VSS<52>  @BASEBOARD_FAB2_LIB.BASEBOARD_FAB2(SCH_1):GND
  129  GND            VSS<51>  @BASEBOARD_FAB2_LIB.BASEBOARD_FAB2(SCH_1):GND
  131  GND            VSS<50>  @BASEBOARD_FAB2_LIB.BASEBOARD_FAB2(SCH_1):GND
  134  GND            VSS<49>  @BASEBOARD_FAB2_LIB.BASEBOARD_FAB2(SCH_1):GND
  136  GND            VSS<48>  @BASEBOARD_FAB2_LIB.BASEBOARD_FAB2(SCH_1):GND
  138  GND            VSS<47>  @BASEBOARD_FAB2_LIB.BASEBOARD_FAB2(SCH_1):GND
  147  GND            VSS<46>  @BASEBOARD_FAB2_LIB.BASEBOARD_FAB2(SCH_1):GND
  149  GND            VSS<45>  @BASEBOARD_FAB2_LIB.BASEBOARD_FAB2(SCH_1):GND
  151  GND            VSS<44>  @BASEBOARD_FAB2_LIB.BASEBOARD_FAB2(SCH_1):GND
  154  GND            VSS<43>  @BASEBOARD_FAB2_LIB.BASEBOARD_FAB2(SCH_1):GND
  156  GND            VSS<42>  @BASEBOARD_FAB2_LIB.BASEBOARD_FAB2(SCH_1):GND
  158  GND            VSS<41>  @BASEBOARD_FAB2_LIB.BASEBOARD_FAB2(SCH_1):GND
  160  GND            VSS<40>  @BASEBOARD_FAB2_LIB.BASEBOARD_FAB2(SCH_1):GND
  162  GND            VSS<39>  @BASEBOARD_FAB2_LIB.BASEBOARD_FAB2(SCH_1):GND
  165  GND            VSS<38>  @BASEBOARD_FAB2_LIB.BASEBOARD_FAB2(SCH_1):GND
  167  GND            VSS<37>  @BASEBOARD_FAB2_LIB.BASEBOARD_FAB2(SCH_1):GND
  169  GND            VSS<36>  @BASEBOARD_FAB2_LIB.BASEBOARD_FAB2(SCH_1):GND
  171  GND            VSS<35>  @BASEBOARD_FAB2_LIB.BASEBOARD_FAB2(SCH_1):GND
  173  GND            VSS<34>  @BASEBOARD_FAB2_LIB.BASEBOARD_FAB2(SCH_1):GND
  176  GND            VSS<33>  @BASEBOARD_FAB2_LIB.BASEBOARD_FAB2(SCH_1):GND
  178  GND            VSS<32>  @BASEBOARD_FAB2_LIB.BASEBOARD_FAB2(SCH_1):GND
  180  GND            VSS<31>  @BASEBOARD_FAB2_LIB.BASEBOARD_FAB2(SCH_1):GND
  182  GND            VSS<30>  @BASEBOARD_FAB2_LIB.BASEBOARD_FAB2(SCH_1):GND
  184  GND            VSS<29>  @BASEBOARD_FAB2_LIB.BASEBOARD_FAB2(SCH_1):GND
  187  GND            VSS<28>  @BASEBOARD_FAB2_LIB.BASEBOARD_FAB2(SCH_1):GND
  189  GND            VSS<27>  @BASEBOARD_FAB2_LIB.BASEBOARD_FAB2(SCH_1):GND
  191  GND            VSS<26>  @BASEBOARD_FAB2_LIB.BASEBOARD_FAB2(SCH_1):GND
  193  GND            VSS<25>  @BASEBOARD_FAB2_LIB.BASEBOARD_FAB2(SCH_1):GND
  195  GND            VSS<24>  @BASEBOARD_FAB2_LIB.BASEBOARD_FAB2(SCH_1):GND
  198  GND            VSS<23>  @BASEBOARD_FAB2_LIB.BASEBOARD_FAB2(SCH_1):GND
  200  GND            VSS<22>  @BASEBOARD_FAB2_LIB.BASEBOARD_FAB2(SCH_1):GND
  202  GND            VSS<21>  @BASEBOARD_FAB2_LIB.BASEBOARD_FAB2(SCH_1):GND
  239  GND            VSS<20>  @BASEBOARD_FAB2_LIB.BASEBOARD_FAB2(SCH_1):GND
  241  GND            VSS<19>  @BASEBOARD_FAB2_LIB.BASEBOARD_FAB2(SCH_1):GND
  243  GND            VSS<18>  @BASEBOARD_FAB2_LIB.BASEBOARD_FAB2(SCH_1):GND
  246  GND            VSS<17>  @BASEBOARD_FAB2_LIB.BASEBOARD_FAB2(SCH_1):GND
  248  GND            VSS<16>  @BASEBOARD_FAB2_LIB.BASEBOARD_FAB2(SCH_1):GND
  250  GND            VSS<15>  @BASEBOARD_FAB2_LIB.BASEBOARD_FAB2(SCH_1):GND
  252  GND            VSS<14>  @BASEBOARD_FAB2_LIB.BASEBOARD_FAB2(SCH_1):GND
  254  GND            VSS<13>  @BASEBOARD_FAB2_LIB.BASEBOARD_FAB2(SCH_1):GND
  257  GND            VSS<12>  @BASEBOARD_FAB2_LIB.BASEBOARD_FAB2(SCH_1):GND
  259  GND            VSS<11>  @BASEBOARD_FAB2_LIB.BASEBOARD_FAB2(SCH_1):GND
  261  GND            VSS<10>  @BASEBOARD_FAB2_LIB.BASEBOARD_FAB2(SCH_1):GND
  263  GND            VSS<9>  @BASEBOARD_FAB2_LIB.BASEBOARD_FAB2(SCH_1):GND
  265  GND            VSS<8>  @BASEBOARD_FAB2_LIB.BASEBOARD_FAB2(SCH_1):GND
  268  GND            VSS<7>  @BASEBOARD_FAB2_LIB.BASEBOARD_FAB2(SCH_1):GND
  270  GND            VSS<6>  @BASEBOARD_FAB2_LIB.BASEBOARD_FAB2(SCH_1):GND
  272  GND            VSS<5>  @BASEBOARD_FAB2_LIB.BASEBOARD_FAB2(SCH_1):GND
  274  GND            VSS<4>  @BASEBOARD_FAB2_LIB.BASEBOARD_FAB2(SCH_1):GND
  276  GND            VSS<3>  @BASEBOARD_FAB2_LIB.BASEBOARD_FAB2(SCH_1):GND
  279  GND            VSS<2>  @BASEBOARD_FAB2_LIB.BASEBOARD_FAB2(SCH_1):GND
  281  GND            VSS<1>  @BASEBOARD_FAB2_LIB.BASEBOARD_FAB2(SCH_1):GND
  283  GND            VSS<0>  @BASEBOARD_FAB2_LIB.BASEBOARD_FAB2(SCH_1):GND

SCONN288_H44441003_PIP  I100  J6L2   [SCONN288_H44441003_PIP-SCONN,HA]
    7  M_E_DQS_DP<9>  DQS9P  @BASEBOARD_FAB2_LIB.BASEBOARD_FAB2(SCH_1):M_E_DQS_DP<9>
  197  M_E_DQS_DP<8>  DQS8P  @BASEBOARD_FAB2_LIB.BASEBOARD_FAB2(SCH_1):M_E_DQS_DP<8>
  278  M_E_DQS_DP<7>  DQS7P  @BASEBOARD_FAB2_LIB.BASEBOARD_FAB2(SCH_1):M_E_DQS_DP<7>
  267  M_E_DQS_DP<6>  DQS6P  @BASEBOARD_FAB2_LIB.BASEBOARD_FAB2(SCH_1):M_E_DQS_DP<6>
  256  M_E_DQS_DP<5>  DQS5P  @BASEBOARD_FAB2_LIB.BASEBOARD_FAB2(SCH_1):M_E_DQS_DP<5>
  245  M_E_DQS_DP<4>  DQS4P  @BASEBOARD_FAB2_LIB.BASEBOARD_FAB2(SCH_1):M_E_DQS_DP<4>
  186  M_E_DQS_DP<3>  DQS3P  @BASEBOARD_FAB2_LIB.BASEBOARD_FAB2(SCH_1):M_E_DQS_DP<3>
  175  M_E_DQS_DP<2>  DQS2P  @BASEBOARD_FAB2_LIB.BASEBOARD_FAB2(SCH_1):M_E_DQS_DP<2>
  164  M_E_DQS_DP<1>  DQS1P  @BASEBOARD_FAB2_LIB.BASEBOARD_FAB2(SCH_1):M_E_DQS_DP<1>
   51  M_E_DQS_DP<17>  DQS17P  @BASEBOARD_FAB2_LIB.BASEBOARD_FAB2(SCH_1):M_E_DQS_DP<17>
  132  M_E_DQS_DP<16>  DQS16P  @BASEBOARD_FAB2_LIB.BASEBOARD_FAB2(SCH_1):M_E_DQS_DP<16>
  121  M_E_DQS_DP<15>  DQS15P  @BASEBOARD_FAB2_LIB.BASEBOARD_FAB2(SCH_1):M_E_DQS_DP<15>
  110  M_E_DQS_DP<14>  DQS14P  @BASEBOARD_FAB2_LIB.BASEBOARD_FAB2(SCH_1):M_E_DQS_DP<14>
   99  M_E_DQS_DP<13>  DQS13P  @BASEBOARD_FAB2_LIB.BASEBOARD_FAB2(SCH_1):M_E_DQS_DP<13>
   40  M_E_DQS_DP<12>  DQS12P  @BASEBOARD_FAB2_LIB.BASEBOARD_FAB2(SCH_1):M_E_DQS_DP<12>
   29  M_E_DQS_DP<11>  DQS11P  @BASEBOARD_FAB2_LIB.BASEBOARD_FAB2(SCH_1):M_E_DQS_DP<11>
   18  M_E_DQS_DP<10>  DQS10P  @BASEBOARD_FAB2_LIB.BASEBOARD_FAB2(SCH_1):M_E_DQS_DP<10>
  153  M_E_DQS_DP<0>  DQS0P  @BASEBOARD_FAB2_LIB.BASEBOARD_FAB2(SCH_1):M_E_DQS_DP<0>
    8  M_E_DQS_DN<9>  DQS9N  @BASEBOARD_FAB2_LIB.BASEBOARD_FAB2(SCH_1):M_E_DQS_DN<9>
  196  M_E_DQS_DN<8>  DQS8N  @BASEBOARD_FAB2_LIB.BASEBOARD_FAB2(SCH_1):M_E_DQS_DN<8>
  277  M_E_DQS_DN<7>  DQS7N  @BASEBOARD_FAB2_LIB.BASEBOARD_FAB2(SCH_1):M_E_DQS_DN<7>
  266  M_E_DQS_DN<6>  DQS6N  @BASEBOARD_FAB2_LIB.BASEBOARD_FAB2(SCH_1):M_E_DQS_DN<6>
  255  M_E_DQS_DN<5>  DQS5N  @BASEBOARD_FAB2_LIB.BASEBOARD_FAB2(SCH_1):M_E_DQS_DN<5>
  244  M_E_DQS_DN<4>  DQS4N  @BASEBOARD_FAB2_LIB.BASEBOARD_FAB2(SCH_1):M_E_DQS_DN<4>
  185  M_E_DQS_DN<3>  DQS3N  @BASEBOARD_FAB2_LIB.BASEBOARD_FAB2(SCH_1):M_E_DQS_DN<3>
  174  M_E_DQS_DN<2>  DQS2N  @BASEBOARD_FAB2_LIB.BASEBOARD_FAB2(SCH_1):M_E_DQS_DN<2>
  163  M_E_DQS_DN<1>  DQS1N  @BASEBOARD_FAB2_LIB.BASEBOARD_FAB2(SCH_1):M_E_DQS_DN<1>
   52  M_E_DQS_DN<17>  DQS17N  @BASEBOARD_FAB2_LIB.BASEBOARD_FAB2(SCH_1):M_E_DQS_DN<17>
  133  M_E_DQS_DN<16>  DQS16N  @BASEBOARD_FAB2_LIB.BASEBOARD_FAB2(SCH_1):M_E_DQS_DN<16>
  122  M_E_DQS_DN<15>  DQS15N  @BASEBOARD_FAB2_LIB.BASEBOARD_FAB2(SCH_1):M_E_DQS_DN<15>
  111  M_E_DQS_DN<14>  DQS14N  @BASEBOARD_FAB2_LIB.BASEBOARD_FAB2(SCH_1):M_E_DQS_DN<14>
  100  M_E_DQS_DN<13>  DQS13N  @BASEBOARD_FAB2_LIB.BASEBOARD_FAB2(SCH_1):M_E_DQS_DN<13>
   41  M_E_DQS_DN<12>  DQS12N  @BASEBOARD_FAB2_LIB.BASEBOARD_FAB2(SCH_1):M_E_DQS_DN<12>
   30  M_E_DQS_DN<11>  DQS11N  @BASEBOARD_FAB2_LIB.BASEBOARD_FAB2(SCH_1):M_E_DQS_DN<11>
   19  M_E_DQS_DN<10>  DQS10N  @BASEBOARD_FAB2_LIB.BASEBOARD_FAB2(SCH_1):M_E_DQS_DN<10>
  152  M_E_DQS_DN<0>  DQS0N  @BASEBOARD_FAB2_LIB.BASEBOARD_FAB2(SCH_1):M_E_DQS_DN<0>

SCONN288_H44441003_PIP  I12  J6L2   [SCONN288_H44441003_PIP-SCONN,HA]
  144  TP_CH_E_DIMM_E1_RFU_2  RFU<2>  @BASEBOARD_FAB2_LIB.BASEBOARD_FAB2(SCH_1):TP_CH_E_DIMM_E1_RFU_2
  227  TP_CH_E_DIMM_E1_RFU_1  RFU<1>  @BASEBOARD_FAB2_LIB.BASEBOARD_FAB2(SCH_1):TP_CH_E_DIMM_E1_RFU_1
  205  TP_CH_E_DIMM_E1_RFU_0  RFU<0>  @BASEBOARD_FAB2_LIB.BASEBOARD_FAB2(SCH_1):TP_CH_E_DIMM_E1_RFU_0
  285  SMB_DDR_DEF_VPP_SDA    SDA  @BASEBOARD_FAB2_LIB.BASEBOARD_FAB2(SCH_1):SMB_DDR_DEF_VPP_SDA
  141  SMB_DDR_DEF_VPP_SCL    SCL  @BASEBOARD_FAB2_LIB.BASEBOARD_FAB2(SCH_1):SMB_DDR_DEF_VPP_SCL
  284  PVPP_DEF       VDDSPD  @BASEBOARD_FAB2_LIB.BASEBOARD_FAB2(SCH_1):PVPP_DEF
  140  PVPP_DEF       SA<1>  @BASEBOARD_FAB2_LIB.BASEBOARD_FAB2(SCH_1):PVPP_DEF
  139  PVPP_DEF       SA<0>  @BASEBOARD_FAB2_LIB.BASEBOARD_FAB2(SCH_1):PVPP_DEF
  146  M_E_VREF       VREFCA  @BASEBOARD_FAB2_LIB.BASEBOARD_FAB2(SCH_1):M_E_VREF
  222  M_E_PAR          PAR  @BASEBOARD_FAB2_LIB.BASEBOARD_FAB2(SCH_1):M_E_PAR
   91  M_E_ODT<3>     ODT<1>  @BASEBOARD_FAB2_LIB.BASEBOARD_FAB2(SCH_1):M_E_ODT<3>
   87  M_E_ODT<2>     ODT<0>  @BASEBOARD_FAB2_LIB.BASEBOARD_FAB2(SCH_1):M_E_ODT<2>
   66  M_E_MA<9>         A9  @BASEBOARD_FAB2_LIB.BASEBOARD_FAB2(SCH_1):M_E_MA<9>
   68  M_E_MA<8>         A8  @BASEBOARD_FAB2_LIB.BASEBOARD_FAB2(SCH_1):M_E_MA<8>
  211  M_E_MA<7>         A7  @BASEBOARD_FAB2_LIB.BASEBOARD_FAB2(SCH_1):M_E_MA<7>
   69  M_E_MA<6>         A6  @BASEBOARD_FAB2_LIB.BASEBOARD_FAB2(SCH_1):M_E_MA<6>
  213  M_E_MA<5>         A5  @BASEBOARD_FAB2_LIB.BASEBOARD_FAB2(SCH_1):M_E_MA<5>
  214  M_E_MA<4>         A4  @BASEBOARD_FAB2_LIB.BASEBOARD_FAB2(SCH_1):M_E_MA<4>
   71  M_E_MA<3>         A3  @BASEBOARD_FAB2_LIB.BASEBOARD_FAB2(SCH_1):M_E_MA<3>
  216  M_E_MA<2>         A2  @BASEBOARD_FAB2_LIB.BASEBOARD_FAB2(SCH_1):M_E_MA<2>
   72  M_E_MA<1>         A1  @BASEBOARD_FAB2_LIB.BASEBOARD_FAB2(SCH_1):M_E_MA<1>
  234  M_E_MA<17>       A17  @BASEBOARD_FAB2_LIB.BASEBOARD_FAB2(SCH_1):M_E_MA<17>
   82  M_E_MA<16>     A16_RAS_N  @BASEBOARD_FAB2_LIB.BASEBOARD_FAB2(SCH_1):M_E_MA<16>
   86  M_E_MA<15>     A15_CAS_N  @BASEBOARD_FAB2_LIB.BASEBOARD_FAB2(SCH_1):M_E_MA<15>
  228  M_E_MA<14>     A14_WE_N  @BASEBOARD_FAB2_LIB.BASEBOARD_FAB2(SCH_1):M_E_MA<14>
  232  M_E_MA<13>       A13  @BASEBOARD_FAB2_LIB.BASEBOARD_FAB2(SCH_1):M_E_MA<13>
   65  M_E_MA<12>       A12  @BASEBOARD_FAB2_LIB.BASEBOARD_FAB2(SCH_1):M_E_MA<12>
  210  M_E_MA<11>       A11  @BASEBOARD_FAB2_LIB.BASEBOARD_FAB2(SCH_1):M_E_MA<11>
  225  M_E_MA<10>       A10  @BASEBOARD_FAB2_LIB.BASEBOARD_FAB2(SCH_1):M_E_MA<10>
   79  M_E_MA<0>         A0  @BASEBOARD_FAB2_LIB.BASEBOARD_FAB2(SCH_1):M_E_MA<0>
  199  M_E_ECC<7>     CB<7>  @BASEBOARD_FAB2_LIB.BASEBOARD_FAB2(SCH_1):M_E_ECC<7>
   54  M_E_ECC<6>     CB<6>  @BASEBOARD_FAB2_LIB.BASEBOARD_FAB2(SCH_1):M_E_ECC<6>
  192  M_E_ECC<5>     CB<5>  @BASEBOARD_FAB2_LIB.BASEBOARD_FAB2(SCH_1):M_E_ECC<5>
   47  M_E_ECC<4>     CB<4>  @BASEBOARD_FAB2_LIB.BASEBOARD_FAB2(SCH_1):M_E_ECC<4>
  201  M_E_ECC<3>     CB<3>  @BASEBOARD_FAB2_LIB.BASEBOARD_FAB2(SCH_1):M_E_ECC<3>
   56  M_E_ECC<2>     CB<2>  @BASEBOARD_FAB2_LIB.BASEBOARD_FAB2(SCH_1):M_E_ECC<2>
  194  M_E_ECC<1>     CB<1>  @BASEBOARD_FAB2_LIB.BASEBOARD_FAB2(SCH_1):M_E_ECC<1>
   49  M_E_ECC<0>     CB<0>  @BASEBOARD_FAB2_LIB.BASEBOARD_FAB2(SCH_1):M_E_ECC<0>
  161  M_E_DQ<9>      DQ<9>  @BASEBOARD_FAB2_LIB.BASEBOARD_FAB2(SCH_1):M_E_DQ<9>
   16  M_E_DQ<8>      DQ<8>  @BASEBOARD_FAB2_LIB.BASEBOARD_FAB2(SCH_1):M_E_DQ<8>
  155  M_E_DQ<7>      DQ<7>  @BASEBOARD_FAB2_LIB.BASEBOARD_FAB2(SCH_1):M_E_DQ<7>
   10  M_E_DQ<6>      DQ<6>  @BASEBOARD_FAB2_LIB.BASEBOARD_FAB2(SCH_1):M_E_DQ<6>
  280  M_E_DQ<63>     DQ<63>  @BASEBOARD_FAB2_LIB.BASEBOARD_FAB2(SCH_1):M_E_DQ<63>
  135  M_E_DQ<62>     DQ<62>  @BASEBOARD_FAB2_LIB.BASEBOARD_FAB2(SCH_1):M_E_DQ<62>
  273  M_E_DQ<61>     DQ<61>  @BASEBOARD_FAB2_LIB.BASEBOARD_FAB2(SCH_1):M_E_DQ<61>
  128  M_E_DQ<60>     DQ<60>  @BASEBOARD_FAB2_LIB.BASEBOARD_FAB2(SCH_1):M_E_DQ<60>
  148  M_E_DQ<5>      DQ<5>  @BASEBOARD_FAB2_LIB.BASEBOARD_FAB2(SCH_1):M_E_DQ<5>
  282  M_E_DQ<59>     DQ<59>  @BASEBOARD_FAB2_LIB.BASEBOARD_FAB2(SCH_1):M_E_DQ<59>
  137  M_E_DQ<58>     DQ<58>  @BASEBOARD_FAB2_LIB.BASEBOARD_FAB2(SCH_1):M_E_DQ<58>
  275  M_E_DQ<57>     DQ<57>  @BASEBOARD_FAB2_LIB.BASEBOARD_FAB2(SCH_1):M_E_DQ<57>
  130  M_E_DQ<56>     DQ<56>  @BASEBOARD_FAB2_LIB.BASEBOARD_FAB2(SCH_1):M_E_DQ<56>
  269  M_E_DQ<55>     DQ<55>  @BASEBOARD_FAB2_LIB.BASEBOARD_FAB2(SCH_1):M_E_DQ<55>
  124  M_E_DQ<54>     DQ<54>  @BASEBOARD_FAB2_LIB.BASEBOARD_FAB2(SCH_1):M_E_DQ<54>
  262  M_E_DQ<53>     DQ<53>  @BASEBOARD_FAB2_LIB.BASEBOARD_FAB2(SCH_1):M_E_DQ<53>
  117  M_E_DQ<52>     DQ<52>  @BASEBOARD_FAB2_LIB.BASEBOARD_FAB2(SCH_1):M_E_DQ<52>
  271  M_E_DQ<51>     DQ<51>  @BASEBOARD_FAB2_LIB.BASEBOARD_FAB2(SCH_1):M_E_DQ<51>
  126  M_E_DQ<50>     DQ<50>  @BASEBOARD_FAB2_LIB.BASEBOARD_FAB2(SCH_1):M_E_DQ<50>
    3  M_E_DQ<4>      DQ<4>  @BASEBOARD_FAB2_LIB.BASEBOARD_FAB2(SCH_1):M_E_DQ<4>
  264  M_E_DQ<49>     DQ<49>  @BASEBOARD_FAB2_LIB.BASEBOARD_FAB2(SCH_1):M_E_DQ<49>
  119  M_E_DQ<48>     DQ<48>  @BASEBOARD_FAB2_LIB.BASEBOARD_FAB2(SCH_1):M_E_DQ<48>
  258  M_E_DQ<47>     DQ<47>  @BASEBOARD_FAB2_LIB.BASEBOARD_FAB2(SCH_1):M_E_DQ<47>
  113  M_E_DQ<46>     DQ<46>  @BASEBOARD_FAB2_LIB.BASEBOARD_FAB2(SCH_1):M_E_DQ<46>
  251  M_E_DQ<45>     DQ<45>  @BASEBOARD_FAB2_LIB.BASEBOARD_FAB2(SCH_1):M_E_DQ<45>
  106  M_E_DQ<44>     DQ<44>  @BASEBOARD_FAB2_LIB.BASEBOARD_FAB2(SCH_1):M_E_DQ<44>
  260  M_E_DQ<43>     DQ<43>  @BASEBOARD_FAB2_LIB.BASEBOARD_FAB2(SCH_1):M_E_DQ<43>
  115  M_E_DQ<42>     DQ<42>  @BASEBOARD_FAB2_LIB.BASEBOARD_FAB2(SCH_1):M_E_DQ<42>
  253  M_E_DQ<41>     DQ<41>  @BASEBOARD_FAB2_LIB.BASEBOARD_FAB2(SCH_1):M_E_DQ<41>
  108  M_E_DQ<40>     DQ<40>  @BASEBOARD_FAB2_LIB.BASEBOARD_FAB2(SCH_1):M_E_DQ<40>
  157  M_E_DQ<3>      DQ<3>  @BASEBOARD_FAB2_LIB.BASEBOARD_FAB2(SCH_1):M_E_DQ<3>
  247  M_E_DQ<39>     DQ<39>  @BASEBOARD_FAB2_LIB.BASEBOARD_FAB2(SCH_1):M_E_DQ<39>
  102  M_E_DQ<38>     DQ<38>  @BASEBOARD_FAB2_LIB.BASEBOARD_FAB2(SCH_1):M_E_DQ<38>
  240  M_E_DQ<37>     DQ<37>  @BASEBOARD_FAB2_LIB.BASEBOARD_FAB2(SCH_1):M_E_DQ<37>
   95  M_E_DQ<36>     DQ<36>  @BASEBOARD_FAB2_LIB.BASEBOARD_FAB2(SCH_1):M_E_DQ<36>
  249  M_E_DQ<35>     DQ<35>  @BASEBOARD_FAB2_LIB.BASEBOARD_FAB2(SCH_1):M_E_DQ<35>
  104  M_E_DQ<34>     DQ<34>  @BASEBOARD_FAB2_LIB.BASEBOARD_FAB2(SCH_1):M_E_DQ<34>
  242  M_E_DQ<33>     DQ<33>  @BASEBOARD_FAB2_LIB.BASEBOARD_FAB2(SCH_1):M_E_DQ<33>
   97  M_E_DQ<32>     DQ<32>  @BASEBOARD_FAB2_LIB.BASEBOARD_FAB2(SCH_1):M_E_DQ<32>
  188  M_E_DQ<31>     DQ<31>  @BASEBOARD_FAB2_LIB.BASEBOARD_FAB2(SCH_1):M_E_DQ<31>
   43  M_E_DQ<30>     DQ<30>  @BASEBOARD_FAB2_LIB.BASEBOARD_FAB2(SCH_1):M_E_DQ<30>
   12  M_E_DQ<2>      DQ<2>  @BASEBOARD_FAB2_LIB.BASEBOARD_FAB2(SCH_1):M_E_DQ<2>
  181  M_E_DQ<29>     DQ<29>  @BASEBOARD_FAB2_LIB.BASEBOARD_FAB2(SCH_1):M_E_DQ<29>
   36  M_E_DQ<28>     DQ<28>  @BASEBOARD_FAB2_LIB.BASEBOARD_FAB2(SCH_1):M_E_DQ<28>
  190  M_E_DQ<27>     DQ<27>  @BASEBOARD_FAB2_LIB.BASEBOARD_FAB2(SCH_1):M_E_DQ<27>
   45  M_E_DQ<26>     DQ<26>  @BASEBOARD_FAB2_LIB.BASEBOARD_FAB2(SCH_1):M_E_DQ<26>
  183  M_E_DQ<25>     DQ<25>  @BASEBOARD_FAB2_LIB.BASEBOARD_FAB2(SCH_1):M_E_DQ<25>
   38  M_E_DQ<24>     DQ<24>  @BASEBOARD_FAB2_LIB.BASEBOARD_FAB2(SCH_1):M_E_DQ<24>
  177  M_E_DQ<23>     DQ<23>  @BASEBOARD_FAB2_LIB.BASEBOARD_FAB2(SCH_1):M_E_DQ<23>
   32  M_E_DQ<22>     DQ<22>  @BASEBOARD_FAB2_LIB.BASEBOARD_FAB2(SCH_1):M_E_DQ<22>
  170  M_E_DQ<21>     DQ<21>  @BASEBOARD_FAB2_LIB.BASEBOARD_FAB2(SCH_1):M_E_DQ<21>
   25  M_E_DQ<20>     DQ<20>  @BASEBOARD_FAB2_LIB.BASEBOARD_FAB2(SCH_1):M_E_DQ<20>
  150  M_E_DQ<1>      DQ<1>  @BASEBOARD_FAB2_LIB.BASEBOARD_FAB2(SCH_1):M_E_DQ<1>
  179  M_E_DQ<19>     DQ<19>  @BASEBOARD_FAB2_LIB.BASEBOARD_FAB2(SCH_1):M_E_DQ<19>
   34  M_E_DQ<18>     DQ<18>  @BASEBOARD_FAB2_LIB.BASEBOARD_FAB2(SCH_1):M_E_DQ<18>
  172  M_E_DQ<17>     DQ<17>  @BASEBOARD_FAB2_LIB.BASEBOARD_FAB2(SCH_1):M_E_DQ<17>
   27  M_E_DQ<16>     DQ<16>  @BASEBOARD_FAB2_LIB.BASEBOARD_FAB2(SCH_1):M_E_DQ<16>
  166  M_E_DQ<15>     DQ<15>  @BASEBOARD_FAB2_LIB.BASEBOARD_FAB2(SCH_1):M_E_DQ<15>
   21  M_E_DQ<14>     DQ<14>  @BASEBOARD_FAB2_LIB.BASEBOARD_FAB2(SCH_1):M_E_DQ<14>
  159  M_E_DQ<13>     DQ<13>  @BASEBOARD_FAB2_LIB.BASEBOARD_FAB2(SCH_1):M_E_DQ<13>
   14  M_E_DQ<12>     DQ<12>  @BASEBOARD_FAB2_LIB.BASEBOARD_FAB2(SCH_1):M_E_DQ<12>
  168  M_E_DQ<11>     DQ<11>  @BASEBOARD_FAB2_LIB.BASEBOARD_FAB2(SCH_1):M_E_DQ<11>
   23  M_E_DQ<10>     DQ<10>  @BASEBOARD_FAB2_LIB.BASEBOARD_FAB2(SCH_1):M_E_DQ<10>
    5  M_E_DQ<0>      DQ<0>  @BASEBOARD_FAB2_LIB.BASEBOARD_FAB2(SCH_1):M_E_DQ<0>
  237  M_E_CS_N<7>    S3_N_C<1>  @BASEBOARD_FAB2_LIB.BASEBOARD_FAB2(SCH_1):M_E_CS_N<7>
   93  M_E_CS_N<6>    S2_N_C<0>  @BASEBOARD_FAB2_LIB.BASEBOARD_FAB2(SCH_1):M_E_CS_N<6>
   89  M_E_CS_N<5>     S1_N  @BASEBOARD_FAB2_LIB.BASEBOARD_FAB2(SCH_1):M_E_CS_N<5>
   84  M_E_CS_N<4>     S0_N  @BASEBOARD_FAB2_LIB.BASEBOARD_FAB2(SCH_1):M_E_CS_N<4>
  218  M_E_CLK_DP<3>   CK1P  @BASEBOARD_FAB2_LIB.BASEBOARD_FAB2(SCH_1):M_E_CLK_DP<3>
   74  M_E_CLK_DP<2>   CK0P  @BASEBOARD_FAB2_LIB.BASEBOARD_FAB2(SCH_1):M_E_CLK_DP<2>
  219  M_E_CLK_DN<3>   CK1N  @BASEBOARD_FAB2_LIB.BASEBOARD_FAB2(SCH_1):M_E_CLK_DN<3>
   75  M_E_CLK_DN<2>   CK0N  @BASEBOARD_FAB2_LIB.BASEBOARD_FAB2(SCH_1):M_E_CLK_DN<2>
  203  M_E_CKE<3>     CKE<1>  @BASEBOARD_FAB2_LIB.BASEBOARD_FAB2(SCH_1):M_E_CKE<3>
   60  M_E_CKE<2>     CKE<0>  @BASEBOARD_FAB2_LIB.BASEBOARD_FAB2(SCH_1):M_E_CKE<2>
  235  M_E_C<2>        C<2>  @BASEBOARD_FAB2_LIB.BASEBOARD_FAB2(SCH_1):M_E_C<2>
  207  M_E_BG<1>      BG<1>  @BASEBOARD_FAB2_LIB.BASEBOARD_FAB2(SCH_1):M_E_BG<1>
   63  M_E_BG<0>      BG<0>  @BASEBOARD_FAB2_LIB.BASEBOARD_FAB2(SCH_1):M_E_BG<0>
  224  M_E_BA<1>      BA<1>  @BASEBOARD_FAB2_LIB.BASEBOARD_FAB2(SCH_1):M_E_BA<1>
   81  M_E_BA<0>      BA<0>  @BASEBOARD_FAB2_LIB.BASEBOARD_FAB2(SCH_1):M_E_BA<0>
  208  M_E_ALERT_N    ALERT_N  @BASEBOARD_FAB2_LIB.BASEBOARD_FAB2(SCH_1):M_E_ALERT_N
   62  M_E_ACT_N      ACT_N  @BASEBOARD_FAB2_LIB.BASEBOARD_FAB2(SCH_1):M_E_ACT_N
   58  M_DEF_RST_N    RESET_N  @BASEBOARD_FAB2_LIB.BASEBOARD_FAB2(SCH_1):M_DEF_RST_N
  238  GND            SA<2>  @BASEBOARD_FAB2_LIB.BASEBOARD_FAB2(SCH_1):GND
   78  FM_DIMM_EVENT_COD_N  EVENT_N  @BASEBOARD_FAB2_LIB.BASEBOARD_FAB2(SCH_1):FM_DIMM_EVENT_COD_N
  230  FM_ADR_COMPLETE_DEF_N  SAVE_N_NC  @BASEBOARD_FAB2_LIB.BASEBOARD_FAB2(SCH_1):FM_ADR_COMPLETE_DEF_N

SCONN288_H44441003_PIP  I50  J6M1   [SCONN288_H44441003_PIP-SCONN,HA]
   77  PVTT_DEF       VTT<1>  @BASEBOARD_FAB2_LIB.BASEBOARD_FAB2(SCH_1):PVTT_DEF
  221  PVTT_DEF       VTT<0>  @BASEBOARD_FAB2_LIB.BASEBOARD_FAB2(SCH_1):PVTT_DEF
  142  PVPP_DEF       VPP<4>  @BASEBOARD_FAB2_LIB.BASEBOARD_FAB2(SCH_1):PVPP_DEF
  143  PVPP_DEF       VPP<3>  @BASEBOARD_FAB2_LIB.BASEBOARD_FAB2(SCH_1):PVPP_DEF
  288  PVPP_DEF       VPP<2>  @BASEBOARD_FAB2_LIB.BASEBOARD_FAB2(SCH_1):PVPP_DEF
  286  PVPP_DEF       VPP<1>  @BASEBOARD_FAB2_LIB.BASEBOARD_FAB2(SCH_1):PVPP_DEF
  287  PVPP_DEF       VPP<0>  @BASEBOARD_FAB2_LIB.BASEBOARD_FAB2(SCH_1):PVPP_DEF
   59  PVDDQ_DEF      VDD<25>  @BASEBOARD_FAB2_LIB.BASEBOARD_FAB2(SCH_1):PVDDQ_DEF
   61  PVDDQ_DEF      VDD<24>  @BASEBOARD_FAB2_LIB.BASEBOARD_FAB2(SCH_1):PVDDQ_DEF
   64  PVDDQ_DEF      VDD<23>  @BASEBOARD_FAB2_LIB.BASEBOARD_FAB2(SCH_1):PVDDQ_DEF
   67  PVDDQ_DEF      VDD<22>  @BASEBOARD_FAB2_LIB.BASEBOARD_FAB2(SCH_1):PVDDQ_DEF
   70  PVDDQ_DEF      VDD<21>  @BASEBOARD_FAB2_LIB.BASEBOARD_FAB2(SCH_1):PVDDQ_DEF
   73  PVDDQ_DEF      VDD<20>  @BASEBOARD_FAB2_LIB.BASEBOARD_FAB2(SCH_1):PVDDQ_DEF
   76  PVDDQ_DEF      VDD<19>  @BASEBOARD_FAB2_LIB.BASEBOARD_FAB2(SCH_1):PVDDQ_DEF
   80  PVDDQ_DEF      VDD<18>  @BASEBOARD_FAB2_LIB.BASEBOARD_FAB2(SCH_1):PVDDQ_DEF
   83  PVDDQ_DEF      VDD<17>  @BASEBOARD_FAB2_LIB.BASEBOARD_FAB2(SCH_1):PVDDQ_DEF
   85  PVDDQ_DEF      VDD<16>  @BASEBOARD_FAB2_LIB.BASEBOARD_FAB2(SCH_1):PVDDQ_DEF
   88  PVDDQ_DEF      VDD<15>  @BASEBOARD_FAB2_LIB.BASEBOARD_FAB2(SCH_1):PVDDQ_DEF
   90  PVDDQ_DEF      VDD<14>  @BASEBOARD_FAB2_LIB.BASEBOARD_FAB2(SCH_1):PVDDQ_DEF
   92  PVDDQ_DEF      VDD<13>  @BASEBOARD_FAB2_LIB.BASEBOARD_FAB2(SCH_1):PVDDQ_DEF
  204  PVDDQ_DEF      VDD<12>  @BASEBOARD_FAB2_LIB.BASEBOARD_FAB2(SCH_1):PVDDQ_DEF
  206  PVDDQ_DEF      VDD<11>  @BASEBOARD_FAB2_LIB.BASEBOARD_FAB2(SCH_1):PVDDQ_DEF
  209  PVDDQ_DEF      VDD<10>  @BASEBOARD_FAB2_LIB.BASEBOARD_FAB2(SCH_1):PVDDQ_DEF
  212  PVDDQ_DEF      VDD<9>  @BASEBOARD_FAB2_LIB.BASEBOARD_FAB2(SCH_1):PVDDQ_DEF
  215  PVDDQ_DEF      VDD<8>  @BASEBOARD_FAB2_LIB.BASEBOARD_FAB2(SCH_1):PVDDQ_DEF
  217  PVDDQ_DEF      VDD<7>  @BASEBOARD_FAB2_LIB.BASEBOARD_FAB2(SCH_1):PVDDQ_DEF
  220  PVDDQ_DEF      VDD<6>  @BASEBOARD_FAB2_LIB.BASEBOARD_FAB2(SCH_1):PVDDQ_DEF
  223  PVDDQ_DEF      VDD<5>  @BASEBOARD_FAB2_LIB.BASEBOARD_FAB2(SCH_1):PVDDQ_DEF
  226  PVDDQ_DEF      VDD<4>  @BASEBOARD_FAB2_LIB.BASEBOARD_FAB2(SCH_1):PVDDQ_DEF
  229  PVDDQ_DEF      VDD<3>  @BASEBOARD_FAB2_LIB.BASEBOARD_FAB2(SCH_1):PVDDQ_DEF
  231  PVDDQ_DEF      VDD<2>  @BASEBOARD_FAB2_LIB.BASEBOARD_FAB2(SCH_1):PVDDQ_DEF
  233  PVDDQ_DEF      VDD<1>  @BASEBOARD_FAB2_LIB.BASEBOARD_FAB2(SCH_1):PVDDQ_DEF
  236  PVDDQ_DEF      VDD<0>  @BASEBOARD_FAB2_LIB.BASEBOARD_FAB2(SCH_1):PVDDQ_DEF
    1  P12V_NVDIMM_DEF  12V<1>  @BASEBOARD_FAB2_LIB.BASEBOARD_FAB2(SCH_1):P12V_NVDIMM_DEF
  145  P12V_NVDIMM_DEF  12V<0>  @BASEBOARD_FAB2_LIB.BASEBOARD_FAB2(SCH_1):P12V_NVDIMM_DEF

SCONN288_H44441003_PIP  I44  J6M1   [SCONN288_H44441003_PIP-SCONN,HA]
    2  GND            VSS<93>  @BASEBOARD_FAB2_LIB.BASEBOARD_FAB2(SCH_1):GND
    4  GND            VSS<92>  @BASEBOARD_FAB2_LIB.BASEBOARD_FAB2(SCH_1):GND
    6  GND            VSS<91>  @BASEBOARD_FAB2_LIB.BASEBOARD_FAB2(SCH_1):GND
    9  GND            VSS<90>  @BASEBOARD_FAB2_LIB.BASEBOARD_FAB2(SCH_1):GND
   11  GND            VSS<89>  @BASEBOARD_FAB2_LIB.BASEBOARD_FAB2(SCH_1):GND
   13  GND            VSS<88>  @BASEBOARD_FAB2_LIB.BASEBOARD_FAB2(SCH_1):GND
   15  GND            VSS<87>  @BASEBOARD_FAB2_LIB.BASEBOARD_FAB2(SCH_1):GND
   17  GND            VSS<86>  @BASEBOARD_FAB2_LIB.BASEBOARD_FAB2(SCH_1):GND
   20  GND            VSS<85>  @BASEBOARD_FAB2_LIB.BASEBOARD_FAB2(SCH_1):GND
   22  GND            VSS<84>  @BASEBOARD_FAB2_LIB.BASEBOARD_FAB2(SCH_1):GND
   24  GND            VSS<83>  @BASEBOARD_FAB2_LIB.BASEBOARD_FAB2(SCH_1):GND
   26  GND            VSS<82>  @BASEBOARD_FAB2_LIB.BASEBOARD_FAB2(SCH_1):GND
   28  GND            VSS<81>  @BASEBOARD_FAB2_LIB.BASEBOARD_FAB2(SCH_1):GND
   31  GND            VSS<80>  @BASEBOARD_FAB2_LIB.BASEBOARD_FAB2(SCH_1):GND
   33  GND            VSS<79>  @BASEBOARD_FAB2_LIB.BASEBOARD_FAB2(SCH_1):GND
   35  GND            VSS<78>  @BASEBOARD_FAB2_LIB.BASEBOARD_FAB2(SCH_1):GND
   37  GND            VSS<77>  @BASEBOARD_FAB2_LIB.BASEBOARD_FAB2(SCH_1):GND
   39  GND            VSS<76>  @BASEBOARD_FAB2_LIB.BASEBOARD_FAB2(SCH_1):GND
   42  GND            VSS<75>  @BASEBOARD_FAB2_LIB.BASEBOARD_FAB2(SCH_1):GND
   44  GND            VSS<74>  @BASEBOARD_FAB2_LIB.BASEBOARD_FAB2(SCH_1):GND
   46  GND            VSS<73>  @BASEBOARD_FAB2_LIB.BASEBOARD_FAB2(SCH_1):GND
   48  GND            VSS<72>  @BASEBOARD_FAB2_LIB.BASEBOARD_FAB2(SCH_1):GND
   50  GND            VSS<71>  @BASEBOARD_FAB2_LIB.BASEBOARD_FAB2(SCH_1):GND
   53  GND            VSS<70>  @BASEBOARD_FAB2_LIB.BASEBOARD_FAB2(SCH_1):GND
   55  GND            VSS<69>  @BASEBOARD_FAB2_LIB.BASEBOARD_FAB2(SCH_1):GND
   57  GND            VSS<68>  @BASEBOARD_FAB2_LIB.BASEBOARD_FAB2(SCH_1):GND
   94  GND            VSS<67>  @BASEBOARD_FAB2_LIB.BASEBOARD_FAB2(SCH_1):GND
   96  GND            VSS<66>  @BASEBOARD_FAB2_LIB.BASEBOARD_FAB2(SCH_1):GND
   98  GND            VSS<65>  @BASEBOARD_FAB2_LIB.BASEBOARD_FAB2(SCH_1):GND
  101  GND            VSS<64>  @BASEBOARD_FAB2_LIB.BASEBOARD_FAB2(SCH_1):GND
  103  GND            VSS<63>  @BASEBOARD_FAB2_LIB.BASEBOARD_FAB2(SCH_1):GND
  105  GND            VSS<62>  @BASEBOARD_FAB2_LIB.BASEBOARD_FAB2(SCH_1):GND
  107  GND            VSS<61>  @BASEBOARD_FAB2_LIB.BASEBOARD_FAB2(SCH_1):GND
  109  GND            VSS<60>  @BASEBOARD_FAB2_LIB.BASEBOARD_FAB2(SCH_1):GND
  112  GND            VSS<59>  @BASEBOARD_FAB2_LIB.BASEBOARD_FAB2(SCH_1):GND
  114  GND            VSS<58>  @BASEBOARD_FAB2_LIB.BASEBOARD_FAB2(SCH_1):GND
  116  GND            VSS<57>  @BASEBOARD_FAB2_LIB.BASEBOARD_FAB2(SCH_1):GND
  118  GND            VSS<56>  @BASEBOARD_FAB2_LIB.BASEBOARD_FAB2(SCH_1):GND
  120  GND            VSS<55>  @BASEBOARD_FAB2_LIB.BASEBOARD_FAB2(SCH_1):GND
  123  GND            VSS<54>  @BASEBOARD_FAB2_LIB.BASEBOARD_FAB2(SCH_1):GND
  125  GND            VSS<53>  @BASEBOARD_FAB2_LIB.BASEBOARD_FAB2(SCH_1):GND
  127  GND            VSS<52>  @BASEBOARD_FAB2_LIB.BASEBOARD_FAB2(SCH_1):GND
  129  GND            VSS<51>  @BASEBOARD_FAB2_LIB.BASEBOARD_FAB2(SCH_1):GND
  131  GND            VSS<50>  @BASEBOARD_FAB2_LIB.BASEBOARD_FAB2(SCH_1):GND
  134  GND            VSS<49>  @BASEBOARD_FAB2_LIB.BASEBOARD_FAB2(SCH_1):GND
  136  GND            VSS<48>  @BASEBOARD_FAB2_LIB.BASEBOARD_FAB2(SCH_1):GND
  138  GND            VSS<47>  @BASEBOARD_FAB2_LIB.BASEBOARD_FAB2(SCH_1):GND
  147  GND            VSS<46>  @BASEBOARD_FAB2_LIB.BASEBOARD_FAB2(SCH_1):GND
  149  GND            VSS<45>  @BASEBOARD_FAB2_LIB.BASEBOARD_FAB2(SCH_1):GND
  151  GND            VSS<44>  @BASEBOARD_FAB2_LIB.BASEBOARD_FAB2(SCH_1):GND
  154  GND            VSS<43>  @BASEBOARD_FAB2_LIB.BASEBOARD_FAB2(SCH_1):GND
  156  GND            VSS<42>  @BASEBOARD_FAB2_LIB.BASEBOARD_FAB2(SCH_1):GND
  158  GND            VSS<41>  @BASEBOARD_FAB2_LIB.BASEBOARD_FAB2(SCH_1):GND
  160  GND            VSS<40>  @BASEBOARD_FAB2_LIB.BASEBOARD_FAB2(SCH_1):GND
  162  GND            VSS<39>  @BASEBOARD_FAB2_LIB.BASEBOARD_FAB2(SCH_1):GND
  165  GND            VSS<38>  @BASEBOARD_FAB2_LIB.BASEBOARD_FAB2(SCH_1):GND
  167  GND            VSS<37>  @BASEBOARD_FAB2_LIB.BASEBOARD_FAB2(SCH_1):GND
  169  GND            VSS<36>  @BASEBOARD_FAB2_LIB.BASEBOARD_FAB2(SCH_1):GND
  171  GND            VSS<35>  @BASEBOARD_FAB2_LIB.BASEBOARD_FAB2(SCH_1):GND
  173  GND            VSS<34>  @BASEBOARD_FAB2_LIB.BASEBOARD_FAB2(SCH_1):GND
  176  GND            VSS<33>  @BASEBOARD_FAB2_LIB.BASEBOARD_FAB2(SCH_1):GND
  178  GND            VSS<32>  @BASEBOARD_FAB2_LIB.BASEBOARD_FAB2(SCH_1):GND
  180  GND            VSS<31>  @BASEBOARD_FAB2_LIB.BASEBOARD_FAB2(SCH_1):GND
  182  GND            VSS<30>  @BASEBOARD_FAB2_LIB.BASEBOARD_FAB2(SCH_1):GND
  184  GND            VSS<29>  @BASEBOARD_FAB2_LIB.BASEBOARD_FAB2(SCH_1):GND
  187  GND            VSS<28>  @BASEBOARD_FAB2_LIB.BASEBOARD_FAB2(SCH_1):GND
  189  GND            VSS<27>  @BASEBOARD_FAB2_LIB.BASEBOARD_FAB2(SCH_1):GND
  191  GND            VSS<26>  @BASEBOARD_FAB2_LIB.BASEBOARD_FAB2(SCH_1):GND
  193  GND            VSS<25>  @BASEBOARD_FAB2_LIB.BASEBOARD_FAB2(SCH_1):GND
  195  GND            VSS<24>  @BASEBOARD_FAB2_LIB.BASEBOARD_FAB2(SCH_1):GND
  198  GND            VSS<23>  @BASEBOARD_FAB2_LIB.BASEBOARD_FAB2(SCH_1):GND
  200  GND            VSS<22>  @BASEBOARD_FAB2_LIB.BASEBOARD_FAB2(SCH_1):GND
  202  GND            VSS<21>  @BASEBOARD_FAB2_LIB.BASEBOARD_FAB2(SCH_1):GND
  239  GND            VSS<20>  @BASEBOARD_FAB2_LIB.BASEBOARD_FAB2(SCH_1):GND
  241  GND            VSS<19>  @BASEBOARD_FAB2_LIB.BASEBOARD_FAB2(SCH_1):GND
  243  GND            VSS<18>  @BASEBOARD_FAB2_LIB.BASEBOARD_FAB2(SCH_1):GND
  246  GND            VSS<17>  @BASEBOARD_FAB2_LIB.BASEBOARD_FAB2(SCH_1):GND
  248  GND            VSS<16>  @BASEBOARD_FAB2_LIB.BASEBOARD_FAB2(SCH_1):GND
  250  GND            VSS<15>  @BASEBOARD_FAB2_LIB.BASEBOARD_FAB2(SCH_1):GND
  252  GND            VSS<14>  @BASEBOARD_FAB2_LIB.BASEBOARD_FAB2(SCH_1):GND
  254  GND            VSS<13>  @BASEBOARD_FAB2_LIB.BASEBOARD_FAB2(SCH_1):GND
  257  GND            VSS<12>  @BASEBOARD_FAB2_LIB.BASEBOARD_FAB2(SCH_1):GND
  259  GND            VSS<11>  @BASEBOARD_FAB2_LIB.BASEBOARD_FAB2(SCH_1):GND
  261  GND            VSS<10>  @BASEBOARD_FAB2_LIB.BASEBOARD_FAB2(SCH_1):GND
  263  GND            VSS<9>  @BASEBOARD_FAB2_LIB.BASEBOARD_FAB2(SCH_1):GND
  265  GND            VSS<8>  @BASEBOARD_FAB2_LIB.BASEBOARD_FAB2(SCH_1):GND
  268  GND            VSS<7>  @BASEBOARD_FAB2_LIB.BASEBOARD_FAB2(SCH_1):GND
  270  GND            VSS<6>  @BASEBOARD_FAB2_LIB.BASEBOARD_FAB2(SCH_1):GND
  272  GND            VSS<5>  @BASEBOARD_FAB2_LIB.BASEBOARD_FAB2(SCH_1):GND
  274  GND            VSS<4>  @BASEBOARD_FAB2_LIB.BASEBOARD_FAB2(SCH_1):GND
  276  GND            VSS<3>  @BASEBOARD_FAB2_LIB.BASEBOARD_FAB2(SCH_1):GND
  279  GND            VSS<2>  @BASEBOARD_FAB2_LIB.BASEBOARD_FAB2(SCH_1):GND
  281  GND            VSS<1>  @BASEBOARD_FAB2_LIB.BASEBOARD_FAB2(SCH_1):GND
  283  GND            VSS<0>  @BASEBOARD_FAB2_LIB.BASEBOARD_FAB2(SCH_1):GND

SCONN288_H44441003_PIP  I46  J6M1   [SCONN288_H44441003_PIP-SCONN,HA]
    7  M_D_DQS_DP<9>  DQS9P  @BASEBOARD_FAB2_LIB.BASEBOARD_FAB2(SCH_1):M_D_DQS_DP<9>
  197  M_D_DQS_DP<8>  DQS8P  @BASEBOARD_FAB2_LIB.BASEBOARD_FAB2(SCH_1):M_D_DQS_DP<8>
  278  M_D_DQS_DP<7>  DQS7P  @BASEBOARD_FAB2_LIB.BASEBOARD_FAB2(SCH_1):M_D_DQS_DP<7>
  267  M_D_DQS_DP<6>  DQS6P  @BASEBOARD_FAB2_LIB.BASEBOARD_FAB2(SCH_1):M_D_DQS_DP<6>
  256  M_D_DQS_DP<5>  DQS5P  @BASEBOARD_FAB2_LIB.BASEBOARD_FAB2(SCH_1):M_D_DQS_DP<5>
  245  M_D_DQS_DP<4>  DQS4P  @BASEBOARD_FAB2_LIB.BASEBOARD_FAB2(SCH_1):M_D_DQS_DP<4>
  186  M_D_DQS_DP<3>  DQS3P  @BASEBOARD_FAB2_LIB.BASEBOARD_FAB2(SCH_1):M_D_DQS_DP<3>
  175  M_D_DQS_DP<2>  DQS2P  @BASEBOARD_FAB2_LIB.BASEBOARD_FAB2(SCH_1):M_D_DQS_DP<2>
  164  M_D_DQS_DP<1>  DQS1P  @BASEBOARD_FAB2_LIB.BASEBOARD_FAB2(SCH_1):M_D_DQS_DP<1>
   51  M_D_DQS_DP<17>  DQS17P  @BASEBOARD_FAB2_LIB.BASEBOARD_FAB2(SCH_1):M_D_DQS_DP<17>
  132  M_D_DQS_DP<16>  DQS16P  @BASEBOARD_FAB2_LIB.BASEBOARD_FAB2(SCH_1):M_D_DQS_DP<16>
  121  M_D_DQS_DP<15>  DQS15P  @BASEBOARD_FAB2_LIB.BASEBOARD_FAB2(SCH_1):M_D_DQS_DP<15>
  110  M_D_DQS_DP<14>  DQS14P  @BASEBOARD_FAB2_LIB.BASEBOARD_FAB2(SCH_1):M_D_DQS_DP<14>
   99  M_D_DQS_DP<13>  DQS13P  @BASEBOARD_FAB2_LIB.BASEBOARD_FAB2(SCH_1):M_D_DQS_DP<13>
   40  M_D_DQS_DP<12>  DQS12P  @BASEBOARD_FAB2_LIB.BASEBOARD_FAB2(SCH_1):M_D_DQS_DP<12>
   29  M_D_DQS_DP<11>  DQS11P  @BASEBOARD_FAB2_LIB.BASEBOARD_FAB2(SCH_1):M_D_DQS_DP<11>
   18  M_D_DQS_DP<10>  DQS10P  @BASEBOARD_FAB2_LIB.BASEBOARD_FAB2(SCH_1):M_D_DQS_DP<10>
  153  M_D_DQS_DP<0>  DQS0P  @BASEBOARD_FAB2_LIB.BASEBOARD_FAB2(SCH_1):M_D_DQS_DP<0>
    8  M_D_DQS_DN<9>  DQS9N  @BASEBOARD_FAB2_LIB.BASEBOARD_FAB2(SCH_1):M_D_DQS_DN<9>
  196  M_D_DQS_DN<8>  DQS8N  @BASEBOARD_FAB2_LIB.BASEBOARD_FAB2(SCH_1):M_D_DQS_DN<8>
  277  M_D_DQS_DN<7>  DQS7N  @BASEBOARD_FAB2_LIB.BASEBOARD_FAB2(SCH_1):M_D_DQS_DN<7>
  266  M_D_DQS_DN<6>  DQS6N  @BASEBOARD_FAB2_LIB.BASEBOARD_FAB2(SCH_1):M_D_DQS_DN<6>
  255  M_D_DQS_DN<5>  DQS5N  @BASEBOARD_FAB2_LIB.BASEBOARD_FAB2(SCH_1):M_D_DQS_DN<5>
  244  M_D_DQS_DN<4>  DQS4N  @BASEBOARD_FAB2_LIB.BASEBOARD_FAB2(SCH_1):M_D_DQS_DN<4>
  185  M_D_DQS_DN<3>  DQS3N  @BASEBOARD_FAB2_LIB.BASEBOARD_FAB2(SCH_1):M_D_DQS_DN<3>
  174  M_D_DQS_DN<2>  DQS2N  @BASEBOARD_FAB2_LIB.BASEBOARD_FAB2(SCH_1):M_D_DQS_DN<2>
  163  M_D_DQS_DN<1>  DQS1N  @BASEBOARD_FAB2_LIB.BASEBOARD_FAB2(SCH_1):M_D_DQS_DN<1>
   52  M_D_DQS_DN<17>  DQS17N  @BASEBOARD_FAB2_LIB.BASEBOARD_FAB2(SCH_1):M_D_DQS_DN<17>
  133  M_D_DQS_DN<16>  DQS16N  @BASEBOARD_FAB2_LIB.BASEBOARD_FAB2(SCH_1):M_D_DQS_DN<16>
  122  M_D_DQS_DN<15>  DQS15N  @BASEBOARD_FAB2_LIB.BASEBOARD_FAB2(SCH_1):M_D_DQS_DN<15>
  111  M_D_DQS_DN<14>  DQS14N  @BASEBOARD_FAB2_LIB.BASEBOARD_FAB2(SCH_1):M_D_DQS_DN<14>
  100  M_D_DQS_DN<13>  DQS13N  @BASEBOARD_FAB2_LIB.BASEBOARD_FAB2(SCH_1):M_D_DQS_DN<13>
   41  M_D_DQS_DN<12>  DQS12N  @BASEBOARD_FAB2_LIB.BASEBOARD_FAB2(SCH_1):M_D_DQS_DN<12>
   30  M_D_DQS_DN<11>  DQS11N  @BASEBOARD_FAB2_LIB.BASEBOARD_FAB2(SCH_1):M_D_DQS_DN<11>
   19  M_D_DQS_DN<10>  DQS10N  @BASEBOARD_FAB2_LIB.BASEBOARD_FAB2(SCH_1):M_D_DQS_DN<10>
  152  M_D_DQS_DN<0>  DQS0N  @BASEBOARD_FAB2_LIB.BASEBOARD_FAB2(SCH_1):M_D_DQS_DN<0>

SCONN288_H44441003_PIP  I158  J6M1   [SCONN288_H44441003_PIP-SCONN,HA]
  144  TP_CH_D_DIMM_D1_RFU_2  RFU<2>  @BASEBOARD_FAB2_LIB.BASEBOARD_FAB2(SCH_1):TP_CH_D_DIMM_D1_RFU_2
  227  TP_CH_D_DIMM_D1_RFU_1  RFU<1>  @BASEBOARD_FAB2_LIB.BASEBOARD_FAB2(SCH_1):TP_CH_D_DIMM_D1_RFU_1
  205  TP_CH_D_DIMM_D1_RFU_0  RFU<0>  @BASEBOARD_FAB2_LIB.BASEBOARD_FAB2(SCH_1):TP_CH_D_DIMM_D1_RFU_0
  285  SMB_DDR_DEF_VPP_SDA    SDA  @BASEBOARD_FAB2_LIB.BASEBOARD_FAB2(SCH_1):SMB_DDR_DEF_VPP_SDA
  141  SMB_DDR_DEF_VPP_SCL    SCL  @BASEBOARD_FAB2_LIB.BASEBOARD_FAB2(SCH_1):SMB_DDR_DEF_VPP_SCL
  284  PVPP_DEF       VDDSPD  @BASEBOARD_FAB2_LIB.BASEBOARD_FAB2(SCH_1):PVPP_DEF
  139  PVPP_DEF       SA<0>  @BASEBOARD_FAB2_LIB.BASEBOARD_FAB2(SCH_1):PVPP_DEF
  146  M_D_VREF       VREFCA  @BASEBOARD_FAB2_LIB.BASEBOARD_FAB2(SCH_1):M_D_VREF
  222  M_D_PAR          PAR  @BASEBOARD_FAB2_LIB.BASEBOARD_FAB2(SCH_1):M_D_PAR
   91  M_D_ODT<3>     ODT<1>  @BASEBOARD_FAB2_LIB.BASEBOARD_FAB2(SCH_1):M_D_ODT<3>
   87  M_D_ODT<2>     ODT<0>  @BASEBOARD_FAB2_LIB.BASEBOARD_FAB2(SCH_1):M_D_ODT<2>
   66  M_D_MA<9>         A9  @BASEBOARD_FAB2_LIB.BASEBOARD_FAB2(SCH_1):M_D_MA<9>
   68  M_D_MA<8>         A8  @BASEBOARD_FAB2_LIB.BASEBOARD_FAB2(SCH_1):M_D_MA<8>
  211  M_D_MA<7>         A7  @BASEBOARD_FAB2_LIB.BASEBOARD_FAB2(SCH_1):M_D_MA<7>
   69  M_D_MA<6>         A6  @BASEBOARD_FAB2_LIB.BASEBOARD_FAB2(SCH_1):M_D_MA<6>
  213  M_D_MA<5>         A5  @BASEBOARD_FAB2_LIB.BASEBOARD_FAB2(SCH_1):M_D_MA<5>
  214  M_D_MA<4>         A4  @BASEBOARD_FAB2_LIB.BASEBOARD_FAB2(SCH_1):M_D_MA<4>
   71  M_D_MA<3>         A3  @BASEBOARD_FAB2_LIB.BASEBOARD_FAB2(SCH_1):M_D_MA<3>
  216  M_D_MA<2>         A2  @BASEBOARD_FAB2_LIB.BASEBOARD_FAB2(SCH_1):M_D_MA<2>
   72  M_D_MA<1>         A1  @BASEBOARD_FAB2_LIB.BASEBOARD_FAB2(SCH_1):M_D_MA<1>
  234  M_D_MA<17>       A17  @BASEBOARD_FAB2_LIB.BASEBOARD_FAB2(SCH_1):M_D_MA<17>
   82  M_D_MA<16>     A16_RAS_N  @BASEBOARD_FAB2_LIB.BASEBOARD_FAB2(SCH_1):M_D_MA<16>
   86  M_D_MA<15>     A15_CAS_N  @BASEBOARD_FAB2_LIB.BASEBOARD_FAB2(SCH_1):M_D_MA<15>
  228  M_D_MA<14>     A14_WE_N  @BASEBOARD_FAB2_LIB.BASEBOARD_FAB2(SCH_1):M_D_MA<14>
  232  M_D_MA<13>       A13  @BASEBOARD_FAB2_LIB.BASEBOARD_FAB2(SCH_1):M_D_MA<13>
   65  M_D_MA<12>       A12  @BASEBOARD_FAB2_LIB.BASEBOARD_FAB2(SCH_1):M_D_MA<12>
  210  M_D_MA<11>       A11  @BASEBOARD_FAB2_LIB.BASEBOARD_FAB2(SCH_1):M_D_MA<11>
  225  M_D_MA<10>       A10  @BASEBOARD_FAB2_LIB.BASEBOARD_FAB2(SCH_1):M_D_MA<10>
   79  M_D_MA<0>         A0  @BASEBOARD_FAB2_LIB.BASEBOARD_FAB2(SCH_1):M_D_MA<0>
  199  M_D_ECC<7>     CB<7>  @BASEBOARD_FAB2_LIB.BASEBOARD_FAB2(SCH_1):M_D_ECC<7>
   54  M_D_ECC<6>     CB<6>  @BASEBOARD_FAB2_LIB.BASEBOARD_FAB2(SCH_1):M_D_ECC<6>
  192  M_D_ECC<5>     CB<5>  @BASEBOARD_FAB2_LIB.BASEBOARD_FAB2(SCH_1):M_D_ECC<5>
   47  M_D_ECC<4>     CB<4>  @BASEBOARD_FAB2_LIB.BASEBOARD_FAB2(SCH_1):M_D_ECC<4>
  201  M_D_ECC<3>     CB<3>  @BASEBOARD_FAB2_LIB.BASEBOARD_FAB2(SCH_1):M_D_ECC<3>
   56  M_D_ECC<2>     CB<2>  @BASEBOARD_FAB2_LIB.BASEBOARD_FAB2(SCH_1):M_D_ECC<2>
  194  M_D_ECC<1>     CB<1>  @BASEBOARD_FAB2_LIB.BASEBOARD_FAB2(SCH_1):M_D_ECC<1>
   49  M_D_ECC<0>     CB<0>  @BASEBOARD_FAB2_LIB.BASEBOARD_FAB2(SCH_1):M_D_ECC<0>
  161  M_D_DQ<9>      DQ<9>  @BASEBOARD_FAB2_LIB.BASEBOARD_FAB2(SCH_1):M_D_DQ<9>
   16  M_D_DQ<8>      DQ<8>  @BASEBOARD_FAB2_LIB.BASEBOARD_FAB2(SCH_1):M_D_DQ<8>
  155  M_D_DQ<7>      DQ<7>  @BASEBOARD_FAB2_LIB.BASEBOARD_FAB2(SCH_1):M_D_DQ<7>
   10  M_D_DQ<6>      DQ<6>  @BASEBOARD_FAB2_LIB.BASEBOARD_FAB2(SCH_1):M_D_DQ<6>
  280  M_D_DQ<63>     DQ<63>  @BASEBOARD_FAB2_LIB.BASEBOARD_FAB2(SCH_1):M_D_DQ<63>
  135  M_D_DQ<62>     DQ<62>  @BASEBOARD_FAB2_LIB.BASEBOARD_FAB2(SCH_1):M_D_DQ<62>
  273  M_D_DQ<61>     DQ<61>  @BASEBOARD_FAB2_LIB.BASEBOARD_FAB2(SCH_1):M_D_DQ<61>
  128  M_D_DQ<60>     DQ<60>  @BASEBOARD_FAB2_LIB.BASEBOARD_FAB2(SCH_1):M_D_DQ<60>
  148  M_D_DQ<5>      DQ<5>  @BASEBOARD_FAB2_LIB.BASEBOARD_FAB2(SCH_1):M_D_DQ<5>
  282  M_D_DQ<59>     DQ<59>  @BASEBOARD_FAB2_LIB.BASEBOARD_FAB2(SCH_1):M_D_DQ<59>
  137  M_D_DQ<58>     DQ<58>  @BASEBOARD_FAB2_LIB.BASEBOARD_FAB2(SCH_1):M_D_DQ<58>
  275  M_D_DQ<57>     DQ<57>  @BASEBOARD_FAB2_LIB.BASEBOARD_FAB2(SCH_1):M_D_DQ<57>
  130  M_D_DQ<56>     DQ<56>  @BASEBOARD_FAB2_LIB.BASEBOARD_FAB2(SCH_1):M_D_DQ<56>
  269  M_D_DQ<55>     DQ<55>  @BASEBOARD_FAB2_LIB.BASEBOARD_FAB2(SCH_1):M_D_DQ<55>
  124  M_D_DQ<54>     DQ<54>  @BASEBOARD_FAB2_LIB.BASEBOARD_FAB2(SCH_1):M_D_DQ<54>
  262  M_D_DQ<53>     DQ<53>  @BASEBOARD_FAB2_LIB.BASEBOARD_FAB2(SCH_1):M_D_DQ<53>
  117  M_D_DQ<52>     DQ<52>  @BASEBOARD_FAB2_LIB.BASEBOARD_FAB2(SCH_1):M_D_DQ<52>
  271  M_D_DQ<51>     DQ<51>  @BASEBOARD_FAB2_LIB.BASEBOARD_FAB2(SCH_1):M_D_DQ<51>
  126  M_D_DQ<50>     DQ<50>  @BASEBOARD_FAB2_LIB.BASEBOARD_FAB2(SCH_1):M_D_DQ<50>
    3  M_D_DQ<4>      DQ<4>  @BASEBOARD_FAB2_LIB.BASEBOARD_FAB2(SCH_1):M_D_DQ<4>
  264  M_D_DQ<49>     DQ<49>  @BASEBOARD_FAB2_LIB.BASEBOARD_FAB2(SCH_1):M_D_DQ<49>
  119  M_D_DQ<48>     DQ<48>  @BASEBOARD_FAB2_LIB.BASEBOARD_FAB2(SCH_1):M_D_DQ<48>
  258  M_D_DQ<47>     DQ<47>  @BASEBOARD_FAB2_LIB.BASEBOARD_FAB2(SCH_1):M_D_DQ<47>
  113  M_D_DQ<46>     DQ<46>  @BASEBOARD_FAB2_LIB.BASEBOARD_FAB2(SCH_1):M_D_DQ<46>
  251  M_D_DQ<45>     DQ<45>  @BASEBOARD_FAB2_LIB.BASEBOARD_FAB2(SCH_1):M_D_DQ<45>
  106  M_D_DQ<44>     DQ<44>  @BASEBOARD_FAB2_LIB.BASEBOARD_FAB2(SCH_1):M_D_DQ<44>
  260  M_D_DQ<43>     DQ<43>  @BASEBOARD_FAB2_LIB.BASEBOARD_FAB2(SCH_1):M_D_DQ<43>
  115  M_D_DQ<42>     DQ<42>  @BASEBOARD_FAB2_LIB.BASEBOARD_FAB2(SCH_1):M_D_DQ<42>
  253  M_D_DQ<41>     DQ<41>  @BASEBOARD_FAB2_LIB.BASEBOARD_FAB2(SCH_1):M_D_DQ<41>
  108  M_D_DQ<40>     DQ<40>  @BASEBOARD_FAB2_LIB.BASEBOARD_FAB2(SCH_1):M_D_DQ<40>
  157  M_D_DQ<3>      DQ<3>  @BASEBOARD_FAB2_LIB.BASEBOARD_FAB2(SCH_1):M_D_DQ<3>
  247  M_D_DQ<39>     DQ<39>  @BASEBOARD_FAB2_LIB.BASEBOARD_FAB2(SCH_1):M_D_DQ<39>
  102  M_D_DQ<38>     DQ<38>  @BASEBOARD_FAB2_LIB.BASEBOARD_FAB2(SCH_1):M_D_DQ<38>
  240  M_D_DQ<37>     DQ<37>  @BASEBOARD_FAB2_LIB.BASEBOARD_FAB2(SCH_1):M_D_DQ<37>
   95  M_D_DQ<36>     DQ<36>  @BASEBOARD_FAB2_LIB.BASEBOARD_FAB2(SCH_1):M_D_DQ<36>
  249  M_D_DQ<35>     DQ<35>  @BASEBOARD_FAB2_LIB.BASEBOARD_FAB2(SCH_1):M_D_DQ<35>
  104  M_D_DQ<34>     DQ<34>  @BASEBOARD_FAB2_LIB.BASEBOARD_FAB2(SCH_1):M_D_DQ<34>
  242  M_D_DQ<33>     DQ<33>  @BASEBOARD_FAB2_LIB.BASEBOARD_FAB2(SCH_1):M_D_DQ<33>
   97  M_D_DQ<32>     DQ<32>  @BASEBOARD_FAB2_LIB.BASEBOARD_FAB2(SCH_1):M_D_DQ<32>
  188  M_D_DQ<31>     DQ<31>  @BASEBOARD_FAB2_LIB.BASEBOARD_FAB2(SCH_1):M_D_DQ<31>
   43  M_D_DQ<30>     DQ<30>  @BASEBOARD_FAB2_LIB.BASEBOARD_FAB2(SCH_1):M_D_DQ<30>
   12  M_D_DQ<2>      DQ<2>  @BASEBOARD_FAB2_LIB.BASEBOARD_FAB2(SCH_1):M_D_DQ<2>
  181  M_D_DQ<29>     DQ<29>  @BASEBOARD_FAB2_LIB.BASEBOARD_FAB2(SCH_1):M_D_DQ<29>
   36  M_D_DQ<28>     DQ<28>  @BASEBOARD_FAB2_LIB.BASEBOARD_FAB2(SCH_1):M_D_DQ<28>
  190  M_D_DQ<27>     DQ<27>  @BASEBOARD_FAB2_LIB.BASEBOARD_FAB2(SCH_1):M_D_DQ<27>
   45  M_D_DQ<26>     DQ<26>  @BASEBOARD_FAB2_LIB.BASEBOARD_FAB2(SCH_1):M_D_DQ<26>
  183  M_D_DQ<25>     DQ<25>  @BASEBOARD_FAB2_LIB.BASEBOARD_FAB2(SCH_1):M_D_DQ<25>
   38  M_D_DQ<24>     DQ<24>  @BASEBOARD_FAB2_LIB.BASEBOARD_FAB2(SCH_1):M_D_DQ<24>
  177  M_D_DQ<23>     DQ<23>  @BASEBOARD_FAB2_LIB.BASEBOARD_FAB2(SCH_1):M_D_DQ<23>
   32  M_D_DQ<22>     DQ<22>  @BASEBOARD_FAB2_LIB.BASEBOARD_FAB2(SCH_1):M_D_DQ<22>
  170  M_D_DQ<21>     DQ<21>  @BASEBOARD_FAB2_LIB.BASEBOARD_FAB2(SCH_1):M_D_DQ<21>
   25  M_D_DQ<20>     DQ<20>  @BASEBOARD_FAB2_LIB.BASEBOARD_FAB2(SCH_1):M_D_DQ<20>
  150  M_D_DQ<1>      DQ<1>  @BASEBOARD_FAB2_LIB.BASEBOARD_FAB2(SCH_1):M_D_DQ<1>
  179  M_D_DQ<19>     DQ<19>  @BASEBOARD_FAB2_LIB.BASEBOARD_FAB2(SCH_1):M_D_DQ<19>
   34  M_D_DQ<18>     DQ<18>  @BASEBOARD_FAB2_LIB.BASEBOARD_FAB2(SCH_1):M_D_DQ<18>
  172  M_D_DQ<17>     DQ<17>  @BASEBOARD_FAB2_LIB.BASEBOARD_FAB2(SCH_1):M_D_DQ<17>
   27  M_D_DQ<16>     DQ<16>  @BASEBOARD_FAB2_LIB.BASEBOARD_FAB2(SCH_1):M_D_DQ<16>
  166  M_D_DQ<15>     DQ<15>  @BASEBOARD_FAB2_LIB.BASEBOARD_FAB2(SCH_1):M_D_DQ<15>
   21  M_D_DQ<14>     DQ<14>  @BASEBOARD_FAB2_LIB.BASEBOARD_FAB2(SCH_1):M_D_DQ<14>
  159  M_D_DQ<13>     DQ<13>  @BASEBOARD_FAB2_LIB.BASEBOARD_FAB2(SCH_1):M_D_DQ<13>
   14  M_D_DQ<12>     DQ<12>  @BASEBOARD_FAB2_LIB.BASEBOARD_FAB2(SCH_1):M_D_DQ<12>
  168  M_D_DQ<11>     DQ<11>  @BASEBOARD_FAB2_LIB.BASEBOARD_FAB2(SCH_1):M_D_DQ<11>
   23  M_D_DQ<10>     DQ<10>  @BASEBOARD_FAB2_LIB.BASEBOARD_FAB2(SCH_1):M_D_DQ<10>
    5  M_D_DQ<0>      DQ<0>  @BASEBOARD_FAB2_LIB.BASEBOARD_FAB2(SCH_1):M_D_DQ<0>
  237  M_D_CS_N<7>    S3_N_C<1>  @BASEBOARD_FAB2_LIB.BASEBOARD_FAB2(SCH_1):M_D_CS_N<7>
   93  M_D_CS_N<6>    S2_N_C<0>  @BASEBOARD_FAB2_LIB.BASEBOARD_FAB2(SCH_1):M_D_CS_N<6>
   89  M_D_CS_N<5>     S1_N  @BASEBOARD_FAB2_LIB.BASEBOARD_FAB2(SCH_1):M_D_CS_N<5>
   84  M_D_CS_N<4>     S0_N  @BASEBOARD_FAB2_LIB.BASEBOARD_FAB2(SCH_1):M_D_CS_N<4>
  218  M_D_CLK_DP<3>   CK1P  @BASEBOARD_FAB2_LIB.BASEBOARD_FAB2(SCH_1):M_D_CLK_DP<3>
   74  M_D_CLK_DP<2>   CK0P  @BASEBOARD_FAB2_LIB.BASEBOARD_FAB2(SCH_1):M_D_CLK_DP<2>
  219  M_D_CLK_DN<3>   CK1N  @BASEBOARD_FAB2_LIB.BASEBOARD_FAB2(SCH_1):M_D_CLK_DN<3>
   75  M_D_CLK_DN<2>   CK0N  @BASEBOARD_FAB2_LIB.BASEBOARD_FAB2(SCH_1):M_D_CLK_DN<2>
  203  M_D_CKE<3>     CKE<1>  @BASEBOARD_FAB2_LIB.BASEBOARD_FAB2(SCH_1):M_D_CKE<3>
   60  M_D_CKE<2>     CKE<0>  @BASEBOARD_FAB2_LIB.BASEBOARD_FAB2(SCH_1):M_D_CKE<2>
  235  M_D_C<2>        C<2>  @BASEBOARD_FAB2_LIB.BASEBOARD_FAB2(SCH_1):M_D_C<2>
  207  M_D_BG<1>      BG<1>  @BASEBOARD_FAB2_LIB.BASEBOARD_FAB2(SCH_1):M_D_BG<1>
   63  M_D_BG<0>      BG<0>  @BASEBOARD_FAB2_LIB.BASEBOARD_FAB2(SCH_1):M_D_BG<0>
  224  M_D_BA<1>      BA<1>  @BASEBOARD_FAB2_LIB.BASEBOARD_FAB2(SCH_1):M_D_BA<1>
   81  M_D_BA<0>      BA<0>  @BASEBOARD_FAB2_LIB.BASEBOARD_FAB2(SCH_1):M_D_BA<0>
  208  M_D_ALERT_N    ALERT_N  @BASEBOARD_FAB2_LIB.BASEBOARD_FAB2(SCH_1):M_D_ALERT_N
   62  M_D_ACT_N      ACT_N  @BASEBOARD_FAB2_LIB.BASEBOARD_FAB2(SCH_1):M_D_ACT_N
   58  M_DEF_RST_N    RESET_N  @BASEBOARD_FAB2_LIB.BASEBOARD_FAB2(SCH_1):M_DEF_RST_N
  238  GND            SA<2>  @BASEBOARD_FAB2_LIB.BASEBOARD_FAB2(SCH_1):GND
  140  GND            SA<1>  @BASEBOARD_FAB2_LIB.BASEBOARD_FAB2(SCH_1):GND
   78  FM_DIMM_EVENT_COD_N  EVENT_N  @BASEBOARD_FAB2_LIB.BASEBOARD_FAB2(SCH_1):FM_DIMM_EVENT_COD_N
  230  FM_ADR_COMPLETE_DEF_N  SAVE_N_NC  @BASEBOARD_FAB2_LIB.BASEBOARD_FAB2(SCH_1):FM_ADR_COMPLETE_DEF_N

SCONN288_H44441003_PIP  I75  J6T1   [SCONN288_H44441003_PIP-SCONN,HA]
   77  PVTT_ABC       VTT<1>  @BASEBOARD_FAB2_LIB.BASEBOARD_FAB2(SCH_1):PVTT_ABC
  221  PVTT_ABC       VTT<0>  @BASEBOARD_FAB2_LIB.BASEBOARD_FAB2(SCH_1):PVTT_ABC
  142  PVPP_ABC       VPP<4>  @BASEBOARD_FAB2_LIB.BASEBOARD_FAB2(SCH_1):PVPP_ABC
  143  PVPP_ABC       VPP<3>  @BASEBOARD_FAB2_LIB.BASEBOARD_FAB2(SCH_1):PVPP_ABC
  288  PVPP_ABC       VPP<2>  @BASEBOARD_FAB2_LIB.BASEBOARD_FAB2(SCH_1):PVPP_ABC
  286  PVPP_ABC       VPP<1>  @BASEBOARD_FAB2_LIB.BASEBOARD_FAB2(SCH_1):PVPP_ABC
  287  PVPP_ABC       VPP<0>  @BASEBOARD_FAB2_LIB.BASEBOARD_FAB2(SCH_1):PVPP_ABC
   59  PVDDQ_ABC      VDD<25>  @BASEBOARD_FAB2_LIB.BASEBOARD_FAB2(SCH_1):PVDDQ_ABC
   61  PVDDQ_ABC      VDD<24>  @BASEBOARD_FAB2_LIB.BASEBOARD_FAB2(SCH_1):PVDDQ_ABC
   64  PVDDQ_ABC      VDD<23>  @BASEBOARD_FAB2_LIB.BASEBOARD_FAB2(SCH_1):PVDDQ_ABC
   67  PVDDQ_ABC      VDD<22>  @BASEBOARD_FAB2_LIB.BASEBOARD_FAB2(SCH_1):PVDDQ_ABC
   70  PVDDQ_ABC      VDD<21>  @BASEBOARD_FAB2_LIB.BASEBOARD_FAB2(SCH_1):PVDDQ_ABC
   73  PVDDQ_ABC      VDD<20>  @BASEBOARD_FAB2_LIB.BASEBOARD_FAB2(SCH_1):PVDDQ_ABC
   76  PVDDQ_ABC      VDD<19>  @BASEBOARD_FAB2_LIB.BASEBOARD_FAB2(SCH_1):PVDDQ_ABC
   80  PVDDQ_ABC      VDD<18>  @BASEBOARD_FAB2_LIB.BASEBOARD_FAB2(SCH_1):PVDDQ_ABC
   83  PVDDQ_ABC      VDD<17>  @BASEBOARD_FAB2_LIB.BASEBOARD_FAB2(SCH_1):PVDDQ_ABC
   85  PVDDQ_ABC      VDD<16>  @BASEBOARD_FAB2_LIB.BASEBOARD_FAB2(SCH_1):PVDDQ_ABC
   88  PVDDQ_ABC      VDD<15>  @BASEBOARD_FAB2_LIB.BASEBOARD_FAB2(SCH_1):PVDDQ_ABC
   90  PVDDQ_ABC      VDD<14>  @BASEBOARD_FAB2_LIB.BASEBOARD_FAB2(SCH_1):PVDDQ_ABC
   92  PVDDQ_ABC      VDD<13>  @BASEBOARD_FAB2_LIB.BASEBOARD_FAB2(SCH_1):PVDDQ_ABC
  204  PVDDQ_ABC      VDD<12>  @BASEBOARD_FAB2_LIB.BASEBOARD_FAB2(SCH_1):PVDDQ_ABC
  206  PVDDQ_ABC      VDD<11>  @BASEBOARD_FAB2_LIB.BASEBOARD_FAB2(SCH_1):PVDDQ_ABC
  209  PVDDQ_ABC      VDD<10>  @BASEBOARD_FAB2_LIB.BASEBOARD_FAB2(SCH_1):PVDDQ_ABC
  212  PVDDQ_ABC      VDD<9>  @BASEBOARD_FAB2_LIB.BASEBOARD_FAB2(SCH_1):PVDDQ_ABC
  215  PVDDQ_ABC      VDD<8>  @BASEBOARD_FAB2_LIB.BASEBOARD_FAB2(SCH_1):PVDDQ_ABC
  217  PVDDQ_ABC      VDD<7>  @BASEBOARD_FAB2_LIB.BASEBOARD_FAB2(SCH_1):PVDDQ_ABC
  220  PVDDQ_ABC      VDD<6>  @BASEBOARD_FAB2_LIB.BASEBOARD_FAB2(SCH_1):PVDDQ_ABC
  223  PVDDQ_ABC      VDD<5>  @BASEBOARD_FAB2_LIB.BASEBOARD_FAB2(SCH_1):PVDDQ_ABC
  226  PVDDQ_ABC      VDD<4>  @BASEBOARD_FAB2_LIB.BASEBOARD_FAB2(SCH_1):PVDDQ_ABC
  229  PVDDQ_ABC      VDD<3>  @BASEBOARD_FAB2_LIB.BASEBOARD_FAB2(SCH_1):PVDDQ_ABC
  231  PVDDQ_ABC      VDD<2>  @BASEBOARD_FAB2_LIB.BASEBOARD_FAB2(SCH_1):PVDDQ_ABC
  233  PVDDQ_ABC      VDD<1>  @BASEBOARD_FAB2_LIB.BASEBOARD_FAB2(SCH_1):PVDDQ_ABC
  236  PVDDQ_ABC      VDD<0>  @BASEBOARD_FAB2_LIB.BASEBOARD_FAB2(SCH_1):PVDDQ_ABC
    1  P12V_NVDIMM_ABC  12V<1>  @BASEBOARD_FAB2_LIB.BASEBOARD_FAB2(SCH_1):P12V_NVDIMM_ABC
  145  P12V_NVDIMM_ABC  12V<0>  @BASEBOARD_FAB2_LIB.BASEBOARD_FAB2(SCH_1):P12V_NVDIMM_ABC

SCONN288_H44441003_PIP  I139  J6T1   [SCONN288_H44441003_PIP-SCONN,HA]
    2  GND            VSS<93>  @BASEBOARD_FAB2_LIB.BASEBOARD_FAB2(SCH_1):GND
    4  GND            VSS<92>  @BASEBOARD_FAB2_LIB.BASEBOARD_FAB2(SCH_1):GND
    6  GND            VSS<91>  @BASEBOARD_FAB2_LIB.BASEBOARD_FAB2(SCH_1):GND
    9  GND            VSS<90>  @BASEBOARD_FAB2_LIB.BASEBOARD_FAB2(SCH_1):GND
   11  GND            VSS<89>  @BASEBOARD_FAB2_LIB.BASEBOARD_FAB2(SCH_1):GND
   13  GND            VSS<88>  @BASEBOARD_FAB2_LIB.BASEBOARD_FAB2(SCH_1):GND
   15  GND            VSS<87>  @BASEBOARD_FAB2_LIB.BASEBOARD_FAB2(SCH_1):GND
   17  GND            VSS<86>  @BASEBOARD_FAB2_LIB.BASEBOARD_FAB2(SCH_1):GND
   20  GND            VSS<85>  @BASEBOARD_FAB2_LIB.BASEBOARD_FAB2(SCH_1):GND
   22  GND            VSS<84>  @BASEBOARD_FAB2_LIB.BASEBOARD_FAB2(SCH_1):GND
   24  GND            VSS<83>  @BASEBOARD_FAB2_LIB.BASEBOARD_FAB2(SCH_1):GND
   26  GND            VSS<82>  @BASEBOARD_FAB2_LIB.BASEBOARD_FAB2(SCH_1):GND
   28  GND            VSS<81>  @BASEBOARD_FAB2_LIB.BASEBOARD_FAB2(SCH_1):GND
   31  GND            VSS<80>  @BASEBOARD_FAB2_LIB.BASEBOARD_FAB2(SCH_1):GND
   33  GND            VSS<79>  @BASEBOARD_FAB2_LIB.BASEBOARD_FAB2(SCH_1):GND
   35  GND            VSS<78>  @BASEBOARD_FAB2_LIB.BASEBOARD_FAB2(SCH_1):GND
   37  GND            VSS<77>  @BASEBOARD_FAB2_LIB.BASEBOARD_FAB2(SCH_1):GND
   39  GND            VSS<76>  @BASEBOARD_FAB2_LIB.BASEBOARD_FAB2(SCH_1):GND
   42  GND            VSS<75>  @BASEBOARD_FAB2_LIB.BASEBOARD_FAB2(SCH_1):GND
   44  GND            VSS<74>  @BASEBOARD_FAB2_LIB.BASEBOARD_FAB2(SCH_1):GND
   46  GND            VSS<73>  @BASEBOARD_FAB2_LIB.BASEBOARD_FAB2(SCH_1):GND
   48  GND            VSS<72>  @BASEBOARD_FAB2_LIB.BASEBOARD_FAB2(SCH_1):GND
   50  GND            VSS<71>  @BASEBOARD_FAB2_LIB.BASEBOARD_FAB2(SCH_1):GND
   53  GND            VSS<70>  @BASEBOARD_FAB2_LIB.BASEBOARD_FAB2(SCH_1):GND
   55  GND            VSS<69>  @BASEBOARD_FAB2_LIB.BASEBOARD_FAB2(SCH_1):GND
   57  GND            VSS<68>  @BASEBOARD_FAB2_LIB.BASEBOARD_FAB2(SCH_1):GND
   94  GND            VSS<67>  @BASEBOARD_FAB2_LIB.BASEBOARD_FAB2(SCH_1):GND
   96  GND            VSS<66>  @BASEBOARD_FAB2_LIB.BASEBOARD_FAB2(SCH_1):GND
   98  GND            VSS<65>  @BASEBOARD_FAB2_LIB.BASEBOARD_FAB2(SCH_1):GND
  101  GND            VSS<64>  @BASEBOARD_FAB2_LIB.BASEBOARD_FAB2(SCH_1):GND
  103  GND            VSS<63>  @BASEBOARD_FAB2_LIB.BASEBOARD_FAB2(SCH_1):GND
  105  GND            VSS<62>  @BASEBOARD_FAB2_LIB.BASEBOARD_FAB2(SCH_1):GND
  107  GND            VSS<61>  @BASEBOARD_FAB2_LIB.BASEBOARD_FAB2(SCH_1):GND
  109  GND            VSS<60>  @BASEBOARD_FAB2_LIB.BASEBOARD_FAB2(SCH_1):GND
  112  GND            VSS<59>  @BASEBOARD_FAB2_LIB.BASEBOARD_FAB2(SCH_1):GND
  114  GND            VSS<58>  @BASEBOARD_FAB2_LIB.BASEBOARD_FAB2(SCH_1):GND
  116  GND            VSS<57>  @BASEBOARD_FAB2_LIB.BASEBOARD_FAB2(SCH_1):GND
  118  GND            VSS<56>  @BASEBOARD_FAB2_LIB.BASEBOARD_FAB2(SCH_1):GND
  120  GND            VSS<55>  @BASEBOARD_FAB2_LIB.BASEBOARD_FAB2(SCH_1):GND
  123  GND            VSS<54>  @BASEBOARD_FAB2_LIB.BASEBOARD_FAB2(SCH_1):GND
  125  GND            VSS<53>  @BASEBOARD_FAB2_LIB.BASEBOARD_FAB2(SCH_1):GND
  127  GND            VSS<52>  @BASEBOARD_FAB2_LIB.BASEBOARD_FAB2(SCH_1):GND
  129  GND            VSS<51>  @BASEBOARD_FAB2_LIB.BASEBOARD_FAB2(SCH_1):GND
  131  GND            VSS<50>  @BASEBOARD_FAB2_LIB.BASEBOARD_FAB2(SCH_1):GND
  134  GND            VSS<49>  @BASEBOARD_FAB2_LIB.BASEBOARD_FAB2(SCH_1):GND
  136  GND            VSS<48>  @BASEBOARD_FAB2_LIB.BASEBOARD_FAB2(SCH_1):GND
  138  GND            VSS<47>  @BASEBOARD_FAB2_LIB.BASEBOARD_FAB2(SCH_1):GND
  147  GND            VSS<46>  @BASEBOARD_FAB2_LIB.BASEBOARD_FAB2(SCH_1):GND
  149  GND            VSS<45>  @BASEBOARD_FAB2_LIB.BASEBOARD_FAB2(SCH_1):GND
  151  GND            VSS<44>  @BASEBOARD_FAB2_LIB.BASEBOARD_FAB2(SCH_1):GND
  154  GND            VSS<43>  @BASEBOARD_FAB2_LIB.BASEBOARD_FAB2(SCH_1):GND
  156  GND            VSS<42>  @BASEBOARD_FAB2_LIB.BASEBOARD_FAB2(SCH_1):GND
  158  GND            VSS<41>  @BASEBOARD_FAB2_LIB.BASEBOARD_FAB2(SCH_1):GND
  160  GND            VSS<40>  @BASEBOARD_FAB2_LIB.BASEBOARD_FAB2(SCH_1):GND
  162  GND            VSS<39>  @BASEBOARD_FAB2_LIB.BASEBOARD_FAB2(SCH_1):GND
  165  GND            VSS<38>  @BASEBOARD_FAB2_LIB.BASEBOARD_FAB2(SCH_1):GND
  167  GND            VSS<37>  @BASEBOARD_FAB2_LIB.BASEBOARD_FAB2(SCH_1):GND
  169  GND            VSS<36>  @BASEBOARD_FAB2_LIB.BASEBOARD_FAB2(SCH_1):GND
  171  GND            VSS<35>  @BASEBOARD_FAB2_LIB.BASEBOARD_FAB2(SCH_1):GND
  173  GND            VSS<34>  @BASEBOARD_FAB2_LIB.BASEBOARD_FAB2(SCH_1):GND
  176  GND            VSS<33>  @BASEBOARD_FAB2_LIB.BASEBOARD_FAB2(SCH_1):GND
  178  GND            VSS<32>  @BASEBOARD_FAB2_LIB.BASEBOARD_FAB2(SCH_1):GND
  180  GND            VSS<31>  @BASEBOARD_FAB2_LIB.BASEBOARD_FAB2(SCH_1):GND
  182  GND            VSS<30>  @BASEBOARD_FAB2_LIB.BASEBOARD_FAB2(SCH_1):GND
  184  GND            VSS<29>  @BASEBOARD_FAB2_LIB.BASEBOARD_FAB2(SCH_1):GND
  187  GND            VSS<28>  @BASEBOARD_FAB2_LIB.BASEBOARD_FAB2(SCH_1):GND
  189  GND            VSS<27>  @BASEBOARD_FAB2_LIB.BASEBOARD_FAB2(SCH_1):GND
  191  GND            VSS<26>  @BASEBOARD_FAB2_LIB.BASEBOARD_FAB2(SCH_1):GND
  193  GND            VSS<25>  @BASEBOARD_FAB2_LIB.BASEBOARD_FAB2(SCH_1):GND
  195  GND            VSS<24>  @BASEBOARD_FAB2_LIB.BASEBOARD_FAB2(SCH_1):GND
  198  GND            VSS<23>  @BASEBOARD_FAB2_LIB.BASEBOARD_FAB2(SCH_1):GND
  200  GND            VSS<22>  @BASEBOARD_FAB2_LIB.BASEBOARD_FAB2(SCH_1):GND
  202  GND            VSS<21>  @BASEBOARD_FAB2_LIB.BASEBOARD_FAB2(SCH_1):GND
  239  GND            VSS<20>  @BASEBOARD_FAB2_LIB.BASEBOARD_FAB2(SCH_1):GND
  241  GND            VSS<19>  @BASEBOARD_FAB2_LIB.BASEBOARD_FAB2(SCH_1):GND
  243  GND            VSS<18>  @BASEBOARD_FAB2_LIB.BASEBOARD_FAB2(SCH_1):GND
  246  GND            VSS<17>  @BASEBOARD_FAB2_LIB.BASEBOARD_FAB2(SCH_1):GND
  248  GND            VSS<16>  @BASEBOARD_FAB2_LIB.BASEBOARD_FAB2(SCH_1):GND
  250  GND            VSS<15>  @BASEBOARD_FAB2_LIB.BASEBOARD_FAB2(SCH_1):GND
  252  GND            VSS<14>  @BASEBOARD_FAB2_LIB.BASEBOARD_FAB2(SCH_1):GND
  254  GND            VSS<13>  @BASEBOARD_FAB2_LIB.BASEBOARD_FAB2(SCH_1):GND
  257  GND            VSS<12>  @BASEBOARD_FAB2_LIB.BASEBOARD_FAB2(SCH_1):GND
  259  GND            VSS<11>  @BASEBOARD_FAB2_LIB.BASEBOARD_FAB2(SCH_1):GND
  261  GND            VSS<10>  @BASEBOARD_FAB2_LIB.BASEBOARD_FAB2(SCH_1):GND
  263  GND            VSS<9>  @BASEBOARD_FAB2_LIB.BASEBOARD_FAB2(SCH_1):GND
  265  GND            VSS<8>  @BASEBOARD_FAB2_LIB.BASEBOARD_FAB2(SCH_1):GND
  268  GND            VSS<7>  @BASEBOARD_FAB2_LIB.BASEBOARD_FAB2(SCH_1):GND
  270  GND            VSS<6>  @BASEBOARD_FAB2_LIB.BASEBOARD_FAB2(SCH_1):GND
  272  GND            VSS<5>  @BASEBOARD_FAB2_LIB.BASEBOARD_FAB2(SCH_1):GND
  274  GND            VSS<4>  @BASEBOARD_FAB2_LIB.BASEBOARD_FAB2(SCH_1):GND
  276  GND            VSS<3>  @BASEBOARD_FAB2_LIB.BASEBOARD_FAB2(SCH_1):GND
  279  GND            VSS<2>  @BASEBOARD_FAB2_LIB.BASEBOARD_FAB2(SCH_1):GND
  281  GND            VSS<1>  @BASEBOARD_FAB2_LIB.BASEBOARD_FAB2(SCH_1):GND
  283  GND            VSS<0>  @BASEBOARD_FAB2_LIB.BASEBOARD_FAB2(SCH_1):GND

SCONN288_H44441003_PIP  I120  J6T1   [SCONN288_H44441003_PIP-SCONN,HA]
    7  M_A_DQS_DP<9>  DQS9P  @BASEBOARD_FAB2_LIB.BASEBOARD_FAB2(SCH_1):M_A_DQS_DP<9>
  197  M_A_DQS_DP<8>  DQS8P  @BASEBOARD_FAB2_LIB.BASEBOARD_FAB2(SCH_1):M_A_DQS_DP<8>
  278  M_A_DQS_DP<7>  DQS7P  @BASEBOARD_FAB2_LIB.BASEBOARD_FAB2(SCH_1):M_A_DQS_DP<7>
  267  M_A_DQS_DP<6>  DQS6P  @BASEBOARD_FAB2_LIB.BASEBOARD_FAB2(SCH_1):M_A_DQS_DP<6>
  256  M_A_DQS_DP<5>  DQS5P  @BASEBOARD_FAB2_LIB.BASEBOARD_FAB2(SCH_1):M_A_DQS_DP<5>
  245  M_A_DQS_DP<4>  DQS4P  @BASEBOARD_FAB2_LIB.BASEBOARD_FAB2(SCH_1):M_A_DQS_DP<4>
  186  M_A_DQS_DP<3>  DQS3P  @BASEBOARD_FAB2_LIB.BASEBOARD_FAB2(SCH_1):M_A_DQS_DP<3>
  175  M_A_DQS_DP<2>  DQS2P  @BASEBOARD_FAB2_LIB.BASEBOARD_FAB2(SCH_1):M_A_DQS_DP<2>
  164  M_A_DQS_DP<1>  DQS1P  @BASEBOARD_FAB2_LIB.BASEBOARD_FAB2(SCH_1):M_A_DQS_DP<1>
   51  M_A_DQS_DP<17>  DQS17P  @BASEBOARD_FAB2_LIB.BASEBOARD_FAB2(SCH_1):M_A_DQS_DP<17>
  132  M_A_DQS_DP<16>  DQS16P  @BASEBOARD_FAB2_LIB.BASEBOARD_FAB2(SCH_1):M_A_DQS_DP<16>
  121  M_A_DQS_DP<15>  DQS15P  @BASEBOARD_FAB2_LIB.BASEBOARD_FAB2(SCH_1):M_A_DQS_DP<15>
  110  M_A_DQS_DP<14>  DQS14P  @BASEBOARD_FAB2_LIB.BASEBOARD_FAB2(SCH_1):M_A_DQS_DP<14>
   99  M_A_DQS_DP<13>  DQS13P  @BASEBOARD_FAB2_LIB.BASEBOARD_FAB2(SCH_1):M_A_DQS_DP<13>
   40  M_A_DQS_DP<12>  DQS12P  @BASEBOARD_FAB2_LIB.BASEBOARD_FAB2(SCH_1):M_A_DQS_DP<12>
   29  M_A_DQS_DP<11>  DQS11P  @BASEBOARD_FAB2_LIB.BASEBOARD_FAB2(SCH_1):M_A_DQS_DP<11>
   18  M_A_DQS_DP<10>  DQS10P  @BASEBOARD_FAB2_LIB.BASEBOARD_FAB2(SCH_1):M_A_DQS_DP<10>
  153  M_A_DQS_DP<0>  DQS0P  @BASEBOARD_FAB2_LIB.BASEBOARD_FAB2(SCH_1):M_A_DQS_DP<0>
    8  M_A_DQS_DN<9>  DQS9N  @BASEBOARD_FAB2_LIB.BASEBOARD_FAB2(SCH_1):M_A_DQS_DN<9>
  196  M_A_DQS_DN<8>  DQS8N  @BASEBOARD_FAB2_LIB.BASEBOARD_FAB2(SCH_1):M_A_DQS_DN<8>
  277  M_A_DQS_DN<7>  DQS7N  @BASEBOARD_FAB2_LIB.BASEBOARD_FAB2(SCH_1):M_A_DQS_DN<7>
  266  M_A_DQS_DN<6>  DQS6N  @BASEBOARD_FAB2_LIB.BASEBOARD_FAB2(SCH_1):M_A_DQS_DN<6>
  255  M_A_DQS_DN<5>  DQS5N  @BASEBOARD_FAB2_LIB.BASEBOARD_FAB2(SCH_1):M_A_DQS_DN<5>
  244  M_A_DQS_DN<4>  DQS4N  @BASEBOARD_FAB2_LIB.BASEBOARD_FAB2(SCH_1):M_A_DQS_DN<4>
  185  M_A_DQS_DN<3>  DQS3N  @BASEBOARD_FAB2_LIB.BASEBOARD_FAB2(SCH_1):M_A_DQS_DN<3>
  174  M_A_DQS_DN<2>  DQS2N  @BASEBOARD_FAB2_LIB.BASEBOARD_FAB2(SCH_1):M_A_DQS_DN<2>
  163  M_A_DQS_DN<1>  DQS1N  @BASEBOARD_FAB2_LIB.BASEBOARD_FAB2(SCH_1):M_A_DQS_DN<1>
   52  M_A_DQS_DN<17>  DQS17N  @BASEBOARD_FAB2_LIB.BASEBOARD_FAB2(SCH_1):M_A_DQS_DN<17>
  133  M_A_DQS_DN<16>  DQS16N  @BASEBOARD_FAB2_LIB.BASEBOARD_FAB2(SCH_1):M_A_DQS_DN<16>
  122  M_A_DQS_DN<15>  DQS15N  @BASEBOARD_FAB2_LIB.BASEBOARD_FAB2(SCH_1):M_A_DQS_DN<15>
  111  M_A_DQS_DN<14>  DQS14N  @BASEBOARD_FAB2_LIB.BASEBOARD_FAB2(SCH_1):M_A_DQS_DN<14>
  100  M_A_DQS_DN<13>  DQS13N  @BASEBOARD_FAB2_LIB.BASEBOARD_FAB2(SCH_1):M_A_DQS_DN<13>
   41  M_A_DQS_DN<12>  DQS12N  @BASEBOARD_FAB2_LIB.BASEBOARD_FAB2(SCH_1):M_A_DQS_DN<12>
   30  M_A_DQS_DN<11>  DQS11N  @BASEBOARD_FAB2_LIB.BASEBOARD_FAB2(SCH_1):M_A_DQS_DN<11>
   19  M_A_DQS_DN<10>  DQS10N  @BASEBOARD_FAB2_LIB.BASEBOARD_FAB2(SCH_1):M_A_DQS_DN<10>
  152  M_A_DQS_DN<0>  DQS0N  @BASEBOARD_FAB2_LIB.BASEBOARD_FAB2(SCH_1):M_A_DQS_DN<0>

SCONN288_H44441003_PIP  I13  J6T1   [SCONN288_H44441003_PIP-SCONN,HA]
  144  TP_CH_A_DIMM_A1_RFU_2  RFU<2>  @BASEBOARD_FAB2_LIB.BASEBOARD_FAB2(SCH_1):TP_CH_A_DIMM_A1_RFU_2
  227  TP_CH_A_DIMM_A1_RFU_1  RFU<1>  @BASEBOARD_FAB2_LIB.BASEBOARD_FAB2(SCH_1):TP_CH_A_DIMM_A1_RFU_1
  205  TP_CH_A_DIMM_A1_RFU_0  RFU<0>  @BASEBOARD_FAB2_LIB.BASEBOARD_FAB2(SCH_1):TP_CH_A_DIMM_A1_RFU_0
  285  SMB_DDR_ABC_VPP_SDA    SDA  @BASEBOARD_FAB2_LIB.BASEBOARD_FAB2(SCH_1):SMB_DDR_ABC_VPP_SDA
  141  SMB_DDR_ABC_VPP_SCL    SCL  @BASEBOARD_FAB2_LIB.BASEBOARD_FAB2(SCH_1):SMB_DDR_ABC_VPP_SCL
  284  PVPP_ABC       VDDSPD  @BASEBOARD_FAB2_LIB.BASEBOARD_FAB2(SCH_1):PVPP_ABC
  139  PVPP_ABC       SA<0>  @BASEBOARD_FAB2_LIB.BASEBOARD_FAB2(SCH_1):PVPP_ABC
  146  M_A_VREF       VREFCA  @BASEBOARD_FAB2_LIB.BASEBOARD_FAB2(SCH_1):M_A_VREF
  222  M_A_PAR          PAR  @BASEBOARD_FAB2_LIB.BASEBOARD_FAB2(SCH_1):M_A_PAR
   91  M_A_ODT<3>     ODT<1>  @BASEBOARD_FAB2_LIB.BASEBOARD_FAB2(SCH_1):M_A_ODT<3>
   87  M_A_ODT<2>     ODT<0>  @BASEBOARD_FAB2_LIB.BASEBOARD_FAB2(SCH_1):M_A_ODT<2>
   66  M_A_MA<9>         A9  @BASEBOARD_FAB2_LIB.BASEBOARD_FAB2(SCH_1):M_A_MA<9>
   68  M_A_MA<8>         A8  @BASEBOARD_FAB2_LIB.BASEBOARD_FAB2(SCH_1):M_A_MA<8>
  211  M_A_MA<7>         A7  @BASEBOARD_FAB2_LIB.BASEBOARD_FAB2(SCH_1):M_A_MA<7>
   69  M_A_MA<6>         A6  @BASEBOARD_FAB2_LIB.BASEBOARD_FAB2(SCH_1):M_A_MA<6>
  213  M_A_MA<5>         A5  @BASEBOARD_FAB2_LIB.BASEBOARD_FAB2(SCH_1):M_A_MA<5>
  214  M_A_MA<4>         A4  @BASEBOARD_FAB2_LIB.BASEBOARD_FAB2(SCH_1):M_A_MA<4>
   71  M_A_MA<3>         A3  @BASEBOARD_FAB2_LIB.BASEBOARD_FAB2(SCH_1):M_A_MA<3>
  216  M_A_MA<2>         A2  @BASEBOARD_FAB2_LIB.BASEBOARD_FAB2(SCH_1):M_A_MA<2>
   72  M_A_MA<1>         A1  @BASEBOARD_FAB2_LIB.BASEBOARD_FAB2(SCH_1):M_A_MA<1>
  234  M_A_MA<17>       A17  @BASEBOARD_FAB2_LIB.BASEBOARD_FAB2(SCH_1):M_A_MA<17>
   82  M_A_MA<16>     A16_RAS_N  @BASEBOARD_FAB2_LIB.BASEBOARD_FAB2(SCH_1):M_A_MA<16>
   86  M_A_MA<15>     A15_CAS_N  @BASEBOARD_FAB2_LIB.BASEBOARD_FAB2(SCH_1):M_A_MA<15>
  228  M_A_MA<14>     A14_WE_N  @BASEBOARD_FAB2_LIB.BASEBOARD_FAB2(SCH_1):M_A_MA<14>
  232  M_A_MA<13>       A13  @BASEBOARD_FAB2_LIB.BASEBOARD_FAB2(SCH_1):M_A_MA<13>
   65  M_A_MA<12>       A12  @BASEBOARD_FAB2_LIB.BASEBOARD_FAB2(SCH_1):M_A_MA<12>
  210  M_A_MA<11>       A11  @BASEBOARD_FAB2_LIB.BASEBOARD_FAB2(SCH_1):M_A_MA<11>
  225  M_A_MA<10>       A10  @BASEBOARD_FAB2_LIB.BASEBOARD_FAB2(SCH_1):M_A_MA<10>
   79  M_A_MA<0>         A0  @BASEBOARD_FAB2_LIB.BASEBOARD_FAB2(SCH_1):M_A_MA<0>
  199  M_A_ECC<7>     CB<7>  @BASEBOARD_FAB2_LIB.BASEBOARD_FAB2(SCH_1):M_A_ECC<7>
   54  M_A_ECC<6>     CB<6>  @BASEBOARD_FAB2_LIB.BASEBOARD_FAB2(SCH_1):M_A_ECC<6>
  192  M_A_ECC<5>     CB<5>  @BASEBOARD_FAB2_LIB.BASEBOARD_FAB2(SCH_1):M_A_ECC<5>
   47  M_A_ECC<4>     CB<4>  @BASEBOARD_FAB2_LIB.BASEBOARD_FAB2(SCH_1):M_A_ECC<4>
  201  M_A_ECC<3>     CB<3>  @BASEBOARD_FAB2_LIB.BASEBOARD_FAB2(SCH_1):M_A_ECC<3>
   56  M_A_ECC<2>     CB<2>  @BASEBOARD_FAB2_LIB.BASEBOARD_FAB2(SCH_1):M_A_ECC<2>
  194  M_A_ECC<1>     CB<1>  @BASEBOARD_FAB2_LIB.BASEBOARD_FAB2(SCH_1):M_A_ECC<1>
   49  M_A_ECC<0>     CB<0>  @BASEBOARD_FAB2_LIB.BASEBOARD_FAB2(SCH_1):M_A_ECC<0>
  161  M_A_DQ<9>      DQ<9>  @BASEBOARD_FAB2_LIB.BASEBOARD_FAB2(SCH_1):M_A_DQ<9>
   16  M_A_DQ<8>      DQ<8>  @BASEBOARD_FAB2_LIB.BASEBOARD_FAB2(SCH_1):M_A_DQ<8>
  155  M_A_DQ<7>      DQ<7>  @BASEBOARD_FAB2_LIB.BASEBOARD_FAB2(SCH_1):M_A_DQ<7>
   10  M_A_DQ<6>      DQ<6>  @BASEBOARD_FAB2_LIB.BASEBOARD_FAB2(SCH_1):M_A_DQ<6>
  280  M_A_DQ<63>     DQ<63>  @BASEBOARD_FAB2_LIB.BASEBOARD_FAB2(SCH_1):M_A_DQ<63>
  135  M_A_DQ<62>     DQ<62>  @BASEBOARD_FAB2_LIB.BASEBOARD_FAB2(SCH_1):M_A_DQ<62>
  273  M_A_DQ<61>     DQ<61>  @BASEBOARD_FAB2_LIB.BASEBOARD_FAB2(SCH_1):M_A_DQ<61>
  128  M_A_DQ<60>     DQ<60>  @BASEBOARD_FAB2_LIB.BASEBOARD_FAB2(SCH_1):M_A_DQ<60>
  148  M_A_DQ<5>      DQ<5>  @BASEBOARD_FAB2_LIB.BASEBOARD_FAB2(SCH_1):M_A_DQ<5>
  282  M_A_DQ<59>     DQ<59>  @BASEBOARD_FAB2_LIB.BASEBOARD_FAB2(SCH_1):M_A_DQ<59>
  137  M_A_DQ<58>     DQ<58>  @BASEBOARD_FAB2_LIB.BASEBOARD_FAB2(SCH_1):M_A_DQ<58>
  275  M_A_DQ<57>     DQ<57>  @BASEBOARD_FAB2_LIB.BASEBOARD_FAB2(SCH_1):M_A_DQ<57>
  130  M_A_DQ<56>     DQ<56>  @BASEBOARD_FAB2_LIB.BASEBOARD_FAB2(SCH_1):M_A_DQ<56>
  269  M_A_DQ<55>     DQ<55>  @BASEBOARD_FAB2_LIB.BASEBOARD_FAB2(SCH_1):M_A_DQ<55>
  124  M_A_DQ<54>     DQ<54>  @BASEBOARD_FAB2_LIB.BASEBOARD_FAB2(SCH_1):M_A_DQ<54>
  262  M_A_DQ<53>     DQ<53>  @BASEBOARD_FAB2_LIB.BASEBOARD_FAB2(SCH_1):M_A_DQ<53>
  117  M_A_DQ<52>     DQ<52>  @BASEBOARD_FAB2_LIB.BASEBOARD_FAB2(SCH_1):M_A_DQ<52>
  271  M_A_DQ<51>     DQ<51>  @BASEBOARD_FAB2_LIB.BASEBOARD_FAB2(SCH_1):M_A_DQ<51>
  126  M_A_DQ<50>     DQ<50>  @BASEBOARD_FAB2_LIB.BASEBOARD_FAB2(SCH_1):M_A_DQ<50>
    3  M_A_DQ<4>      DQ<4>  @BASEBOARD_FAB2_LIB.BASEBOARD_FAB2(SCH_1):M_A_DQ<4>
  264  M_A_DQ<49>     DQ<49>  @BASEBOARD_FAB2_LIB.BASEBOARD_FAB2(SCH_1):M_A_DQ<49>
  119  M_A_DQ<48>     DQ<48>  @BASEBOARD_FAB2_LIB.BASEBOARD_FAB2(SCH_1):M_A_DQ<48>
  258  M_A_DQ<47>     DQ<47>  @BASEBOARD_FAB2_LIB.BASEBOARD_FAB2(SCH_1):M_A_DQ<47>
  113  M_A_DQ<46>     DQ<46>  @BASEBOARD_FAB2_LIB.BASEBOARD_FAB2(SCH_1):M_A_DQ<46>
  251  M_A_DQ<45>     DQ<45>  @BASEBOARD_FAB2_LIB.BASEBOARD_FAB2(SCH_1):M_A_DQ<45>
  106  M_A_DQ<44>     DQ<44>  @BASEBOARD_FAB2_LIB.BASEBOARD_FAB2(SCH_1):M_A_DQ<44>
  260  M_A_DQ<43>     DQ<43>  @BASEBOARD_FAB2_LIB.BASEBOARD_FAB2(SCH_1):M_A_DQ<43>
  115  M_A_DQ<42>     DQ<42>  @BASEBOARD_FAB2_LIB.BASEBOARD_FAB2(SCH_1):M_A_DQ<42>
  253  M_A_DQ<41>     DQ<41>  @BASEBOARD_FAB2_LIB.BASEBOARD_FAB2(SCH_1):M_A_DQ<41>
  108  M_A_DQ<40>     DQ<40>  @BASEBOARD_FAB2_LIB.BASEBOARD_FAB2(SCH_1):M_A_DQ<40>
  157  M_A_DQ<3>      DQ<3>  @BASEBOARD_FAB2_LIB.BASEBOARD_FAB2(SCH_1):M_A_DQ<3>
  247  M_A_DQ<39>     DQ<39>  @BASEBOARD_FAB2_LIB.BASEBOARD_FAB2(SCH_1):M_A_DQ<39>
  102  M_A_DQ<38>     DQ<38>  @BASEBOARD_FAB2_LIB.BASEBOARD_FAB2(SCH_1):M_A_DQ<38>
  240  M_A_DQ<37>     DQ<37>  @BASEBOARD_FAB2_LIB.BASEBOARD_FAB2(SCH_1):M_A_DQ<37>
   95  M_A_DQ<36>     DQ<36>  @BASEBOARD_FAB2_LIB.BASEBOARD_FAB2(SCH_1):M_A_DQ<36>
  249  M_A_DQ<35>     DQ<35>  @BASEBOARD_FAB2_LIB.BASEBOARD_FAB2(SCH_1):M_A_DQ<35>
  104  M_A_DQ<34>     DQ<34>  @BASEBOARD_FAB2_LIB.BASEBOARD_FAB2(SCH_1):M_A_DQ<34>
  242  M_A_DQ<33>     DQ<33>  @BASEBOARD_FAB2_LIB.BASEBOARD_FAB2(SCH_1):M_A_DQ<33>
   97  M_A_DQ<32>     DQ<32>  @BASEBOARD_FAB2_LIB.BASEBOARD_FAB2(SCH_1):M_A_DQ<32>
  188  M_A_DQ<31>     DQ<31>  @BASEBOARD_FAB2_LIB.BASEBOARD_FAB2(SCH_1):M_A_DQ<31>
   43  M_A_DQ<30>     DQ<30>  @BASEBOARD_FAB2_LIB.BASEBOARD_FAB2(SCH_1):M_A_DQ<30>
   12  M_A_DQ<2>      DQ<2>  @BASEBOARD_FAB2_LIB.BASEBOARD_FAB2(SCH_1):M_A_DQ<2>
  181  M_A_DQ<29>     DQ<29>  @BASEBOARD_FAB2_LIB.BASEBOARD_FAB2(SCH_1):M_A_DQ<29>
   36  M_A_DQ<28>     DQ<28>  @BASEBOARD_FAB2_LIB.BASEBOARD_FAB2(SCH_1):M_A_DQ<28>
  190  M_A_DQ<27>     DQ<27>  @BASEBOARD_FAB2_LIB.BASEBOARD_FAB2(SCH_1):M_A_DQ<27>
   45  M_A_DQ<26>     DQ<26>  @BASEBOARD_FAB2_LIB.BASEBOARD_FAB2(SCH_1):M_A_DQ<26>
  183  M_A_DQ<25>     DQ<25>  @BASEBOARD_FAB2_LIB.BASEBOARD_FAB2(SCH_1):M_A_DQ<25>
   38  M_A_DQ<24>     DQ<24>  @BASEBOARD_FAB2_LIB.BASEBOARD_FAB2(SCH_1):M_A_DQ<24>
  177  M_A_DQ<23>     DQ<23>  @BASEBOARD_FAB2_LIB.BASEBOARD_FAB2(SCH_1):M_A_DQ<23>
   32  M_A_DQ<22>     DQ<22>  @BASEBOARD_FAB2_LIB.BASEBOARD_FAB2(SCH_1):M_A_DQ<22>
  170  M_A_DQ<21>     DQ<21>  @BASEBOARD_FAB2_LIB.BASEBOARD_FAB2(SCH_1):M_A_DQ<21>
   25  M_A_DQ<20>     DQ<20>  @BASEBOARD_FAB2_LIB.BASEBOARD_FAB2(SCH_1):M_A_DQ<20>
  150  M_A_DQ<1>      DQ<1>  @BASEBOARD_FAB2_LIB.BASEBOARD_FAB2(SCH_1):M_A_DQ<1>
  179  M_A_DQ<19>     DQ<19>  @BASEBOARD_FAB2_LIB.BASEBOARD_FAB2(SCH_1):M_A_DQ<19>
   34  M_A_DQ<18>     DQ<18>  @BASEBOARD_FAB2_LIB.BASEBOARD_FAB2(SCH_1):M_A_DQ<18>
  172  M_A_DQ<17>     DQ<17>  @BASEBOARD_FAB2_LIB.BASEBOARD_FAB2(SCH_1):M_A_DQ<17>
   27  M_A_DQ<16>     DQ<16>  @BASEBOARD_FAB2_LIB.BASEBOARD_FAB2(SCH_1):M_A_DQ<16>
  166  M_A_DQ<15>     DQ<15>  @BASEBOARD_FAB2_LIB.BASEBOARD_FAB2(SCH_1):M_A_DQ<15>
   21  M_A_DQ<14>     DQ<14>  @BASEBOARD_FAB2_LIB.BASEBOARD_FAB2(SCH_1):M_A_DQ<14>
  159  M_A_DQ<13>     DQ<13>  @BASEBOARD_FAB2_LIB.BASEBOARD_FAB2(SCH_1):M_A_DQ<13>
   14  M_A_DQ<12>     DQ<12>  @BASEBOARD_FAB2_LIB.BASEBOARD_FAB2(SCH_1):M_A_DQ<12>
  168  M_A_DQ<11>     DQ<11>  @BASEBOARD_FAB2_LIB.BASEBOARD_FAB2(SCH_1):M_A_DQ<11>
   23  M_A_DQ<10>     DQ<10>  @BASEBOARD_FAB2_LIB.BASEBOARD_FAB2(SCH_1):M_A_DQ<10>
    5  M_A_DQ<0>      DQ<0>  @BASEBOARD_FAB2_LIB.BASEBOARD_FAB2(SCH_1):M_A_DQ<0>
  237  M_A_CS_N<7>    S3_N_C<1>  @BASEBOARD_FAB2_LIB.BASEBOARD_FAB2(SCH_1):M_A_CS_N<7>
   93  M_A_CS_N<6>    S2_N_C<0>  @BASEBOARD_FAB2_LIB.BASEBOARD_FAB2(SCH_1):M_A_CS_N<6>
   89  M_A_CS_N<5>     S1_N  @BASEBOARD_FAB2_LIB.BASEBOARD_FAB2(SCH_1):M_A_CS_N<5>
   84  M_A_CS_N<4>     S0_N  @BASEBOARD_FAB2_LIB.BASEBOARD_FAB2(SCH_1):M_A_CS_N<4>
  218  M_A_CLK_DP<3>   CK1P  @BASEBOARD_FAB2_LIB.BASEBOARD_FAB2(SCH_1):M_A_CLK_DP<3>
   74  M_A_CLK_DP<2>   CK0P  @BASEBOARD_FAB2_LIB.BASEBOARD_FAB2(SCH_1):M_A_CLK_DP<2>
  219  M_A_CLK_DN<3>   CK1N  @BASEBOARD_FAB2_LIB.BASEBOARD_FAB2(SCH_1):M_A_CLK_DN<3>
   75  M_A_CLK_DN<2>   CK0N  @BASEBOARD_FAB2_LIB.BASEBOARD_FAB2(SCH_1):M_A_CLK_DN<2>
  203  M_A_CKE<3>     CKE<1>  @BASEBOARD_FAB2_LIB.BASEBOARD_FAB2(SCH_1):M_A_CKE<3>
   60  M_A_CKE<2>     CKE<0>  @BASEBOARD_FAB2_LIB.BASEBOARD_FAB2(SCH_1):M_A_CKE<2>
  235  M_A_C<2>        C<2>  @BASEBOARD_FAB2_LIB.BASEBOARD_FAB2(SCH_1):M_A_C<2>
  207  M_A_BG<1>      BG<1>  @BASEBOARD_FAB2_LIB.BASEBOARD_FAB2(SCH_1):M_A_BG<1>
   63  M_A_BG<0>      BG<0>  @BASEBOARD_FAB2_LIB.BASEBOARD_FAB2(SCH_1):M_A_BG<0>
  224  M_A_BA<1>      BA<1>  @BASEBOARD_FAB2_LIB.BASEBOARD_FAB2(SCH_1):M_A_BA<1>
   81  M_A_BA<0>      BA<0>  @BASEBOARD_FAB2_LIB.BASEBOARD_FAB2(SCH_1):M_A_BA<0>
  208  M_A_ALERT_N    ALERT_N  @BASEBOARD_FAB2_LIB.BASEBOARD_FAB2(SCH_1):M_A_ALERT_N
   62  M_A_ACT_N      ACT_N  @BASEBOARD_FAB2_LIB.BASEBOARD_FAB2(SCH_1):M_A_ACT_N
   58  M_ABC_RST_N    RESET_N  @BASEBOARD_FAB2_LIB.BASEBOARD_FAB2(SCH_1):M_ABC_RST_N
  238  GND            SA<2>  @BASEBOARD_FAB2_LIB.BASEBOARD_FAB2(SCH_1):GND
  140  GND            SA<1>  @BASEBOARD_FAB2_LIB.BASEBOARD_FAB2(SCH_1):GND
   78  FM_DIMM_EVENT_COD_N  EVENT_N  @BASEBOARD_FAB2_LIB.BASEBOARD_FAB2(SCH_1):FM_DIMM_EVENT_COD_N
  230  FM_ADR_COMPLETE_ABC_N  SAVE_N_NC  @BASEBOARD_FAB2_LIB.BASEBOARD_FAB2(SCH_1):FM_ADR_COMPLETE_ABC_N

SCONN288_H44441003_PIP  I67  J6U1   [SCONN288_H44441003_PIP-SCONN,HA]
   77  PVTT_ABC       VTT<1>  @BASEBOARD_FAB2_LIB.BASEBOARD_FAB2(SCH_1):PVTT_ABC
  221  PVTT_ABC       VTT<0>  @BASEBOARD_FAB2_LIB.BASEBOARD_FAB2(SCH_1):PVTT_ABC
  142  PVPP_ABC       VPP<4>  @BASEBOARD_FAB2_LIB.BASEBOARD_FAB2(SCH_1):PVPP_ABC
  143  PVPP_ABC       VPP<3>  @BASEBOARD_FAB2_LIB.BASEBOARD_FAB2(SCH_1):PVPP_ABC
  288  PVPP_ABC       VPP<2>  @BASEBOARD_FAB2_LIB.BASEBOARD_FAB2(SCH_1):PVPP_ABC
  286  PVPP_ABC       VPP<1>  @BASEBOARD_FAB2_LIB.BASEBOARD_FAB2(SCH_1):PVPP_ABC
  287  PVPP_ABC       VPP<0>  @BASEBOARD_FAB2_LIB.BASEBOARD_FAB2(SCH_1):PVPP_ABC
   59  PVDDQ_ABC      VDD<25>  @BASEBOARD_FAB2_LIB.BASEBOARD_FAB2(SCH_1):PVDDQ_ABC
   61  PVDDQ_ABC      VDD<24>  @BASEBOARD_FAB2_LIB.BASEBOARD_FAB2(SCH_1):PVDDQ_ABC
   64  PVDDQ_ABC      VDD<23>  @BASEBOARD_FAB2_LIB.BASEBOARD_FAB2(SCH_1):PVDDQ_ABC
   67  PVDDQ_ABC      VDD<22>  @BASEBOARD_FAB2_LIB.BASEBOARD_FAB2(SCH_1):PVDDQ_ABC
   70  PVDDQ_ABC      VDD<21>  @BASEBOARD_FAB2_LIB.BASEBOARD_FAB2(SCH_1):PVDDQ_ABC
   73  PVDDQ_ABC      VDD<20>  @BASEBOARD_FAB2_LIB.BASEBOARD_FAB2(SCH_1):PVDDQ_ABC
   76  PVDDQ_ABC      VDD<19>  @BASEBOARD_FAB2_LIB.BASEBOARD_FAB2(SCH_1):PVDDQ_ABC
   80  PVDDQ_ABC      VDD<18>  @BASEBOARD_FAB2_LIB.BASEBOARD_FAB2(SCH_1):PVDDQ_ABC
   83  PVDDQ_ABC      VDD<17>  @BASEBOARD_FAB2_LIB.BASEBOARD_FAB2(SCH_1):PVDDQ_ABC
   85  PVDDQ_ABC      VDD<16>  @BASEBOARD_FAB2_LIB.BASEBOARD_FAB2(SCH_1):PVDDQ_ABC
   88  PVDDQ_ABC      VDD<15>  @BASEBOARD_FAB2_LIB.BASEBOARD_FAB2(SCH_1):PVDDQ_ABC
   90  PVDDQ_ABC      VDD<14>  @BASEBOARD_FAB2_LIB.BASEBOARD_FAB2(SCH_1):PVDDQ_ABC
   92  PVDDQ_ABC      VDD<13>  @BASEBOARD_FAB2_LIB.BASEBOARD_FAB2(SCH_1):PVDDQ_ABC
  204  PVDDQ_ABC      VDD<12>  @BASEBOARD_FAB2_LIB.BASEBOARD_FAB2(SCH_1):PVDDQ_ABC
  206  PVDDQ_ABC      VDD<11>  @BASEBOARD_FAB2_LIB.BASEBOARD_FAB2(SCH_1):PVDDQ_ABC
  209  PVDDQ_ABC      VDD<10>  @BASEBOARD_FAB2_LIB.BASEBOARD_FAB2(SCH_1):PVDDQ_ABC
  212  PVDDQ_ABC      VDD<9>  @BASEBOARD_FAB2_LIB.BASEBOARD_FAB2(SCH_1):PVDDQ_ABC
  215  PVDDQ_ABC      VDD<8>  @BASEBOARD_FAB2_LIB.BASEBOARD_FAB2(SCH_1):PVDDQ_ABC
  217  PVDDQ_ABC      VDD<7>  @BASEBOARD_FAB2_LIB.BASEBOARD_FAB2(SCH_1):PVDDQ_ABC
  220  PVDDQ_ABC      VDD<6>  @BASEBOARD_FAB2_LIB.BASEBOARD_FAB2(SCH_1):PVDDQ_ABC
  223  PVDDQ_ABC      VDD<5>  @BASEBOARD_FAB2_LIB.BASEBOARD_FAB2(SCH_1):PVDDQ_ABC
  226  PVDDQ_ABC      VDD<4>  @BASEBOARD_FAB2_LIB.BASEBOARD_FAB2(SCH_1):PVDDQ_ABC
  229  PVDDQ_ABC      VDD<3>  @BASEBOARD_FAB2_LIB.BASEBOARD_FAB2(SCH_1):PVDDQ_ABC
  231  PVDDQ_ABC      VDD<2>  @BASEBOARD_FAB2_LIB.BASEBOARD_FAB2(SCH_1):PVDDQ_ABC
  233  PVDDQ_ABC      VDD<1>  @BASEBOARD_FAB2_LIB.BASEBOARD_FAB2(SCH_1):PVDDQ_ABC
  236  PVDDQ_ABC      VDD<0>  @BASEBOARD_FAB2_LIB.BASEBOARD_FAB2(SCH_1):PVDDQ_ABC
    1  P12V_NVDIMM_ABC  12V<1>  @BASEBOARD_FAB2_LIB.BASEBOARD_FAB2(SCH_1):P12V_NVDIMM_ABC
  145  P12V_NVDIMM_ABC  12V<0>  @BASEBOARD_FAB2_LIB.BASEBOARD_FAB2(SCH_1):P12V_NVDIMM_ABC

SCONN288_H44441003_PIP  I138  J6U1   [SCONN288_H44441003_PIP-SCONN,HA]
    2  GND            VSS<93>  @BASEBOARD_FAB2_LIB.BASEBOARD_FAB2(SCH_1):GND
    4  GND            VSS<92>  @BASEBOARD_FAB2_LIB.BASEBOARD_FAB2(SCH_1):GND
    6  GND            VSS<91>  @BASEBOARD_FAB2_LIB.BASEBOARD_FAB2(SCH_1):GND
    9  GND            VSS<90>  @BASEBOARD_FAB2_LIB.BASEBOARD_FAB2(SCH_1):GND
   11  GND            VSS<89>  @BASEBOARD_FAB2_LIB.BASEBOARD_FAB2(SCH_1):GND
   13  GND            VSS<88>  @BASEBOARD_FAB2_LIB.BASEBOARD_FAB2(SCH_1):GND
   15  GND            VSS<87>  @BASEBOARD_FAB2_LIB.BASEBOARD_FAB2(SCH_1):GND
   17  GND            VSS<86>  @BASEBOARD_FAB2_LIB.BASEBOARD_FAB2(SCH_1):GND
   20  GND            VSS<85>  @BASEBOARD_FAB2_LIB.BASEBOARD_FAB2(SCH_1):GND
   22  GND            VSS<84>  @BASEBOARD_FAB2_LIB.BASEBOARD_FAB2(SCH_1):GND
   24  GND            VSS<83>  @BASEBOARD_FAB2_LIB.BASEBOARD_FAB2(SCH_1):GND
   26  GND            VSS<82>  @BASEBOARD_FAB2_LIB.BASEBOARD_FAB2(SCH_1):GND
   28  GND            VSS<81>  @BASEBOARD_FAB2_LIB.BASEBOARD_FAB2(SCH_1):GND
   31  GND            VSS<80>  @BASEBOARD_FAB2_LIB.BASEBOARD_FAB2(SCH_1):GND
   33  GND            VSS<79>  @BASEBOARD_FAB2_LIB.BASEBOARD_FAB2(SCH_1):GND
   35  GND            VSS<78>  @BASEBOARD_FAB2_LIB.BASEBOARD_FAB2(SCH_1):GND
   37  GND            VSS<77>  @BASEBOARD_FAB2_LIB.BASEBOARD_FAB2(SCH_1):GND
   39  GND            VSS<76>  @BASEBOARD_FAB2_LIB.BASEBOARD_FAB2(SCH_1):GND
   42  GND            VSS<75>  @BASEBOARD_FAB2_LIB.BASEBOARD_FAB2(SCH_1):GND
   44  GND            VSS<74>  @BASEBOARD_FAB2_LIB.BASEBOARD_FAB2(SCH_1):GND
   46  GND            VSS<73>  @BASEBOARD_FAB2_LIB.BASEBOARD_FAB2(SCH_1):GND
   48  GND            VSS<72>  @BASEBOARD_FAB2_LIB.BASEBOARD_FAB2(SCH_1):GND
   50  GND            VSS<71>  @BASEBOARD_FAB2_LIB.BASEBOARD_FAB2(SCH_1):GND
   53  GND            VSS<70>  @BASEBOARD_FAB2_LIB.BASEBOARD_FAB2(SCH_1):GND
   55  GND            VSS<69>  @BASEBOARD_FAB2_LIB.BASEBOARD_FAB2(SCH_1):GND
   57  GND            VSS<68>  @BASEBOARD_FAB2_LIB.BASEBOARD_FAB2(SCH_1):GND
   94  GND            VSS<67>  @BASEBOARD_FAB2_LIB.BASEBOARD_FAB2(SCH_1):GND
   96  GND            VSS<66>  @BASEBOARD_FAB2_LIB.BASEBOARD_FAB2(SCH_1):GND
   98  GND            VSS<65>  @BASEBOARD_FAB2_LIB.BASEBOARD_FAB2(SCH_1):GND
  101  GND            VSS<64>  @BASEBOARD_FAB2_LIB.BASEBOARD_FAB2(SCH_1):GND
  103  GND            VSS<63>  @BASEBOARD_FAB2_LIB.BASEBOARD_FAB2(SCH_1):GND
  105  GND            VSS<62>  @BASEBOARD_FAB2_LIB.BASEBOARD_FAB2(SCH_1):GND
  107  GND            VSS<61>  @BASEBOARD_FAB2_LIB.BASEBOARD_FAB2(SCH_1):GND
  109  GND            VSS<60>  @BASEBOARD_FAB2_LIB.BASEBOARD_FAB2(SCH_1):GND
  112  GND            VSS<59>  @BASEBOARD_FAB2_LIB.BASEBOARD_FAB2(SCH_1):GND
  114  GND            VSS<58>  @BASEBOARD_FAB2_LIB.BASEBOARD_FAB2(SCH_1):GND
  116  GND            VSS<57>  @BASEBOARD_FAB2_LIB.BASEBOARD_FAB2(SCH_1):GND
  118  GND            VSS<56>  @BASEBOARD_FAB2_LIB.BASEBOARD_FAB2(SCH_1):GND
  120  GND            VSS<55>  @BASEBOARD_FAB2_LIB.BASEBOARD_FAB2(SCH_1):GND
  123  GND            VSS<54>  @BASEBOARD_FAB2_LIB.BASEBOARD_FAB2(SCH_1):GND
  125  GND            VSS<53>  @BASEBOARD_FAB2_LIB.BASEBOARD_FAB2(SCH_1):GND
  127  GND            VSS<52>  @BASEBOARD_FAB2_LIB.BASEBOARD_FAB2(SCH_1):GND
  129  GND            VSS<51>  @BASEBOARD_FAB2_LIB.BASEBOARD_FAB2(SCH_1):GND
  131  GND            VSS<50>  @BASEBOARD_FAB2_LIB.BASEBOARD_FAB2(SCH_1):GND
  134  GND            VSS<49>  @BASEBOARD_FAB2_LIB.BASEBOARD_FAB2(SCH_1):GND
  136  GND            VSS<48>  @BASEBOARD_FAB2_LIB.BASEBOARD_FAB2(SCH_1):GND
  138  GND            VSS<47>  @BASEBOARD_FAB2_LIB.BASEBOARD_FAB2(SCH_1):GND
  147  GND            VSS<46>  @BASEBOARD_FAB2_LIB.BASEBOARD_FAB2(SCH_1):GND
  149  GND            VSS<45>  @BASEBOARD_FAB2_LIB.BASEBOARD_FAB2(SCH_1):GND
  151  GND            VSS<44>  @BASEBOARD_FAB2_LIB.BASEBOARD_FAB2(SCH_1):GND
  154  GND            VSS<43>  @BASEBOARD_FAB2_LIB.BASEBOARD_FAB2(SCH_1):GND
  156  GND            VSS<42>  @BASEBOARD_FAB2_LIB.BASEBOARD_FAB2(SCH_1):GND
  158  GND            VSS<41>  @BASEBOARD_FAB2_LIB.BASEBOARD_FAB2(SCH_1):GND
  160  GND            VSS<40>  @BASEBOARD_FAB2_LIB.BASEBOARD_FAB2(SCH_1):GND
  162  GND            VSS<39>  @BASEBOARD_FAB2_LIB.BASEBOARD_FAB2(SCH_1):GND
  165  GND            VSS<38>  @BASEBOARD_FAB2_LIB.BASEBOARD_FAB2(SCH_1):GND
  167  GND            VSS<37>  @BASEBOARD_FAB2_LIB.BASEBOARD_FAB2(SCH_1):GND
  169  GND            VSS<36>  @BASEBOARD_FAB2_LIB.BASEBOARD_FAB2(SCH_1):GND
  171  GND            VSS<35>  @BASEBOARD_FAB2_LIB.BASEBOARD_FAB2(SCH_1):GND
  173  GND            VSS<34>  @BASEBOARD_FAB2_LIB.BASEBOARD_FAB2(SCH_1):GND
  176  GND            VSS<33>  @BASEBOARD_FAB2_LIB.BASEBOARD_FAB2(SCH_1):GND
  178  GND            VSS<32>  @BASEBOARD_FAB2_LIB.BASEBOARD_FAB2(SCH_1):GND
  180  GND            VSS<31>  @BASEBOARD_FAB2_LIB.BASEBOARD_FAB2(SCH_1):GND
  182  GND            VSS<30>  @BASEBOARD_FAB2_LIB.BASEBOARD_FAB2(SCH_1):GND
  184  GND            VSS<29>  @BASEBOARD_FAB2_LIB.BASEBOARD_FAB2(SCH_1):GND
  187  GND            VSS<28>  @BASEBOARD_FAB2_LIB.BASEBOARD_FAB2(SCH_1):GND
  189  GND            VSS<27>  @BASEBOARD_FAB2_LIB.BASEBOARD_FAB2(SCH_1):GND
  191  GND            VSS<26>  @BASEBOARD_FAB2_LIB.BASEBOARD_FAB2(SCH_1):GND
  193  GND            VSS<25>  @BASEBOARD_FAB2_LIB.BASEBOARD_FAB2(SCH_1):GND
  195  GND            VSS<24>  @BASEBOARD_FAB2_LIB.BASEBOARD_FAB2(SCH_1):GND
  198  GND            VSS<23>  @BASEBOARD_FAB2_LIB.BASEBOARD_FAB2(SCH_1):GND
  200  GND            VSS<22>  @BASEBOARD_FAB2_LIB.BASEBOARD_FAB2(SCH_1):GND
  202  GND            VSS<21>  @BASEBOARD_FAB2_LIB.BASEBOARD_FAB2(SCH_1):GND
  239  GND            VSS<20>  @BASEBOARD_FAB2_LIB.BASEBOARD_FAB2(SCH_1):GND
  241  GND            VSS<19>  @BASEBOARD_FAB2_LIB.BASEBOARD_FAB2(SCH_1):GND
  243  GND            VSS<18>  @BASEBOARD_FAB2_LIB.BASEBOARD_FAB2(SCH_1):GND
  246  GND            VSS<17>  @BASEBOARD_FAB2_LIB.BASEBOARD_FAB2(SCH_1):GND
  248  GND            VSS<16>  @BASEBOARD_FAB2_LIB.BASEBOARD_FAB2(SCH_1):GND
  250  GND            VSS<15>  @BASEBOARD_FAB2_LIB.BASEBOARD_FAB2(SCH_1):GND
  252  GND            VSS<14>  @BASEBOARD_FAB2_LIB.BASEBOARD_FAB2(SCH_1):GND
  254  GND            VSS<13>  @BASEBOARD_FAB2_LIB.BASEBOARD_FAB2(SCH_1):GND
  257  GND            VSS<12>  @BASEBOARD_FAB2_LIB.BASEBOARD_FAB2(SCH_1):GND
  259  GND            VSS<11>  @BASEBOARD_FAB2_LIB.BASEBOARD_FAB2(SCH_1):GND
  261  GND            VSS<10>  @BASEBOARD_FAB2_LIB.BASEBOARD_FAB2(SCH_1):GND
  263  GND            VSS<9>  @BASEBOARD_FAB2_LIB.BASEBOARD_FAB2(SCH_1):GND
  265  GND            VSS<8>  @BASEBOARD_FAB2_LIB.BASEBOARD_FAB2(SCH_1):GND
  268  GND            VSS<7>  @BASEBOARD_FAB2_LIB.BASEBOARD_FAB2(SCH_1):GND
  270  GND            VSS<6>  @BASEBOARD_FAB2_LIB.BASEBOARD_FAB2(SCH_1):GND
  272  GND            VSS<5>  @BASEBOARD_FAB2_LIB.BASEBOARD_FAB2(SCH_1):GND
  274  GND            VSS<4>  @BASEBOARD_FAB2_LIB.BASEBOARD_FAB2(SCH_1):GND
  276  GND            VSS<3>  @BASEBOARD_FAB2_LIB.BASEBOARD_FAB2(SCH_1):GND
  279  GND            VSS<2>  @BASEBOARD_FAB2_LIB.BASEBOARD_FAB2(SCH_1):GND
  281  GND            VSS<1>  @BASEBOARD_FAB2_LIB.BASEBOARD_FAB2(SCH_1):GND
  283  GND            VSS<0>  @BASEBOARD_FAB2_LIB.BASEBOARD_FAB2(SCH_1):GND

SCONN288_H44441003_PIP  I112  J6U1   [SCONN288_H44441003_PIP-SCONN,HA]
    7  M_B_DQS_DP<9>  DQS9P  @BASEBOARD_FAB2_LIB.BASEBOARD_FAB2(SCH_1):M_B_DQS_DP<9>
  197  M_B_DQS_DP<8>  DQS8P  @BASEBOARD_FAB2_LIB.BASEBOARD_FAB2(SCH_1):M_B_DQS_DP<8>
  278  M_B_DQS_DP<7>  DQS7P  @BASEBOARD_FAB2_LIB.BASEBOARD_FAB2(SCH_1):M_B_DQS_DP<7>
  267  M_B_DQS_DP<6>  DQS6P  @BASEBOARD_FAB2_LIB.BASEBOARD_FAB2(SCH_1):M_B_DQS_DP<6>
  256  M_B_DQS_DP<5>  DQS5P  @BASEBOARD_FAB2_LIB.BASEBOARD_FAB2(SCH_1):M_B_DQS_DP<5>
  245  M_B_DQS_DP<4>  DQS4P  @BASEBOARD_FAB2_LIB.BASEBOARD_FAB2(SCH_1):M_B_DQS_DP<4>
  186  M_B_DQS_DP<3>  DQS3P  @BASEBOARD_FAB2_LIB.BASEBOARD_FAB2(SCH_1):M_B_DQS_DP<3>
  175  M_B_DQS_DP<2>  DQS2P  @BASEBOARD_FAB2_LIB.BASEBOARD_FAB2(SCH_1):M_B_DQS_DP<2>
  164  M_B_DQS_DP<1>  DQS1P  @BASEBOARD_FAB2_LIB.BASEBOARD_FAB2(SCH_1):M_B_DQS_DP<1>
   51  M_B_DQS_DP<17>  DQS17P  @BASEBOARD_FAB2_LIB.BASEBOARD_FAB2(SCH_1):M_B_DQS_DP<17>
  132  M_B_DQS_DP<16>  DQS16P  @BASEBOARD_FAB2_LIB.BASEBOARD_FAB2(SCH_1):M_B_DQS_DP<16>
  121  M_B_DQS_DP<15>  DQS15P  @BASEBOARD_FAB2_LIB.BASEBOARD_FAB2(SCH_1):M_B_DQS_DP<15>
  110  M_B_DQS_DP<14>  DQS14P  @BASEBOARD_FAB2_LIB.BASEBOARD_FAB2(SCH_1):M_B_DQS_DP<14>
   99  M_B_DQS_DP<13>  DQS13P  @BASEBOARD_FAB2_LIB.BASEBOARD_FAB2(SCH_1):M_B_DQS_DP<13>
   40  M_B_DQS_DP<12>  DQS12P  @BASEBOARD_FAB2_LIB.BASEBOARD_FAB2(SCH_1):M_B_DQS_DP<12>
   29  M_B_DQS_DP<11>  DQS11P  @BASEBOARD_FAB2_LIB.BASEBOARD_FAB2(SCH_1):M_B_DQS_DP<11>
   18  M_B_DQS_DP<10>  DQS10P  @BASEBOARD_FAB2_LIB.BASEBOARD_FAB2(SCH_1):M_B_DQS_DP<10>
  153  M_B_DQS_DP<0>  DQS0P  @BASEBOARD_FAB2_LIB.BASEBOARD_FAB2(SCH_1):M_B_DQS_DP<0>
    8  M_B_DQS_DN<9>  DQS9N  @BASEBOARD_FAB2_LIB.BASEBOARD_FAB2(SCH_1):M_B_DQS_DN<9>
  196  M_B_DQS_DN<8>  DQS8N  @BASEBOARD_FAB2_LIB.BASEBOARD_FAB2(SCH_1):M_B_DQS_DN<8>
  277  M_B_DQS_DN<7>  DQS7N  @BASEBOARD_FAB2_LIB.BASEBOARD_FAB2(SCH_1):M_B_DQS_DN<7>
  266  M_B_DQS_DN<6>  DQS6N  @BASEBOARD_FAB2_LIB.BASEBOARD_FAB2(SCH_1):M_B_DQS_DN<6>
  255  M_B_DQS_DN<5>  DQS5N  @BASEBOARD_FAB2_LIB.BASEBOARD_FAB2(SCH_1):M_B_DQS_DN<5>
  244  M_B_DQS_DN<4>  DQS4N  @BASEBOARD_FAB2_LIB.BASEBOARD_FAB2(SCH_1):M_B_DQS_DN<4>
  185  M_B_DQS_DN<3>  DQS3N  @BASEBOARD_FAB2_LIB.BASEBOARD_FAB2(SCH_1):M_B_DQS_DN<3>
  174  M_B_DQS_DN<2>  DQS2N  @BASEBOARD_FAB2_LIB.BASEBOARD_FAB2(SCH_1):M_B_DQS_DN<2>
  163  M_B_DQS_DN<1>  DQS1N  @BASEBOARD_FAB2_LIB.BASEBOARD_FAB2(SCH_1):M_B_DQS_DN<1>
   52  M_B_DQS_DN<17>  DQS17N  @BASEBOARD_FAB2_LIB.BASEBOARD_FAB2(SCH_1):M_B_DQS_DN<17>
  133  M_B_DQS_DN<16>  DQS16N  @BASEBOARD_FAB2_LIB.BASEBOARD_FAB2(SCH_1):M_B_DQS_DN<16>
  122  M_B_DQS_DN<15>  DQS15N  @BASEBOARD_FAB2_LIB.BASEBOARD_FAB2(SCH_1):M_B_DQS_DN<15>
  111  M_B_DQS_DN<14>  DQS14N  @BASEBOARD_FAB2_LIB.BASEBOARD_FAB2(SCH_1):M_B_DQS_DN<14>
  100  M_B_DQS_DN<13>  DQS13N  @BASEBOARD_FAB2_LIB.BASEBOARD_FAB2(SCH_1):M_B_DQS_DN<13>
   41  M_B_DQS_DN<12>  DQS12N  @BASEBOARD_FAB2_LIB.BASEBOARD_FAB2(SCH_1):M_B_DQS_DN<12>
   30  M_B_DQS_DN<11>  DQS11N  @BASEBOARD_FAB2_LIB.BASEBOARD_FAB2(SCH_1):M_B_DQS_DN<11>
   19  M_B_DQS_DN<10>  DQS10N  @BASEBOARD_FAB2_LIB.BASEBOARD_FAB2(SCH_1):M_B_DQS_DN<10>
  152  M_B_DQS_DN<0>  DQS0N  @BASEBOARD_FAB2_LIB.BASEBOARD_FAB2(SCH_1):M_B_DQS_DN<0>

SCONN288_H44441003_PIP  I14  J6U1   [SCONN288_H44441003_PIP-SCONN,HA]
  144  TP_CH_B_DIMM_B1_RFU_2  RFU<2>  @BASEBOARD_FAB2_LIB.BASEBOARD_FAB2(SCH_1):TP_CH_B_DIMM_B1_RFU_2
  227  TP_CH_B_DIMM_B1_RFU_1  RFU<1>  @BASEBOARD_FAB2_LIB.BASEBOARD_FAB2(SCH_1):TP_CH_B_DIMM_B1_RFU_1
  205  TP_CH_B_DIMM_B1_RFU_0  RFU<0>  @BASEBOARD_FAB2_LIB.BASEBOARD_FAB2(SCH_1):TP_CH_B_DIMM_B1_RFU_0
  285  SMB_DDR_ABC_VPP_SDA    SDA  @BASEBOARD_FAB2_LIB.BASEBOARD_FAB2(SCH_1):SMB_DDR_ABC_VPP_SDA
  141  SMB_DDR_ABC_VPP_SCL    SCL  @BASEBOARD_FAB2_LIB.BASEBOARD_FAB2(SCH_1):SMB_DDR_ABC_VPP_SCL
  284  PVPP_ABC       VDDSPD  @BASEBOARD_FAB2_LIB.BASEBOARD_FAB2(SCH_1):PVPP_ABC
  140  PVPP_ABC       SA<1>  @BASEBOARD_FAB2_LIB.BASEBOARD_FAB2(SCH_1):PVPP_ABC
  139  PVPP_ABC       SA<0>  @BASEBOARD_FAB2_LIB.BASEBOARD_FAB2(SCH_1):PVPP_ABC
  146  M_B_VREF       VREFCA  @BASEBOARD_FAB2_LIB.BASEBOARD_FAB2(SCH_1):M_B_VREF
  222  M_B_PAR          PAR  @BASEBOARD_FAB2_LIB.BASEBOARD_FAB2(SCH_1):M_B_PAR
   91  M_B_ODT<3>     ODT<1>  @BASEBOARD_FAB2_LIB.BASEBOARD_FAB2(SCH_1):M_B_ODT<3>
   87  M_B_ODT<2>     ODT<0>  @BASEBOARD_FAB2_LIB.BASEBOARD_FAB2(SCH_1):M_B_ODT<2>
   66  M_B_MA<9>         A9  @BASEBOARD_FAB2_LIB.BASEBOARD_FAB2(SCH_1):M_B_MA<9>
   68  M_B_MA<8>         A8  @BASEBOARD_FAB2_LIB.BASEBOARD_FAB2(SCH_1):M_B_MA<8>
  211  M_B_MA<7>         A7  @BASEBOARD_FAB2_LIB.BASEBOARD_FAB2(SCH_1):M_B_MA<7>
   69  M_B_MA<6>         A6  @BASEBOARD_FAB2_LIB.BASEBOARD_FAB2(SCH_1):M_B_MA<6>
  213  M_B_MA<5>         A5  @BASEBOARD_FAB2_LIB.BASEBOARD_FAB2(SCH_1):M_B_MA<5>
  214  M_B_MA<4>         A4  @BASEBOARD_FAB2_LIB.BASEBOARD_FAB2(SCH_1):M_B_MA<4>
   71  M_B_MA<3>         A3  @BASEBOARD_FAB2_LIB.BASEBOARD_FAB2(SCH_1):M_B_MA<3>
  216  M_B_MA<2>         A2  @BASEBOARD_FAB2_LIB.BASEBOARD_FAB2(SCH_1):M_B_MA<2>
   72  M_B_MA<1>         A1  @BASEBOARD_FAB2_LIB.BASEBOARD_FAB2(SCH_1):M_B_MA<1>
  234  M_B_MA<17>       A17  @BASEBOARD_FAB2_LIB.BASEBOARD_FAB2(SCH_1):M_B_MA<17>
   82  M_B_MA<16>     A16_RAS_N  @BASEBOARD_FAB2_LIB.BASEBOARD_FAB2(SCH_1):M_B_MA<16>
   86  M_B_MA<15>     A15_CAS_N  @BASEBOARD_FAB2_LIB.BASEBOARD_FAB2(SCH_1):M_B_MA<15>
  228  M_B_MA<14>     A14_WE_N  @BASEBOARD_FAB2_LIB.BASEBOARD_FAB2(SCH_1):M_B_MA<14>
  232  M_B_MA<13>       A13  @BASEBOARD_FAB2_LIB.BASEBOARD_FAB2(SCH_1):M_B_MA<13>
   65  M_B_MA<12>       A12  @BASEBOARD_FAB2_LIB.BASEBOARD_FAB2(SCH_1):M_B_MA<12>
  210  M_B_MA<11>       A11  @BASEBOARD_FAB2_LIB.BASEBOARD_FAB2(SCH_1):M_B_MA<11>
  225  M_B_MA<10>       A10  @BASEBOARD_FAB2_LIB.BASEBOARD_FAB2(SCH_1):M_B_MA<10>
   79  M_B_MA<0>         A0  @BASEBOARD_FAB2_LIB.BASEBOARD_FAB2(SCH_1):M_B_MA<0>
  199  M_B_ECC<7>     CB<7>  @BASEBOARD_FAB2_LIB.BASEBOARD_FAB2(SCH_1):M_B_ECC<7>
   54  M_B_ECC<6>     CB<6>  @BASEBOARD_FAB2_LIB.BASEBOARD_FAB2(SCH_1):M_B_ECC<6>
  192  M_B_ECC<5>     CB<5>  @BASEBOARD_FAB2_LIB.BASEBOARD_FAB2(SCH_1):M_B_ECC<5>
   47  M_B_ECC<4>     CB<4>  @BASEBOARD_FAB2_LIB.BASEBOARD_FAB2(SCH_1):M_B_ECC<4>
  201  M_B_ECC<3>     CB<3>  @BASEBOARD_FAB2_LIB.BASEBOARD_FAB2(SCH_1):M_B_ECC<3>
   56  M_B_ECC<2>     CB<2>  @BASEBOARD_FAB2_LIB.BASEBOARD_FAB2(SCH_1):M_B_ECC<2>
  194  M_B_ECC<1>     CB<1>  @BASEBOARD_FAB2_LIB.BASEBOARD_FAB2(SCH_1):M_B_ECC<1>
   49  M_B_ECC<0>     CB<0>  @BASEBOARD_FAB2_LIB.BASEBOARD_FAB2(SCH_1):M_B_ECC<0>
  161  M_B_DQ<9>      DQ<9>  @BASEBOARD_FAB2_LIB.BASEBOARD_FAB2(SCH_1):M_B_DQ<9>
   16  M_B_DQ<8>      DQ<8>  @BASEBOARD_FAB2_LIB.BASEBOARD_FAB2(SCH_1):M_B_DQ<8>
  155  M_B_DQ<7>      DQ<7>  @BASEBOARD_FAB2_LIB.BASEBOARD_FAB2(SCH_1):M_B_DQ<7>
   10  M_B_DQ<6>      DQ<6>  @BASEBOARD_FAB2_LIB.BASEBOARD_FAB2(SCH_1):M_B_DQ<6>
  280  M_B_DQ<63>     DQ<63>  @BASEBOARD_FAB2_LIB.BASEBOARD_FAB2(SCH_1):M_B_DQ<63>
  135  M_B_DQ<62>     DQ<62>  @BASEBOARD_FAB2_LIB.BASEBOARD_FAB2(SCH_1):M_B_DQ<62>
  273  M_B_DQ<61>     DQ<61>  @BASEBOARD_FAB2_LIB.BASEBOARD_FAB2(SCH_1):M_B_DQ<61>
  128  M_B_DQ<60>     DQ<60>  @BASEBOARD_FAB2_LIB.BASEBOARD_FAB2(SCH_1):M_B_DQ<60>
  148  M_B_DQ<5>      DQ<5>  @BASEBOARD_FAB2_LIB.BASEBOARD_FAB2(SCH_1):M_B_DQ<5>
  282  M_B_DQ<59>     DQ<59>  @BASEBOARD_FAB2_LIB.BASEBOARD_FAB2(SCH_1):M_B_DQ<59>
  137  M_B_DQ<58>     DQ<58>  @BASEBOARD_FAB2_LIB.BASEBOARD_FAB2(SCH_1):M_B_DQ<58>
  275  M_B_DQ<57>     DQ<57>  @BASEBOARD_FAB2_LIB.BASEBOARD_FAB2(SCH_1):M_B_DQ<57>
  130  M_B_DQ<56>     DQ<56>  @BASEBOARD_FAB2_LIB.BASEBOARD_FAB2(SCH_1):M_B_DQ<56>
  269  M_B_DQ<55>     DQ<55>  @BASEBOARD_FAB2_LIB.BASEBOARD_FAB2(SCH_1):M_B_DQ<55>
  124  M_B_DQ<54>     DQ<54>  @BASEBOARD_FAB2_LIB.BASEBOARD_FAB2(SCH_1):M_B_DQ<54>
  262  M_B_DQ<53>     DQ<53>  @BASEBOARD_FAB2_LIB.BASEBOARD_FAB2(SCH_1):M_B_DQ<53>
  117  M_B_DQ<52>     DQ<52>  @BASEBOARD_FAB2_LIB.BASEBOARD_FAB2(SCH_1):M_B_DQ<52>
  271  M_B_DQ<51>     DQ<51>  @BASEBOARD_FAB2_LIB.BASEBOARD_FAB2(SCH_1):M_B_DQ<51>
  126  M_B_DQ<50>     DQ<50>  @BASEBOARD_FAB2_LIB.BASEBOARD_FAB2(SCH_1):M_B_DQ<50>
    3  M_B_DQ<4>      DQ<4>  @BASEBOARD_FAB2_LIB.BASEBOARD_FAB2(SCH_1):M_B_DQ<4>
  264  M_B_DQ<49>     DQ<49>  @BASEBOARD_FAB2_LIB.BASEBOARD_FAB2(SCH_1):M_B_DQ<49>
  119  M_B_DQ<48>     DQ<48>  @BASEBOARD_FAB2_LIB.BASEBOARD_FAB2(SCH_1):M_B_DQ<48>
  258  M_B_DQ<47>     DQ<47>  @BASEBOARD_FAB2_LIB.BASEBOARD_FAB2(SCH_1):M_B_DQ<47>
  113  M_B_DQ<46>     DQ<46>  @BASEBOARD_FAB2_LIB.BASEBOARD_FAB2(SCH_1):M_B_DQ<46>
  251  M_B_DQ<45>     DQ<45>  @BASEBOARD_FAB2_LIB.BASEBOARD_FAB2(SCH_1):M_B_DQ<45>
  106  M_B_DQ<44>     DQ<44>  @BASEBOARD_FAB2_LIB.BASEBOARD_FAB2(SCH_1):M_B_DQ<44>
  260  M_B_DQ<43>     DQ<43>  @BASEBOARD_FAB2_LIB.BASEBOARD_FAB2(SCH_1):M_B_DQ<43>
  115  M_B_DQ<42>     DQ<42>  @BASEBOARD_FAB2_LIB.BASEBOARD_FAB2(SCH_1):M_B_DQ<42>
  253  M_B_DQ<41>     DQ<41>  @BASEBOARD_FAB2_LIB.BASEBOARD_FAB2(SCH_1):M_B_DQ<41>
  108  M_B_DQ<40>     DQ<40>  @BASEBOARD_FAB2_LIB.BASEBOARD_FAB2(SCH_1):M_B_DQ<40>
  157  M_B_DQ<3>      DQ<3>  @BASEBOARD_FAB2_LIB.BASEBOARD_FAB2(SCH_1):M_B_DQ<3>
  247  M_B_DQ<39>     DQ<39>  @BASEBOARD_FAB2_LIB.BASEBOARD_FAB2(SCH_1):M_B_DQ<39>
  102  M_B_DQ<38>     DQ<38>  @BASEBOARD_FAB2_LIB.BASEBOARD_FAB2(SCH_1):M_B_DQ<38>
  240  M_B_DQ<37>     DQ<37>  @BASEBOARD_FAB2_LIB.BASEBOARD_FAB2(SCH_1):M_B_DQ<37>
   95  M_B_DQ<36>     DQ<36>  @BASEBOARD_FAB2_LIB.BASEBOARD_FAB2(SCH_1):M_B_DQ<36>
  249  M_B_DQ<35>     DQ<35>  @BASEBOARD_FAB2_LIB.BASEBOARD_FAB2(SCH_1):M_B_DQ<35>
  104  M_B_DQ<34>     DQ<34>  @BASEBOARD_FAB2_LIB.BASEBOARD_FAB2(SCH_1):M_B_DQ<34>
  242  M_B_DQ<33>     DQ<33>  @BASEBOARD_FAB2_LIB.BASEBOARD_FAB2(SCH_1):M_B_DQ<33>
   97  M_B_DQ<32>     DQ<32>  @BASEBOARD_FAB2_LIB.BASEBOARD_FAB2(SCH_1):M_B_DQ<32>
  188  M_B_DQ<31>     DQ<31>  @BASEBOARD_FAB2_LIB.BASEBOARD_FAB2(SCH_1):M_B_DQ<31>
   43  M_B_DQ<30>     DQ<30>  @BASEBOARD_FAB2_LIB.BASEBOARD_FAB2(SCH_1):M_B_DQ<30>
   12  M_B_DQ<2>      DQ<2>  @BASEBOARD_FAB2_LIB.BASEBOARD_FAB2(SCH_1):M_B_DQ<2>
  181  M_B_DQ<29>     DQ<29>  @BASEBOARD_FAB2_LIB.BASEBOARD_FAB2(SCH_1):M_B_DQ<29>
   36  M_B_DQ<28>     DQ<28>  @BASEBOARD_FAB2_LIB.BASEBOARD_FAB2(SCH_1):M_B_DQ<28>
  190  M_B_DQ<27>     DQ<27>  @BASEBOARD_FAB2_LIB.BASEBOARD_FAB2(SCH_1):M_B_DQ<27>
   45  M_B_DQ<26>     DQ<26>  @BASEBOARD_FAB2_LIB.BASEBOARD_FAB2(SCH_1):M_B_DQ<26>
  183  M_B_DQ<25>     DQ<25>  @BASEBOARD_FAB2_LIB.BASEBOARD_FAB2(SCH_1):M_B_DQ<25>
   38  M_B_DQ<24>     DQ<24>  @BASEBOARD_FAB2_LIB.BASEBOARD_FAB2(SCH_1):M_B_DQ<24>
  177  M_B_DQ<23>     DQ<23>  @BASEBOARD_FAB2_LIB.BASEBOARD_FAB2(SCH_1):M_B_DQ<23>
   32  M_B_DQ<22>     DQ<22>  @BASEBOARD_FAB2_LIB.BASEBOARD_FAB2(SCH_1):M_B_DQ<22>
  170  M_B_DQ<21>     DQ<21>  @BASEBOARD_FAB2_LIB.BASEBOARD_FAB2(SCH_1):M_B_DQ<21>
   25  M_B_DQ<20>     DQ<20>  @BASEBOARD_FAB2_LIB.BASEBOARD_FAB2(SCH_1):M_B_DQ<20>
  150  M_B_DQ<1>      DQ<1>  @BASEBOARD_FAB2_LIB.BASEBOARD_FAB2(SCH_1):M_B_DQ<1>
  179  M_B_DQ<19>     DQ<19>  @BASEBOARD_FAB2_LIB.BASEBOARD_FAB2(SCH_1):M_B_DQ<19>
   34  M_B_DQ<18>     DQ<18>  @BASEBOARD_FAB2_LIB.BASEBOARD_FAB2(SCH_1):M_B_DQ<18>
  172  M_B_DQ<17>     DQ<17>  @BASEBOARD_FAB2_LIB.BASEBOARD_FAB2(SCH_1):M_B_DQ<17>
   27  M_B_DQ<16>     DQ<16>  @BASEBOARD_FAB2_LIB.BASEBOARD_FAB2(SCH_1):M_B_DQ<16>
  166  M_B_DQ<15>     DQ<15>  @BASEBOARD_FAB2_LIB.BASEBOARD_FAB2(SCH_1):M_B_DQ<15>
   21  M_B_DQ<14>     DQ<14>  @BASEBOARD_FAB2_LIB.BASEBOARD_FAB2(SCH_1):M_B_DQ<14>
  159  M_B_DQ<13>     DQ<13>  @BASEBOARD_FAB2_LIB.BASEBOARD_FAB2(SCH_1):M_B_DQ<13>
   14  M_B_DQ<12>     DQ<12>  @BASEBOARD_FAB2_LIB.BASEBOARD_FAB2(SCH_1):M_B_DQ<12>
  168  M_B_DQ<11>     DQ<11>  @BASEBOARD_FAB2_LIB.BASEBOARD_FAB2(SCH_1):M_B_DQ<11>
   23  M_B_DQ<10>     DQ<10>  @BASEBOARD_FAB2_LIB.BASEBOARD_FAB2(SCH_1):M_B_DQ<10>
    5  M_B_DQ<0>      DQ<0>  @BASEBOARD_FAB2_LIB.BASEBOARD_FAB2(SCH_1):M_B_DQ<0>
  237  M_B_CS_N<7>    S3_N_C<1>  @BASEBOARD_FAB2_LIB.BASEBOARD_FAB2(SCH_1):M_B_CS_N<7>
   93  M_B_CS_N<6>    S2_N_C<0>  @BASEBOARD_FAB2_LIB.BASEBOARD_FAB2(SCH_1):M_B_CS_N<6>
   89  M_B_CS_N<5>     S1_N  @BASEBOARD_FAB2_LIB.BASEBOARD_FAB2(SCH_1):M_B_CS_N<5>
   84  M_B_CS_N<4>     S0_N  @BASEBOARD_FAB2_LIB.BASEBOARD_FAB2(SCH_1):M_B_CS_N<4>
  218  M_B_CLK_DP<3>   CK1P  @BASEBOARD_FAB2_LIB.BASEBOARD_FAB2(SCH_1):M_B_CLK_DP<3>
   74  M_B_CLK_DP<2>   CK0P  @BASEBOARD_FAB2_LIB.BASEBOARD_FAB2(SCH_1):M_B_CLK_DP<2>
  219  M_B_CLK_DN<3>   CK1N  @BASEBOARD_FAB2_LIB.BASEBOARD_FAB2(SCH_1):M_B_CLK_DN<3>
   75  M_B_CLK_DN<2>   CK0N  @BASEBOARD_FAB2_LIB.BASEBOARD_FAB2(SCH_1):M_B_CLK_DN<2>
  203  M_B_CKE<3>     CKE<1>  @BASEBOARD_FAB2_LIB.BASEBOARD_FAB2(SCH_1):M_B_CKE<3>
   60  M_B_CKE<2>     CKE<0>  @BASEBOARD_FAB2_LIB.BASEBOARD_FAB2(SCH_1):M_B_CKE<2>
  235  M_B_C<2>        C<2>  @BASEBOARD_FAB2_LIB.BASEBOARD_FAB2(SCH_1):M_B_C<2>
  207  M_B_BG<1>      BG<1>  @BASEBOARD_FAB2_LIB.BASEBOARD_FAB2(SCH_1):M_B_BG<1>
   63  M_B_BG<0>      BG<0>  @BASEBOARD_FAB2_LIB.BASEBOARD_FAB2(SCH_1):M_B_BG<0>
  224  M_B_BA<1>      BA<1>  @BASEBOARD_FAB2_LIB.BASEBOARD_FAB2(SCH_1):M_B_BA<1>
   81  M_B_BA<0>      BA<0>  @BASEBOARD_FAB2_LIB.BASEBOARD_FAB2(SCH_1):M_B_BA<0>
  208  M_B_ALERT_N    ALERT_N  @BASEBOARD_FAB2_LIB.BASEBOARD_FAB2(SCH_1):M_B_ALERT_N
   62  M_B_ACT_N      ACT_N  @BASEBOARD_FAB2_LIB.BASEBOARD_FAB2(SCH_1):M_B_ACT_N
   58  M_ABC_RST_N    RESET_N  @BASEBOARD_FAB2_LIB.BASEBOARD_FAB2(SCH_1):M_ABC_RST_N
  238  GND            SA<2>  @BASEBOARD_FAB2_LIB.BASEBOARD_FAB2(SCH_1):GND
   78  FM_DIMM_EVENT_COD_N  EVENT_N  @BASEBOARD_FAB2_LIB.BASEBOARD_FAB2(SCH_1):FM_DIMM_EVENT_COD_N
  230  FM_ADR_COMPLETE_ABC_N  SAVE_N_NC  @BASEBOARD_FAB2_LIB.BASEBOARD_FAB2(SCH_1):FM_ADR_COMPLETE_ABC_N

SCONN288_H44441003_PIP  I171  J6U2   [SCONN288_H44441003_PIP-SCONN,HA]
   77  PVTT_ABC       VTT<1>  @BASEBOARD_FAB2_LIB.BASEBOARD_FAB2(SCH_1):PVTT_ABC
  221  PVTT_ABC       VTT<0>  @BASEBOARD_FAB2_LIB.BASEBOARD_FAB2(SCH_1):PVTT_ABC
  142  PVPP_ABC       VPP<4>  @BASEBOARD_FAB2_LIB.BASEBOARD_FAB2(SCH_1):PVPP_ABC
  143  PVPP_ABC       VPP<3>  @BASEBOARD_FAB2_LIB.BASEBOARD_FAB2(SCH_1):PVPP_ABC
  288  PVPP_ABC       VPP<2>  @BASEBOARD_FAB2_LIB.BASEBOARD_FAB2(SCH_1):PVPP_ABC
  286  PVPP_ABC       VPP<1>  @BASEBOARD_FAB2_LIB.BASEBOARD_FAB2(SCH_1):PVPP_ABC
  287  PVPP_ABC       VPP<0>  @BASEBOARD_FAB2_LIB.BASEBOARD_FAB2(SCH_1):PVPP_ABC
   59  PVDDQ_ABC      VDD<25>  @BASEBOARD_FAB2_LIB.BASEBOARD_FAB2(SCH_1):PVDDQ_ABC
   61  PVDDQ_ABC      VDD<24>  @BASEBOARD_FAB2_LIB.BASEBOARD_FAB2(SCH_1):PVDDQ_ABC
   64  PVDDQ_ABC      VDD<23>  @BASEBOARD_FAB2_LIB.BASEBOARD_FAB2(SCH_1):PVDDQ_ABC
   67  PVDDQ_ABC      VDD<22>  @BASEBOARD_FAB2_LIB.BASEBOARD_FAB2(SCH_1):PVDDQ_ABC
   70  PVDDQ_ABC      VDD<21>  @BASEBOARD_FAB2_LIB.BASEBOARD_FAB2(SCH_1):PVDDQ_ABC
   73  PVDDQ_ABC      VDD<20>  @BASEBOARD_FAB2_LIB.BASEBOARD_FAB2(SCH_1):PVDDQ_ABC
   76  PVDDQ_ABC      VDD<19>  @BASEBOARD_FAB2_LIB.BASEBOARD_FAB2(SCH_1):PVDDQ_ABC
   80  PVDDQ_ABC      VDD<18>  @BASEBOARD_FAB2_LIB.BASEBOARD_FAB2(SCH_1):PVDDQ_ABC
   83  PVDDQ_ABC      VDD<17>  @BASEBOARD_FAB2_LIB.BASEBOARD_FAB2(SCH_1):PVDDQ_ABC
   85  PVDDQ_ABC      VDD<16>  @BASEBOARD_FAB2_LIB.BASEBOARD_FAB2(SCH_1):PVDDQ_ABC
   88  PVDDQ_ABC      VDD<15>  @BASEBOARD_FAB2_LIB.BASEBOARD_FAB2(SCH_1):PVDDQ_ABC
   90  PVDDQ_ABC      VDD<14>  @BASEBOARD_FAB2_LIB.BASEBOARD_FAB2(SCH_1):PVDDQ_ABC
   92  PVDDQ_ABC      VDD<13>  @BASEBOARD_FAB2_LIB.BASEBOARD_FAB2(SCH_1):PVDDQ_ABC
  204  PVDDQ_ABC      VDD<12>  @BASEBOARD_FAB2_LIB.BASEBOARD_FAB2(SCH_1):PVDDQ_ABC
  206  PVDDQ_ABC      VDD<11>  @BASEBOARD_FAB2_LIB.BASEBOARD_FAB2(SCH_1):PVDDQ_ABC
  209  PVDDQ_ABC      VDD<10>  @BASEBOARD_FAB2_LIB.BASEBOARD_FAB2(SCH_1):PVDDQ_ABC
  212  PVDDQ_ABC      VDD<9>  @BASEBOARD_FAB2_LIB.BASEBOARD_FAB2(SCH_1):PVDDQ_ABC
  215  PVDDQ_ABC      VDD<8>  @BASEBOARD_FAB2_LIB.BASEBOARD_FAB2(SCH_1):PVDDQ_ABC
  217  PVDDQ_ABC      VDD<7>  @BASEBOARD_FAB2_LIB.BASEBOARD_FAB2(SCH_1):PVDDQ_ABC
  220  PVDDQ_ABC      VDD<6>  @BASEBOARD_FAB2_LIB.BASEBOARD_FAB2(SCH_1):PVDDQ_ABC
  223  PVDDQ_ABC      VDD<5>  @BASEBOARD_FAB2_LIB.BASEBOARD_FAB2(SCH_1):PVDDQ_ABC
  226  PVDDQ_ABC      VDD<4>  @BASEBOARD_FAB2_LIB.BASEBOARD_FAB2(SCH_1):PVDDQ_ABC
  229  PVDDQ_ABC      VDD<3>  @BASEBOARD_FAB2_LIB.BASEBOARD_FAB2(SCH_1):PVDDQ_ABC
  231  PVDDQ_ABC      VDD<2>  @BASEBOARD_FAB2_LIB.BASEBOARD_FAB2(SCH_1):PVDDQ_ABC
  233  PVDDQ_ABC      VDD<1>  @BASEBOARD_FAB2_LIB.BASEBOARD_FAB2(SCH_1):PVDDQ_ABC
  236  PVDDQ_ABC      VDD<0>  @BASEBOARD_FAB2_LIB.BASEBOARD_FAB2(SCH_1):PVDDQ_ABC
    1  P12V_NVDIMM_ABC  12V<1>  @BASEBOARD_FAB2_LIB.BASEBOARD_FAB2(SCH_1):P12V_NVDIMM_ABC
  145  P12V_NVDIMM_ABC  12V<0>  @BASEBOARD_FAB2_LIB.BASEBOARD_FAB2(SCH_1):P12V_NVDIMM_ABC

SCONN288_H44441003_PIP  I43  J6U2   [SCONN288_H44441003_PIP-SCONN,HA]
    2  GND            VSS<93>  @BASEBOARD_FAB2_LIB.BASEBOARD_FAB2(SCH_1):GND
    4  GND            VSS<92>  @BASEBOARD_FAB2_LIB.BASEBOARD_FAB2(SCH_1):GND
    6  GND            VSS<91>  @BASEBOARD_FAB2_LIB.BASEBOARD_FAB2(SCH_1):GND
    9  GND            VSS<90>  @BASEBOARD_FAB2_LIB.BASEBOARD_FAB2(SCH_1):GND
   11  GND            VSS<89>  @BASEBOARD_FAB2_LIB.BASEBOARD_FAB2(SCH_1):GND
   13  GND            VSS<88>  @BASEBOARD_FAB2_LIB.BASEBOARD_FAB2(SCH_1):GND
   15  GND            VSS<87>  @BASEBOARD_FAB2_LIB.BASEBOARD_FAB2(SCH_1):GND
   17  GND            VSS<86>  @BASEBOARD_FAB2_LIB.BASEBOARD_FAB2(SCH_1):GND
   20  GND            VSS<85>  @BASEBOARD_FAB2_LIB.BASEBOARD_FAB2(SCH_1):GND
   22  GND            VSS<84>  @BASEBOARD_FAB2_LIB.BASEBOARD_FAB2(SCH_1):GND
   24  GND            VSS<83>  @BASEBOARD_FAB2_LIB.BASEBOARD_FAB2(SCH_1):GND
   26  GND            VSS<82>  @BASEBOARD_FAB2_LIB.BASEBOARD_FAB2(SCH_1):GND
   28  GND            VSS<81>  @BASEBOARD_FAB2_LIB.BASEBOARD_FAB2(SCH_1):GND
   31  GND            VSS<80>  @BASEBOARD_FAB2_LIB.BASEBOARD_FAB2(SCH_1):GND
   33  GND            VSS<79>  @BASEBOARD_FAB2_LIB.BASEBOARD_FAB2(SCH_1):GND
   35  GND            VSS<78>  @BASEBOARD_FAB2_LIB.BASEBOARD_FAB2(SCH_1):GND
   37  GND            VSS<77>  @BASEBOARD_FAB2_LIB.BASEBOARD_FAB2(SCH_1):GND
   39  GND            VSS<76>  @BASEBOARD_FAB2_LIB.BASEBOARD_FAB2(SCH_1):GND
   42  GND            VSS<75>  @BASEBOARD_FAB2_LIB.BASEBOARD_FAB2(SCH_1):GND
   44  GND            VSS<74>  @BASEBOARD_FAB2_LIB.BASEBOARD_FAB2(SCH_1):GND
   46  GND            VSS<73>  @BASEBOARD_FAB2_LIB.BASEBOARD_FAB2(SCH_1):GND
   48  GND            VSS<72>  @BASEBOARD_FAB2_LIB.BASEBOARD_FAB2(SCH_1):GND
   50  GND            VSS<71>  @BASEBOARD_FAB2_LIB.BASEBOARD_FAB2(SCH_1):GND
   53  GND            VSS<70>  @BASEBOARD_FAB2_LIB.BASEBOARD_FAB2(SCH_1):GND
   55  GND            VSS<69>  @BASEBOARD_FAB2_LIB.BASEBOARD_FAB2(SCH_1):GND
   57  GND            VSS<68>  @BASEBOARD_FAB2_LIB.BASEBOARD_FAB2(SCH_1):GND
   94  GND            VSS<67>  @BASEBOARD_FAB2_LIB.BASEBOARD_FAB2(SCH_1):GND
   96  GND            VSS<66>  @BASEBOARD_FAB2_LIB.BASEBOARD_FAB2(SCH_1):GND
   98  GND            VSS<65>  @BASEBOARD_FAB2_LIB.BASEBOARD_FAB2(SCH_1):GND
  101  GND            VSS<64>  @BASEBOARD_FAB2_LIB.BASEBOARD_FAB2(SCH_1):GND
  103  GND            VSS<63>  @BASEBOARD_FAB2_LIB.BASEBOARD_FAB2(SCH_1):GND
  105  GND            VSS<62>  @BASEBOARD_FAB2_LIB.BASEBOARD_FAB2(SCH_1):GND
  107  GND            VSS<61>  @BASEBOARD_FAB2_LIB.BASEBOARD_FAB2(SCH_1):GND
  109  GND            VSS<60>  @BASEBOARD_FAB2_LIB.BASEBOARD_FAB2(SCH_1):GND
  112  GND            VSS<59>  @BASEBOARD_FAB2_LIB.BASEBOARD_FAB2(SCH_1):GND
  114  GND            VSS<58>  @BASEBOARD_FAB2_LIB.BASEBOARD_FAB2(SCH_1):GND
  116  GND            VSS<57>  @BASEBOARD_FAB2_LIB.BASEBOARD_FAB2(SCH_1):GND
  118  GND            VSS<56>  @BASEBOARD_FAB2_LIB.BASEBOARD_FAB2(SCH_1):GND
  120  GND            VSS<55>  @BASEBOARD_FAB2_LIB.BASEBOARD_FAB2(SCH_1):GND
  123  GND            VSS<54>  @BASEBOARD_FAB2_LIB.BASEBOARD_FAB2(SCH_1):GND
  125  GND            VSS<53>  @BASEBOARD_FAB2_LIB.BASEBOARD_FAB2(SCH_1):GND
  127  GND            VSS<52>  @BASEBOARD_FAB2_LIB.BASEBOARD_FAB2(SCH_1):GND
  129  GND            VSS<51>  @BASEBOARD_FAB2_LIB.BASEBOARD_FAB2(SCH_1):GND
  131  GND            VSS<50>  @BASEBOARD_FAB2_LIB.BASEBOARD_FAB2(SCH_1):GND
  134  GND            VSS<49>  @BASEBOARD_FAB2_LIB.BASEBOARD_FAB2(SCH_1):GND
  136  GND            VSS<48>  @BASEBOARD_FAB2_LIB.BASEBOARD_FAB2(SCH_1):GND
  138  GND            VSS<47>  @BASEBOARD_FAB2_LIB.BASEBOARD_FAB2(SCH_1):GND
  147  GND            VSS<46>  @BASEBOARD_FAB2_LIB.BASEBOARD_FAB2(SCH_1):GND
  149  GND            VSS<45>  @BASEBOARD_FAB2_LIB.BASEBOARD_FAB2(SCH_1):GND
  151  GND            VSS<44>  @BASEBOARD_FAB2_LIB.BASEBOARD_FAB2(SCH_1):GND
  154  GND            VSS<43>  @BASEBOARD_FAB2_LIB.BASEBOARD_FAB2(SCH_1):GND
  156  GND            VSS<42>  @BASEBOARD_FAB2_LIB.BASEBOARD_FAB2(SCH_1):GND
  158  GND            VSS<41>  @BASEBOARD_FAB2_LIB.BASEBOARD_FAB2(SCH_1):GND
  160  GND            VSS<40>  @BASEBOARD_FAB2_LIB.BASEBOARD_FAB2(SCH_1):GND
  162  GND            VSS<39>  @BASEBOARD_FAB2_LIB.BASEBOARD_FAB2(SCH_1):GND
  165  GND            VSS<38>  @BASEBOARD_FAB2_LIB.BASEBOARD_FAB2(SCH_1):GND
  167  GND            VSS<37>  @BASEBOARD_FAB2_LIB.BASEBOARD_FAB2(SCH_1):GND
  169  GND            VSS<36>  @BASEBOARD_FAB2_LIB.BASEBOARD_FAB2(SCH_1):GND
  171  GND            VSS<35>  @BASEBOARD_FAB2_LIB.BASEBOARD_FAB2(SCH_1):GND
  173  GND            VSS<34>  @BASEBOARD_FAB2_LIB.BASEBOARD_FAB2(SCH_1):GND
  176  GND            VSS<33>  @BASEBOARD_FAB2_LIB.BASEBOARD_FAB2(SCH_1):GND
  178  GND            VSS<32>  @BASEBOARD_FAB2_LIB.BASEBOARD_FAB2(SCH_1):GND
  180  GND            VSS<31>  @BASEBOARD_FAB2_LIB.BASEBOARD_FAB2(SCH_1):GND
  182  GND            VSS<30>  @BASEBOARD_FAB2_LIB.BASEBOARD_FAB2(SCH_1):GND
  184  GND            VSS<29>  @BASEBOARD_FAB2_LIB.BASEBOARD_FAB2(SCH_1):GND
  187  GND            VSS<28>  @BASEBOARD_FAB2_LIB.BASEBOARD_FAB2(SCH_1):GND
  189  GND            VSS<27>  @BASEBOARD_FAB2_LIB.BASEBOARD_FAB2(SCH_1):GND
  191  GND            VSS<26>  @BASEBOARD_FAB2_LIB.BASEBOARD_FAB2(SCH_1):GND
  193  GND            VSS<25>  @BASEBOARD_FAB2_LIB.BASEBOARD_FAB2(SCH_1):GND
  195  GND            VSS<24>  @BASEBOARD_FAB2_LIB.BASEBOARD_FAB2(SCH_1):GND
  198  GND            VSS<23>  @BASEBOARD_FAB2_LIB.BASEBOARD_FAB2(SCH_1):GND
  200  GND            VSS<22>  @BASEBOARD_FAB2_LIB.BASEBOARD_FAB2(SCH_1):GND
  202  GND            VSS<21>  @BASEBOARD_FAB2_LIB.BASEBOARD_FAB2(SCH_1):GND
  239  GND            VSS<20>  @BASEBOARD_FAB2_LIB.BASEBOARD_FAB2(SCH_1):GND
  241  GND            VSS<19>  @BASEBOARD_FAB2_LIB.BASEBOARD_FAB2(SCH_1):GND
  243  GND            VSS<18>  @BASEBOARD_FAB2_LIB.BASEBOARD_FAB2(SCH_1):GND
  246  GND            VSS<17>  @BASEBOARD_FAB2_LIB.BASEBOARD_FAB2(SCH_1):GND
  248  GND            VSS<16>  @BASEBOARD_FAB2_LIB.BASEBOARD_FAB2(SCH_1):GND
  250  GND            VSS<15>  @BASEBOARD_FAB2_LIB.BASEBOARD_FAB2(SCH_1):GND
  252  GND            VSS<14>  @BASEBOARD_FAB2_LIB.BASEBOARD_FAB2(SCH_1):GND
  254  GND            VSS<13>  @BASEBOARD_FAB2_LIB.BASEBOARD_FAB2(SCH_1):GND
  257  GND            VSS<12>  @BASEBOARD_FAB2_LIB.BASEBOARD_FAB2(SCH_1):GND
  259  GND            VSS<11>  @BASEBOARD_FAB2_LIB.BASEBOARD_FAB2(SCH_1):GND
  261  GND            VSS<10>  @BASEBOARD_FAB2_LIB.BASEBOARD_FAB2(SCH_1):GND
  263  GND            VSS<9>  @BASEBOARD_FAB2_LIB.BASEBOARD_FAB2(SCH_1):GND
  265  GND            VSS<8>  @BASEBOARD_FAB2_LIB.BASEBOARD_FAB2(SCH_1):GND
  268  GND            VSS<7>  @BASEBOARD_FAB2_LIB.BASEBOARD_FAB2(SCH_1):GND
  270  GND            VSS<6>  @BASEBOARD_FAB2_LIB.BASEBOARD_FAB2(SCH_1):GND
  272  GND            VSS<5>  @BASEBOARD_FAB2_LIB.BASEBOARD_FAB2(SCH_1):GND
  274  GND            VSS<4>  @BASEBOARD_FAB2_LIB.BASEBOARD_FAB2(SCH_1):GND
  276  GND            VSS<3>  @BASEBOARD_FAB2_LIB.BASEBOARD_FAB2(SCH_1):GND
  279  GND            VSS<2>  @BASEBOARD_FAB2_LIB.BASEBOARD_FAB2(SCH_1):GND
  281  GND            VSS<1>  @BASEBOARD_FAB2_LIB.BASEBOARD_FAB2(SCH_1):GND
  283  GND            VSS<0>  @BASEBOARD_FAB2_LIB.BASEBOARD_FAB2(SCH_1):GND

SCONN288_H44441003_PIP  I61  J6U2   [SCONN288_H44441003_PIP-SCONN,HA]
    7  M_C_DQS_DP<9>  DQS9P  @BASEBOARD_FAB2_LIB.BASEBOARD_FAB2(SCH_1):M_C_DQS_DP<9>
  197  M_C_DQS_DP<8>  DQS8P  @BASEBOARD_FAB2_LIB.BASEBOARD_FAB2(SCH_1):M_C_DQS_DP<8>
  278  M_C_DQS_DP<7>  DQS7P  @BASEBOARD_FAB2_LIB.BASEBOARD_FAB2(SCH_1):M_C_DQS_DP<7>
  267  M_C_DQS_DP<6>  DQS6P  @BASEBOARD_FAB2_LIB.BASEBOARD_FAB2(SCH_1):M_C_DQS_DP<6>
  256  M_C_DQS_DP<5>  DQS5P  @BASEBOARD_FAB2_LIB.BASEBOARD_FAB2(SCH_1):M_C_DQS_DP<5>
  245  M_C_DQS_DP<4>  DQS4P  @BASEBOARD_FAB2_LIB.BASEBOARD_FAB2(SCH_1):M_C_DQS_DP<4>
  186  M_C_DQS_DP<3>  DQS3P  @BASEBOARD_FAB2_LIB.BASEBOARD_FAB2(SCH_1):M_C_DQS_DP<3>
  175  M_C_DQS_DP<2>  DQS2P  @BASEBOARD_FAB2_LIB.BASEBOARD_FAB2(SCH_1):M_C_DQS_DP<2>
  164  M_C_DQS_DP<1>  DQS1P  @BASEBOARD_FAB2_LIB.BASEBOARD_FAB2(SCH_1):M_C_DQS_DP<1>
   51  M_C_DQS_DP<17>  DQS17P  @BASEBOARD_FAB2_LIB.BASEBOARD_FAB2(SCH_1):M_C_DQS_DP<17>
  132  M_C_DQS_DP<16>  DQS16P  @BASEBOARD_FAB2_LIB.BASEBOARD_FAB2(SCH_1):M_C_DQS_DP<16>
  121  M_C_DQS_DP<15>  DQS15P  @BASEBOARD_FAB2_LIB.BASEBOARD_FAB2(SCH_1):M_C_DQS_DP<15>
  110  M_C_DQS_DP<14>  DQS14P  @BASEBOARD_FAB2_LIB.BASEBOARD_FAB2(SCH_1):M_C_DQS_DP<14>
   99  M_C_DQS_DP<13>  DQS13P  @BASEBOARD_FAB2_LIB.BASEBOARD_FAB2(SCH_1):M_C_DQS_DP<13>
   40  M_C_DQS_DP<12>  DQS12P  @BASEBOARD_FAB2_LIB.BASEBOARD_FAB2(SCH_1):M_C_DQS_DP<12>
   29  M_C_DQS_DP<11>  DQS11P  @BASEBOARD_FAB2_LIB.BASEBOARD_FAB2(SCH_1):M_C_DQS_DP<11>
   18  M_C_DQS_DP<10>  DQS10P  @BASEBOARD_FAB2_LIB.BASEBOARD_FAB2(SCH_1):M_C_DQS_DP<10>
  153  M_C_DQS_DP<0>  DQS0P  @BASEBOARD_FAB2_LIB.BASEBOARD_FAB2(SCH_1):M_C_DQS_DP<0>
    8  M_C_DQS_DN<9>  DQS9N  @BASEBOARD_FAB2_LIB.BASEBOARD_FAB2(SCH_1):M_C_DQS_DN<9>
  196  M_C_DQS_DN<8>  DQS8N  @BASEBOARD_FAB2_LIB.BASEBOARD_FAB2(SCH_1):M_C_DQS_DN<8>
  277  M_C_DQS_DN<7>  DQS7N  @BASEBOARD_FAB2_LIB.BASEBOARD_FAB2(SCH_1):M_C_DQS_DN<7>
  266  M_C_DQS_DN<6>  DQS6N  @BASEBOARD_FAB2_LIB.BASEBOARD_FAB2(SCH_1):M_C_DQS_DN<6>
  255  M_C_DQS_DN<5>  DQS5N  @BASEBOARD_FAB2_LIB.BASEBOARD_FAB2(SCH_1):M_C_DQS_DN<5>
  244  M_C_DQS_DN<4>  DQS4N  @BASEBOARD_FAB2_LIB.BASEBOARD_FAB2(SCH_1):M_C_DQS_DN<4>
  185  M_C_DQS_DN<3>  DQS3N  @BASEBOARD_FAB2_LIB.BASEBOARD_FAB2(SCH_1):M_C_DQS_DN<3>
  174  M_C_DQS_DN<2>  DQS2N  @BASEBOARD_FAB2_LIB.BASEBOARD_FAB2(SCH_1):M_C_DQS_DN<2>
  163  M_C_DQS_DN<1>  DQS1N  @BASEBOARD_FAB2_LIB.BASEBOARD_FAB2(SCH_1):M_C_DQS_DN<1>
   52  M_C_DQS_DN<17>  DQS17N  @BASEBOARD_FAB2_LIB.BASEBOARD_FAB2(SCH_1):M_C_DQS_DN<17>
  133  M_C_DQS_DN<16>  DQS16N  @BASEBOARD_FAB2_LIB.BASEBOARD_FAB2(SCH_1):M_C_DQS_DN<16>
  122  M_C_DQS_DN<15>  DQS15N  @BASEBOARD_FAB2_LIB.BASEBOARD_FAB2(SCH_1):M_C_DQS_DN<15>
  111  M_C_DQS_DN<14>  DQS14N  @BASEBOARD_FAB2_LIB.BASEBOARD_FAB2(SCH_1):M_C_DQS_DN<14>
  100  M_C_DQS_DN<13>  DQS13N  @BASEBOARD_FAB2_LIB.BASEBOARD_FAB2(SCH_1):M_C_DQS_DN<13>
   41  M_C_DQS_DN<12>  DQS12N  @BASEBOARD_FAB2_LIB.BASEBOARD_FAB2(SCH_1):M_C_DQS_DN<12>
   30  M_C_DQS_DN<11>  DQS11N  @BASEBOARD_FAB2_LIB.BASEBOARD_FAB2(SCH_1):M_C_DQS_DN<11>
   19  M_C_DQS_DN<10>  DQS10N  @BASEBOARD_FAB2_LIB.BASEBOARD_FAB2(SCH_1):M_C_DQS_DN<10>
  152  M_C_DQS_DN<0>  DQS0N  @BASEBOARD_FAB2_LIB.BASEBOARD_FAB2(SCH_1):M_C_DQS_DN<0>

SCONN288_H44441003_PIP  I111  J6U2   [SCONN288_H44441003_PIP-SCONN,HA]
  144  TP_CH_C_DIMM_C1_RFU_2  RFU<2>  @BASEBOARD_FAB2_LIB.BASEBOARD_FAB2(SCH_1):TP_CH_C_DIMM_C1_RFU_2
  227  TP_CH_C_DIMM_C1_RFU_1  RFU<1>  @BASEBOARD_FAB2_LIB.BASEBOARD_FAB2(SCH_1):TP_CH_C_DIMM_C1_RFU_1
  205  TP_CH_C_DIMM_C1_RFU_0  RFU<0>  @BASEBOARD_FAB2_LIB.BASEBOARD_FAB2(SCH_1):TP_CH_C_DIMM_C1_RFU_0
  285  SMB_DDR_ABC_VPP_SDA    SDA  @BASEBOARD_FAB2_LIB.BASEBOARD_FAB2(SCH_1):SMB_DDR_ABC_VPP_SDA
  141  SMB_DDR_ABC_VPP_SCL    SCL  @BASEBOARD_FAB2_LIB.BASEBOARD_FAB2(SCH_1):SMB_DDR_ABC_VPP_SCL
  284  PVPP_ABC       VDDSPD  @BASEBOARD_FAB2_LIB.BASEBOARD_FAB2(SCH_1):PVPP_ABC
  238  PVPP_ABC       SA<2>  @BASEBOARD_FAB2_LIB.BASEBOARD_FAB2(SCH_1):PVPP_ABC
  139  PVPP_ABC       SA<0>  @BASEBOARD_FAB2_LIB.BASEBOARD_FAB2(SCH_1):PVPP_ABC
  146  M_C_VREF       VREFCA  @BASEBOARD_FAB2_LIB.BASEBOARD_FAB2(SCH_1):M_C_VREF
  222  M_C_PAR          PAR  @BASEBOARD_FAB2_LIB.BASEBOARD_FAB2(SCH_1):M_C_PAR
   91  M_C_ODT<3>     ODT<1>  @BASEBOARD_FAB2_LIB.BASEBOARD_FAB2(SCH_1):M_C_ODT<3>
   87  M_C_ODT<2>     ODT<0>  @BASEBOARD_FAB2_LIB.BASEBOARD_FAB2(SCH_1):M_C_ODT<2>
   66  M_C_MA<9>         A9  @BASEBOARD_FAB2_LIB.BASEBOARD_FAB2(SCH_1):M_C_MA<9>
   68  M_C_MA<8>         A8  @BASEBOARD_FAB2_LIB.BASEBOARD_FAB2(SCH_1):M_C_MA<8>
  211  M_C_MA<7>         A7  @BASEBOARD_FAB2_LIB.BASEBOARD_FAB2(SCH_1):M_C_MA<7>
   69  M_C_MA<6>         A6  @BASEBOARD_FAB2_LIB.BASEBOARD_FAB2(SCH_1):M_C_MA<6>
  213  M_C_MA<5>         A5  @BASEBOARD_FAB2_LIB.BASEBOARD_FAB2(SCH_1):M_C_MA<5>
  214  M_C_MA<4>         A4  @BASEBOARD_FAB2_LIB.BASEBOARD_FAB2(SCH_1):M_C_MA<4>
   71  M_C_MA<3>         A3  @BASEBOARD_FAB2_LIB.BASEBOARD_FAB2(SCH_1):M_C_MA<3>
  216  M_C_MA<2>         A2  @BASEBOARD_FAB2_LIB.BASEBOARD_FAB2(SCH_1):M_C_MA<2>
   72  M_C_MA<1>         A1  @BASEBOARD_FAB2_LIB.BASEBOARD_FAB2(SCH_1):M_C_MA<1>
  234  M_C_MA<17>       A17  @BASEBOARD_FAB2_LIB.BASEBOARD_FAB2(SCH_1):M_C_MA<17>
   82  M_C_MA<16>     A16_RAS_N  @BASEBOARD_FAB2_LIB.BASEBOARD_FAB2(SCH_1):M_C_MA<16>
   86  M_C_MA<15>     A15_CAS_N  @BASEBOARD_FAB2_LIB.BASEBOARD_FAB2(SCH_1):M_C_MA<15>
  228  M_C_MA<14>     A14_WE_N  @BASEBOARD_FAB2_LIB.BASEBOARD_FAB2(SCH_1):M_C_MA<14>
  232  M_C_MA<13>       A13  @BASEBOARD_FAB2_LIB.BASEBOARD_FAB2(SCH_1):M_C_MA<13>
   65  M_C_MA<12>       A12  @BASEBOARD_FAB2_LIB.BASEBOARD_FAB2(SCH_1):M_C_MA<12>
  210  M_C_MA<11>       A11  @BASEBOARD_FAB2_LIB.BASEBOARD_FAB2(SCH_1):M_C_MA<11>
  225  M_C_MA<10>       A10  @BASEBOARD_FAB2_LIB.BASEBOARD_FAB2(SCH_1):M_C_MA<10>
   79  M_C_MA<0>         A0  @BASEBOARD_FAB2_LIB.BASEBOARD_FAB2(SCH_1):M_C_MA<0>
  199  M_C_ECC<7>     CB<7>  @BASEBOARD_FAB2_LIB.BASEBOARD_FAB2(SCH_1):M_C_ECC<7>
   54  M_C_ECC<6>     CB<6>  @BASEBOARD_FAB2_LIB.BASEBOARD_FAB2(SCH_1):M_C_ECC<6>
  192  M_C_ECC<5>     CB<5>  @BASEBOARD_FAB2_LIB.BASEBOARD_FAB2(SCH_1):M_C_ECC<5>
   47  M_C_ECC<4>     CB<4>  @BASEBOARD_FAB2_LIB.BASEBOARD_FAB2(SCH_1):M_C_ECC<4>
  201  M_C_ECC<3>     CB<3>  @BASEBOARD_FAB2_LIB.BASEBOARD_FAB2(SCH_1):M_C_ECC<3>
   56  M_C_ECC<2>     CB<2>  @BASEBOARD_FAB2_LIB.BASEBOARD_FAB2(SCH_1):M_C_ECC<2>
  194  M_C_ECC<1>     CB<1>  @BASEBOARD_FAB2_LIB.BASEBOARD_FAB2(SCH_1):M_C_ECC<1>
   49  M_C_ECC<0>     CB<0>  @BASEBOARD_FAB2_LIB.BASEBOARD_FAB2(SCH_1):M_C_ECC<0>
  161  M_C_DQ<9>      DQ<9>  @BASEBOARD_FAB2_LIB.BASEBOARD_FAB2(SCH_1):M_C_DQ<9>
   16  M_C_DQ<8>      DQ<8>  @BASEBOARD_FAB2_LIB.BASEBOARD_FAB2(SCH_1):M_C_DQ<8>
  155  M_C_DQ<7>      DQ<7>  @BASEBOARD_FAB2_LIB.BASEBOARD_FAB2(SCH_1):M_C_DQ<7>
   10  M_C_DQ<6>      DQ<6>  @BASEBOARD_FAB2_LIB.BASEBOARD_FAB2(SCH_1):M_C_DQ<6>
  280  M_C_DQ<63>     DQ<63>  @BASEBOARD_FAB2_LIB.BASEBOARD_FAB2(SCH_1):M_C_DQ<63>
  135  M_C_DQ<62>     DQ<62>  @BASEBOARD_FAB2_LIB.BASEBOARD_FAB2(SCH_1):M_C_DQ<62>
  273  M_C_DQ<61>     DQ<61>  @BASEBOARD_FAB2_LIB.BASEBOARD_FAB2(SCH_1):M_C_DQ<61>
  128  M_C_DQ<60>     DQ<60>  @BASEBOARD_FAB2_LIB.BASEBOARD_FAB2(SCH_1):M_C_DQ<60>
  148  M_C_DQ<5>      DQ<5>  @BASEBOARD_FAB2_LIB.BASEBOARD_FAB2(SCH_1):M_C_DQ<5>
  282  M_C_DQ<59>     DQ<59>  @BASEBOARD_FAB2_LIB.BASEBOARD_FAB2(SCH_1):M_C_DQ<59>
  137  M_C_DQ<58>     DQ<58>  @BASEBOARD_FAB2_LIB.BASEBOARD_FAB2(SCH_1):M_C_DQ<58>
  275  M_C_DQ<57>     DQ<57>  @BASEBOARD_FAB2_LIB.BASEBOARD_FAB2(SCH_1):M_C_DQ<57>
  130  M_C_DQ<56>     DQ<56>  @BASEBOARD_FAB2_LIB.BASEBOARD_FAB2(SCH_1):M_C_DQ<56>
  269  M_C_DQ<55>     DQ<55>  @BASEBOARD_FAB2_LIB.BASEBOARD_FAB2(SCH_1):M_C_DQ<55>
  124  M_C_DQ<54>     DQ<54>  @BASEBOARD_FAB2_LIB.BASEBOARD_FAB2(SCH_1):M_C_DQ<54>
  262  M_C_DQ<53>     DQ<53>  @BASEBOARD_FAB2_LIB.BASEBOARD_FAB2(SCH_1):M_C_DQ<53>
  117  M_C_DQ<52>     DQ<52>  @BASEBOARD_FAB2_LIB.BASEBOARD_FAB2(SCH_1):M_C_DQ<52>
  271  M_C_DQ<51>     DQ<51>  @BASEBOARD_FAB2_LIB.BASEBOARD_FAB2(SCH_1):M_C_DQ<51>
  126  M_C_DQ<50>     DQ<50>  @BASEBOARD_FAB2_LIB.BASEBOARD_FAB2(SCH_1):M_C_DQ<50>
    3  M_C_DQ<4>      DQ<4>  @BASEBOARD_FAB2_LIB.BASEBOARD_FAB2(SCH_1):M_C_DQ<4>
  264  M_C_DQ<49>     DQ<49>  @BASEBOARD_FAB2_LIB.BASEBOARD_FAB2(SCH_1):M_C_DQ<49>
  119  M_C_DQ<48>     DQ<48>  @BASEBOARD_FAB2_LIB.BASEBOARD_FAB2(SCH_1):M_C_DQ<48>
  258  M_C_DQ<47>     DQ<47>  @BASEBOARD_FAB2_LIB.BASEBOARD_FAB2(SCH_1):M_C_DQ<47>
  113  M_C_DQ<46>     DQ<46>  @BASEBOARD_FAB2_LIB.BASEBOARD_FAB2(SCH_1):M_C_DQ<46>
  251  M_C_DQ<45>     DQ<45>  @BASEBOARD_FAB2_LIB.BASEBOARD_FAB2(SCH_1):M_C_DQ<45>
  106  M_C_DQ<44>     DQ<44>  @BASEBOARD_FAB2_LIB.BASEBOARD_FAB2(SCH_1):M_C_DQ<44>
  260  M_C_DQ<43>     DQ<43>  @BASEBOARD_FAB2_LIB.BASEBOARD_FAB2(SCH_1):M_C_DQ<43>
  115  M_C_DQ<42>     DQ<42>  @BASEBOARD_FAB2_LIB.BASEBOARD_FAB2(SCH_1):M_C_DQ<42>
  253  M_C_DQ<41>     DQ<41>  @BASEBOARD_FAB2_LIB.BASEBOARD_FAB2(SCH_1):M_C_DQ<41>
  108  M_C_DQ<40>     DQ<40>  @BASEBOARD_FAB2_LIB.BASEBOARD_FAB2(SCH_1):M_C_DQ<40>
  157  M_C_DQ<3>      DQ<3>  @BASEBOARD_FAB2_LIB.BASEBOARD_FAB2(SCH_1):M_C_DQ<3>
  247  M_C_DQ<39>     DQ<39>  @BASEBOARD_FAB2_LIB.BASEBOARD_FAB2(SCH_1):M_C_DQ<39>
  102  M_C_DQ<38>     DQ<38>  @BASEBOARD_FAB2_LIB.BASEBOARD_FAB2(SCH_1):M_C_DQ<38>
  240  M_C_DQ<37>     DQ<37>  @BASEBOARD_FAB2_LIB.BASEBOARD_FAB2(SCH_1):M_C_DQ<37>
   95  M_C_DQ<36>     DQ<36>  @BASEBOARD_FAB2_LIB.BASEBOARD_FAB2(SCH_1):M_C_DQ<36>
  249  M_C_DQ<35>     DQ<35>  @BASEBOARD_FAB2_LIB.BASEBOARD_FAB2(SCH_1):M_C_DQ<35>
  104  M_C_DQ<34>     DQ<34>  @BASEBOARD_FAB2_LIB.BASEBOARD_FAB2(SCH_1):M_C_DQ<34>
  242  M_C_DQ<33>     DQ<33>  @BASEBOARD_FAB2_LIB.BASEBOARD_FAB2(SCH_1):M_C_DQ<33>
   97  M_C_DQ<32>     DQ<32>  @BASEBOARD_FAB2_LIB.BASEBOARD_FAB2(SCH_1):M_C_DQ<32>
  188  M_C_DQ<31>     DQ<31>  @BASEBOARD_FAB2_LIB.BASEBOARD_FAB2(SCH_1):M_C_DQ<31>
   43  M_C_DQ<30>     DQ<30>  @BASEBOARD_FAB2_LIB.BASEBOARD_FAB2(SCH_1):M_C_DQ<30>
   12  M_C_DQ<2>      DQ<2>  @BASEBOARD_FAB2_LIB.BASEBOARD_FAB2(SCH_1):M_C_DQ<2>
  181  M_C_DQ<29>     DQ<29>  @BASEBOARD_FAB2_LIB.BASEBOARD_FAB2(SCH_1):M_C_DQ<29>
   36  M_C_DQ<28>     DQ<28>  @BASEBOARD_FAB2_LIB.BASEBOARD_FAB2(SCH_1):M_C_DQ<28>
  190  M_C_DQ<27>     DQ<27>  @BASEBOARD_FAB2_LIB.BASEBOARD_FAB2(SCH_1):M_C_DQ<27>
   45  M_C_DQ<26>     DQ<26>  @BASEBOARD_FAB2_LIB.BASEBOARD_FAB2(SCH_1):M_C_DQ<26>
  183  M_C_DQ<25>     DQ<25>  @BASEBOARD_FAB2_LIB.BASEBOARD_FAB2(SCH_1):M_C_DQ<25>
   38  M_C_DQ<24>     DQ<24>  @BASEBOARD_FAB2_LIB.BASEBOARD_FAB2(SCH_1):M_C_DQ<24>
  177  M_C_DQ<23>     DQ<23>  @BASEBOARD_FAB2_LIB.BASEBOARD_FAB2(SCH_1):M_C_DQ<23>
   32  M_C_DQ<22>     DQ<22>  @BASEBOARD_FAB2_LIB.BASEBOARD_FAB2(SCH_1):M_C_DQ<22>
  170  M_C_DQ<21>     DQ<21>  @BASEBOARD_FAB2_LIB.BASEBOARD_FAB2(SCH_1):M_C_DQ<21>
   25  M_C_DQ<20>     DQ<20>  @BASEBOARD_FAB2_LIB.BASEBOARD_FAB2(SCH_1):M_C_DQ<20>
  150  M_C_DQ<1>      DQ<1>  @BASEBOARD_FAB2_LIB.BASEBOARD_FAB2(SCH_1):M_C_DQ<1>
  179  M_C_DQ<19>     DQ<19>  @BASEBOARD_FAB2_LIB.BASEBOARD_FAB2(SCH_1):M_C_DQ<19>
   34  M_C_DQ<18>     DQ<18>  @BASEBOARD_FAB2_LIB.BASEBOARD_FAB2(SCH_1):M_C_DQ<18>
  172  M_C_DQ<17>     DQ<17>  @BASEBOARD_FAB2_LIB.BASEBOARD_FAB2(SCH_1):M_C_DQ<17>
   27  M_C_DQ<16>     DQ<16>  @BASEBOARD_FAB2_LIB.BASEBOARD_FAB2(SCH_1):M_C_DQ<16>
  166  M_C_DQ<15>     DQ<15>  @BASEBOARD_FAB2_LIB.BASEBOARD_FAB2(SCH_1):M_C_DQ<15>
   21  M_C_DQ<14>     DQ<14>  @BASEBOARD_FAB2_LIB.BASEBOARD_FAB2(SCH_1):M_C_DQ<14>
  159  M_C_DQ<13>     DQ<13>  @BASEBOARD_FAB2_LIB.BASEBOARD_FAB2(SCH_1):M_C_DQ<13>
   14  M_C_DQ<12>     DQ<12>  @BASEBOARD_FAB2_LIB.BASEBOARD_FAB2(SCH_1):M_C_DQ<12>
  168  M_C_DQ<11>     DQ<11>  @BASEBOARD_FAB2_LIB.BASEBOARD_FAB2(SCH_1):M_C_DQ<11>
   23  M_C_DQ<10>     DQ<10>  @BASEBOARD_FAB2_LIB.BASEBOARD_FAB2(SCH_1):M_C_DQ<10>
    5  M_C_DQ<0>      DQ<0>  @BASEBOARD_FAB2_LIB.BASEBOARD_FAB2(SCH_1):M_C_DQ<0>
  237  M_C_CS_N<7>    S3_N_C<1>  @BASEBOARD_FAB2_LIB.BASEBOARD_FAB2(SCH_1):M_C_CS_N<7>
   93  M_C_CS_N<6>    S2_N_C<0>  @BASEBOARD_FAB2_LIB.BASEBOARD_FAB2(SCH_1):M_C_CS_N<6>
   89  M_C_CS_N<5>     S1_N  @BASEBOARD_FAB2_LIB.BASEBOARD_FAB2(SCH_1):M_C_CS_N<5>
   84  M_C_CS_N<4>     S0_N  @BASEBOARD_FAB2_LIB.BASEBOARD_FAB2(SCH_1):M_C_CS_N<4>
  218  M_C_CLK_DP<3>   CK1P  @BASEBOARD_FAB2_LIB.BASEBOARD_FAB2(SCH_1):M_C_CLK_DP<3>
   74  M_C_CLK_DP<2>   CK0P  @BASEBOARD_FAB2_LIB.BASEBOARD_FAB2(SCH_1):M_C_CLK_DP<2>
  219  M_C_CLK_DN<3>   CK1N  @BASEBOARD_FAB2_LIB.BASEBOARD_FAB2(SCH_1):M_C_CLK_DN<3>
   75  M_C_CLK_DN<2>   CK0N  @BASEBOARD_FAB2_LIB.BASEBOARD_FAB2(SCH_1):M_C_CLK_DN<2>
  203  M_C_CKE<3>     CKE<1>  @BASEBOARD_FAB2_LIB.BASEBOARD_FAB2(SCH_1):M_C_CKE<3>
   60  M_C_CKE<2>     CKE<0>  @BASEBOARD_FAB2_LIB.BASEBOARD_FAB2(SCH_1):M_C_CKE<2>
  235  M_C_C<2>        C<2>  @BASEBOARD_FAB2_LIB.BASEBOARD_FAB2(SCH_1):M_C_C<2>
  207  M_C_BG<1>      BG<1>  @BASEBOARD_FAB2_LIB.BASEBOARD_FAB2(SCH_1):M_C_BG<1>
   63  M_C_BG<0>      BG<0>  @BASEBOARD_FAB2_LIB.BASEBOARD_FAB2(SCH_1):M_C_BG<0>
  224  M_C_BA<1>      BA<1>  @BASEBOARD_FAB2_LIB.BASEBOARD_FAB2(SCH_1):M_C_BA<1>
   81  M_C_BA<0>      BA<0>  @BASEBOARD_FAB2_LIB.BASEBOARD_FAB2(SCH_1):M_C_BA<0>
  208  M_C_ALERT_N    ALERT_N  @BASEBOARD_FAB2_LIB.BASEBOARD_FAB2(SCH_1):M_C_ALERT_N
   62  M_C_ACT_N      ACT_N  @BASEBOARD_FAB2_LIB.BASEBOARD_FAB2(SCH_1):M_C_ACT_N
   58  M_ABC_RST_N    RESET_N  @BASEBOARD_FAB2_LIB.BASEBOARD_FAB2(SCH_1):M_ABC_RST_N
  140  GND            SA<1>  @BASEBOARD_FAB2_LIB.BASEBOARD_FAB2(SCH_1):GND
   78  FM_DIMM_EVENT_COD_N  EVENT_N  @BASEBOARD_FAB2_LIB.BASEBOARD_FAB2(SCH_1):FM_DIMM_EVENT_COD_N
  230  FM_ADR_COMPLETE_ABC_N  SAVE_N_NC  @BASEBOARD_FAB2_LIB.BASEBOARD_FAB2(SCH_1):FM_ADR_COMPLETE_ABC_N

CONN8_C77962004  I47  J7G2   [CONN8_C77962004_PIP-CONN,C7796A]
    5  PWRGD_P3V3_STBY    IO5  @BASEBOARD_FAB2_LIB.BASEBOARD_FAB2(SCH_1):PWRGD_P3V3_STBY
    1  P3V3_STBY_PLD_D    IO1  @BASEBOARD_FAB2_LIB.BASEBOARD_FAB2(SCH_1):P3V3_STBY_PLD_D
    4  JTAG_TRST_N      IO4  @BASEBOARD_FAB2_LIB.BASEBOARD_FAB2(SCH_1):JTAG_TRST_N
    6  JTAG_TMS_R       IO6  @BASEBOARD_FAB2_LIB.BASEBOARD_FAB2(SCH_1):JTAG_TMS_R
    2  JTAG_TDO_R       IO2  @BASEBOARD_FAB2_LIB.BASEBOARD_FAB2(SCH_1):JTAG_TDO_R
    3  JTAG_TDI_R       IO3  @BASEBOARD_FAB2_LIB.BASEBOARD_FAB2(SCH_1):JTAG_TDI_R
    8  JTAG_TCK_R       IO8  @BASEBOARD_FAB2_LIB.BASEBOARD_FAB2(SCH_1):JTAG_TCK_R
    7  GND              IO7  @BASEBOARD_FAB2_LIB.BASEBOARD_FAB2(SCH_1):GND

CONN12_C73564003  I174  J7G3   [CONN12_C73564003_PIP-CONN,C735A]
    7  TP_PASSWORD_CLEAR    IO7  @BASEBOARD_FAB2_LIB.BASEBOARD_FAB2(SCH_1):TP_PASSWORD_CLEAR
    1  TP_ME_RCVR_BOOT    IO1  @BASEBOARD_FAB2_LIB.BASEBOARD_FAB2(SCH_1):TP_ME_RCVR_BOOT
    2  TP_BIOS_USB_RECOVERY    IO2  @BASEBOARD_FAB2_LIB.BASEBOARD_FAB2(SCH_1):TP_BIOS_USB_RECOVERY
    8  TP_BIOS_RECOVER_BOOT    IO8  @BASEBOARD_FAB2_LIB.BASEBOARD_FAB2(SCH_1):TP_BIOS_RECOVER_BOOT
    6  PU_BIOS_USB_RECOVERY    IO6  @BASEBOARD_FAB2_LIB.BASEBOARD_FAB2(SCH_1):PU_BIOS_USB_RECOVERY
   12  PU_BIOS_RECOVER_BOOT   IO12  @BASEBOARD_FAB2_LIB.BASEBOARD_FAB2(SCH_1):PU_BIOS_RECOVER_BOOT
   11  PD_PASSWORD_CLEAR   IO11  @BASEBOARD_FAB2_LIB.BASEBOARD_FAB2(SCH_1):PD_PASSWORD_CLEAR
    5  PD_ME_RCVR_N     IO5  @BASEBOARD_FAB2_LIB.BASEBOARD_FAB2(SCH_1):PD_ME_RCVR_N
    9  FM_PASSWORD_CLEAR_N    IO9  @BASEBOARD_FAB2_LIB.BASEBOARD_FAB2(SCH_1):FM_PASSWORD_CLEAR_N
    3  FM_ME_RECOVER_N    IO3  @BASEBOARD_FAB2_LIB.BASEBOARD_FAB2(SCH_1):FM_ME_RECOVER_N
    4  FM_BIOS_USB_RECOVERY    IO4  @BASEBOARD_FAB2_LIB.BASEBOARD_FAB2(SCH_1):FM_BIOS_USB_RECOVERY
   10  FM_BIOS_TOP_SWAP   IO10  @BASEBOARD_FAB2_LIB.BASEBOARD_FAB2(SCH_1):FM_BIOS_TOP_SWAP

CONN72_G97614002_A_CP  I163  J8A1   [CONN72_G97614002_A_CP-CONN,G97A]
  2B2  TP_SGPIO_SATA_LOAD1_R  SIDEBANDB_1  @BASEBOARD_FAB2_LIB.BASEBOARD_FAB2(SCH_1):TP_SGPIO_SATA_LOAD1_R
  2C1  TP_SGPIO_SATA_DATA1_R  SIDEBANDB_4  @BASEBOARD_FAB2_LIB.BASEBOARD_FAB2(SCH_1):TP_SGPIO_SATA_DATA1_R
  2A2  TP_SGPIO_SATA_CLOCK1_R  SIDEBANDB_0  @BASEBOARD_FAB2_LIB.BASEBOARD_FAB2(SCH_1):TP_SGPIO_SATA_CLOCK1_R
  2A1  TP_FM_QAT_CBL_PRSNT1_N_R  SIDEBANDB_7  @BASEBOARD_FAB2_LIB.BASEBOARD_FAB2(SCH_1):TP_FM_QAT_CBL_PRSNT1_N_R
  1A1  TP_FM_QAT_CBL_PRSNT0_R_N  SIDEBANDA_7  @BASEBOARD_FAB2_LIB.BASEBOARD_FAB2(SCH_1):TP_FM_QAT_CBL_PRSNT0_R_N
  1B2  SGPIO_PCH_SATA_LOAD_R  SIDEBANDA_1  @BASEBOARD_FAB2_LIB.BASEBOARD_FAB2(SCH_1):SGPIO_PCH_SATA_LOAD_R
  1C1  SGPIO_PCH_SATA_DOUT0_R  SIDEBANDA_4  @BASEBOARD_FAB2_LIB.BASEBOARD_FAB2(SCH_1):SGPIO_PCH_SATA_DOUT0_R
  1A2  SGPIO_PCH_SATA_CLOCK_R  SIDEBANDA_0  @BASEBOARD_FAB2_LIB.BASEBOARD_FAB2(SCH_1):SGPIO_PCH_SATA_CLOCK_R
  2C7  SATA6G_P7_TX_C_DP  TXB3_DP  @BASEBOARD_FAB2_LIB.BASEBOARD_FAB2(SCH_1):SATA6G_P7_TX_C_DP
  2C8  SATA6G_P7_TX_C_DN  TXB3_DN  @BASEBOARD_FAB2_LIB.BASEBOARD_FAB2(SCH_1):SATA6G_P7_TX_C_DN
  2A7  SATA6G_P7_RX_C_DP  RXB3_DP  @BASEBOARD_FAB2_LIB.BASEBOARD_FAB2(SCH_1):SATA6G_P7_RX_C_DP
  2A8  SATA6G_P7_RX_C_DN  RXB3_DN  @BASEBOARD_FAB2_LIB.BASEBOARD_FAB2(SCH_1):SATA6G_P7_RX_C_DN
  2D7  SATA6G_P6_TX_C_DP  TXB2_DP  @BASEBOARD_FAB2_LIB.BASEBOARD_FAB2(SCH_1):SATA6G_P6_TX_C_DP
  2D8  SATA6G_P6_TX_C_DN  TXB2_DN  @BASEBOARD_FAB2_LIB.BASEBOARD_FAB2(SCH_1):SATA6G_P6_TX_C_DN
  2B7  SATA6G_P6_RX_C_DP  RXB2_DP  @BASEBOARD_FAB2_LIB.BASEBOARD_FAB2(SCH_1):SATA6G_P6_RX_C_DP
  2B8  SATA6G_P6_RX_C_DN  RXB2_DN  @BASEBOARD_FAB2_LIB.BASEBOARD_FAB2(SCH_1):SATA6G_P6_RX_C_DN
  2C4  SATA6G_P5_TX_C_DP  TXB1_DP  @BASEBOARD_FAB2_LIB.BASEBOARD_FAB2(SCH_1):SATA6G_P5_TX_C_DP
  2C5  SATA6G_P5_TX_C_DN  TXB1_DN  @BASEBOARD_FAB2_LIB.BASEBOARD_FAB2(SCH_1):SATA6G_P5_TX_C_DN
  2A4  SATA6G_P5_RX_C_DP  RXB1_DP  @BASEBOARD_FAB2_LIB.BASEBOARD_FAB2(SCH_1):SATA6G_P5_RX_C_DP
  2A5  SATA6G_P5_RX_C_DN  RXB1_DN  @BASEBOARD_FAB2_LIB.BASEBOARD_FAB2(SCH_1):SATA6G_P5_RX_C_DN
  2D4  SATA6G_P4_TX_C_DP  TXB0_DP  @BASEBOARD_FAB2_LIB.BASEBOARD_FAB2(SCH_1):SATA6G_P4_TX_C_DP
  2D5  SATA6G_P4_TX_C_DN  TXB0_DN  @BASEBOARD_FAB2_LIB.BASEBOARD_FAB2(SCH_1):SATA6G_P4_TX_C_DN
  2B4  SATA6G_P4_RX_C_DP  RXB0_DP  @BASEBOARD_FAB2_LIB.BASEBOARD_FAB2(SCH_1):SATA6G_P4_RX_C_DP
  2B5  SATA6G_P4_RX_C_DN  RXB0_DN  @BASEBOARD_FAB2_LIB.BASEBOARD_FAB2(SCH_1):SATA6G_P4_RX_C_DN
  1C7  SATA6G_P3_TX_C_DP  TXA3_DP  @BASEBOARD_FAB2_LIB.BASEBOARD_FAB2(SCH_1):SATA6G_P3_TX_C_DP
  1C8  SATA6G_P3_TX_C_DN  TXA3_DN  @BASEBOARD_FAB2_LIB.BASEBOARD_FAB2(SCH_1):SATA6G_P3_TX_C_DN
  1A7  SATA6G_P3_RX_C_DP  RXA3_DP  @BASEBOARD_FAB2_LIB.BASEBOARD_FAB2(SCH_1):SATA6G_P3_RX_C_DP
  1A8  SATA6G_P3_RX_C_DN  RXA3_DN  @BASEBOARD_FAB2_LIB.BASEBOARD_FAB2(SCH_1):SATA6G_P3_RX_C_DN
  1D7  SATA6G_P2_TX_C_DP  TXA2_DP  @BASEBOARD_FAB2_LIB.BASEBOARD_FAB2(SCH_1):SATA6G_P2_TX_C_DP
  1D8  SATA6G_P2_TX_C_DN  TXA2_DN  @BASEBOARD_FAB2_LIB.BASEBOARD_FAB2(SCH_1):SATA6G_P2_TX_C_DN
  1B7  SATA6G_P2_RX_C_DP  RXA2_DP  @BASEBOARD_FAB2_LIB.BASEBOARD_FAB2(SCH_1):SATA6G_P2_RX_C_DP
  1B8  SATA6G_P2_RX_C_DN  RXA2_DN  @BASEBOARD_FAB2_LIB.BASEBOARD_FAB2(SCH_1):SATA6G_P2_RX_C_DN
  1C4  SATA6G_P1_TX_C_DP  TXA1_DP  @BASEBOARD_FAB2_LIB.BASEBOARD_FAB2(SCH_1):SATA6G_P1_TX_C_DP
  1C5  SATA6G_P1_TX_C_DN  TXA1_DN  @BASEBOARD_FAB2_LIB.BASEBOARD_FAB2(SCH_1):SATA6G_P1_TX_C_DN
  1A4  SATA6G_P1_RX_C_DP  RXA1_DP  @BASEBOARD_FAB2_LIB.BASEBOARD_FAB2(SCH_1):SATA6G_P1_RX_C_DP
  1A5  SATA6G_P1_RX_C_DN  RXA1_DN  @BASEBOARD_FAB2_LIB.BASEBOARD_FAB2(SCH_1):SATA6G_P1_RX_C_DN
  1D4  SATA6G_P0_TX_C_DP  TXA0_DP  @BASEBOARD_FAB2_LIB.BASEBOARD_FAB2(SCH_1):SATA6G_P0_TX_C_DP
  1D5  SATA6G_P0_TX_C_DN  TXA0_DN  @BASEBOARD_FAB2_LIB.BASEBOARD_FAB2(SCH_1):SATA6G_P0_TX_C_DN
  1B4  SATA6G_P0_RX_C_DP  RXA0_DP  @BASEBOARD_FAB2_LIB.BASEBOARD_FAB2(SCH_1):SATA6G_P0_RX_C_DP
  1B5  SATA6G_P0_RX_C_DN  RXA0_DN  @BASEBOARD_FAB2_LIB.BASEBOARD_FAB2(SCH_1):SATA6G_P0_RX_C_DN
  2D1  PU_DATAIN1_SATA_1_R  SIDEBANDB_5  @BASEBOARD_FAB2_LIB.BASEBOARD_FAB2(SCH_1):PU_DATAIN1_SATA_1_R
  1D1  PU_DATAIN1_SATA_0_R  SIDEBANDA_5  @BASEBOARD_FAB2_LIB.BASEBOARD_FAB2(SCH_1):PU_DATAIN1_SATA_0_R
  2D2  PD_SATA1_CONTROLLER_TYPE_R  SIDEBANDB_6  @BASEBOARD_FAB2_LIB.BASEBOARD_FAB2(SCH_1):PD_SATA1_CONTROLLER_TYPE_R
  1D2  PD_SATA0_CONTROLLER_TYPE_R  SIDEBANDA_6  @BASEBOARD_FAB2_LIB.BASEBOARD_FAB2(SCH_1):PD_SATA0_CONTROLLER_TYPE_R
  2B1  GND            SIDEBANDB_3  @BASEBOARD_FAB2_LIB.BASEBOARD_FAB2(SCH_1):GND
  2C2  GND            SIDEBANDB_2  @BASEBOARD_FAB2_LIB.BASEBOARD_FAB2(SCH_1):GND
  1B1  GND            SIDEBANDA_3  @BASEBOARD_FAB2_LIB.BASEBOARD_FAB2(SCH_1):GND
  1C2  GND            SIDEBANDA_2  @BASEBOARD_FAB2_LIB.BASEBOARD_FAB2(SCH_1):GND
  1A3  GND            GND<23>  @BASEBOARD_FAB2_LIB.BASEBOARD_FAB2(SCH_1):GND
  1A6  GND            GND<22>  @BASEBOARD_FAB2_LIB.BASEBOARD_FAB2(SCH_1):GND
  1A9  GND            GND<21>  @BASEBOARD_FAB2_LIB.BASEBOARD_FAB2(SCH_1):GND
  1B3  GND            GND<20>  @BASEBOARD_FAB2_LIB.BASEBOARD_FAB2(SCH_1):GND
  1B6  GND            GND<19>  @BASEBOARD_FAB2_LIB.BASEBOARD_FAB2(SCH_1):GND
  1B9  GND            GND<18>  @BASEBOARD_FAB2_LIB.BASEBOARD_FAB2(SCH_1):GND
  1C3  GND            GND<17>  @BASEBOARD_FAB2_LIB.BASEBOARD_FAB2(SCH_1):GND
  1C6  GND            GND<16>  @BASEBOARD_FAB2_LIB.BASEBOARD_FAB2(SCH_1):GND
  1C9  GND            GND<15>  @BASEBOARD_FAB2_LIB.BASEBOARD_FAB2(SCH_1):GND
  1D3  GND            GND<14>  @BASEBOARD_FAB2_LIB.BASEBOARD_FAB2(SCH_1):GND
  1D6  GND            GND<13>  @BASEBOARD_FAB2_LIB.BASEBOARD_FAB2(SCH_1):GND
  1D9  GND            GND<12>  @BASEBOARD_FAB2_LIB.BASEBOARD_FAB2(SCH_1):GND
  2A3  GND            GND<11>  @BASEBOARD_FAB2_LIB.BASEBOARD_FAB2(SCH_1):GND
  2A6  GND            GND<10>  @BASEBOARD_FAB2_LIB.BASEBOARD_FAB2(SCH_1):GND
  2A9  GND            GND<9>  @BASEBOARD_FAB2_LIB.BASEBOARD_FAB2(SCH_1):GND
  2B3  GND            GND<8>  @BASEBOARD_FAB2_LIB.BASEBOARD_FAB2(SCH_1):GND
  2B6  GND            GND<7>  @BASEBOARD_FAB2_LIB.BASEBOARD_FAB2(SCH_1):GND
  2B9  GND            GND<6>  @BASEBOARD_FAB2_LIB.BASEBOARD_FAB2(SCH_1):GND
  2C3  GND            GND<5>  @BASEBOARD_FAB2_LIB.BASEBOARD_FAB2(SCH_1):GND
  2C6  GND            GND<4>  @BASEBOARD_FAB2_LIB.BASEBOARD_FAB2(SCH_1):GND
  2C9  GND            GND<3>  @BASEBOARD_FAB2_LIB.BASEBOARD_FAB2(SCH_1):GND
  2D3  GND            GND<2>  @BASEBOARD_FAB2_LIB.BASEBOARD_FAB2(SCH_1):GND
  2D6  GND            GND<1>  @BASEBOARD_FAB2_LIB.BASEBOARD_FAB2(SCH_1):GND
  2D9  GND            GND<0>  @BASEBOARD_FAB2_LIB.BASEBOARD_FAB2(SCH_1):GND

CONN36_G97614001_CP  I26  J8A2   [CONN36_G97614001_CP-CONN,G9761A]
   A1  TP_FM_QAT_CBL_PRSNT2_N  SIDEBAND7  @BASEBOARD_FAB2_LIB.BASEBOARD_FAB2(SCH_1):TP_FM_QAT_CBL_PRSNT2_N
   B2  SGPIO_PCH_SSATA_LOAD_R  SIDEBAND1  @BASEBOARD_FAB2_LIB.BASEBOARD_FAB2(SCH_1):SGPIO_PCH_SSATA_LOAD_R
   C1  SGPIO_PCH_SSATA_DOUT0_R  SIDEBAND4  @BASEBOARD_FAB2_LIB.BASEBOARD_FAB2(SCH_1):SGPIO_PCH_SSATA_DOUT0_R
   A2  SGPIO_PCH_SSATA_CLOCK_R  SIDEBAND0  @BASEBOARD_FAB2_LIB.BASEBOARD_FAB2(SCH_1):SGPIO_PCH_SSATA_CLOCK_R
   C4  SATA6G_P9_TX_C_DP  TXA1_DP  @BASEBOARD_FAB2_LIB.BASEBOARD_FAB2(SCH_1):SATA6G_P9_TX_C_DP
   C5  SATA6G_P9_TX_C_DN  TXA1_DN  @BASEBOARD_FAB2_LIB.BASEBOARD_FAB2(SCH_1):SATA6G_P9_TX_C_DN
   A4  SATA6G_P9_RX_C_DP  RXA1_DP  @BASEBOARD_FAB2_LIB.BASEBOARD_FAB2(SCH_1):SATA6G_P9_RX_C_DP
   A5  SATA6G_P9_RX_C_DN  RXA1_DN  @BASEBOARD_FAB2_LIB.BASEBOARD_FAB2(SCH_1):SATA6G_P9_RX_C_DN
   D4  SATA6G_P8_TX_C_DP  TXA0_DP  @BASEBOARD_FAB2_LIB.BASEBOARD_FAB2(SCH_1):SATA6G_P8_TX_C_DP
   D5  SATA6G_P8_TX_C_DN  TXA0_DN  @BASEBOARD_FAB2_LIB.BASEBOARD_FAB2(SCH_1):SATA6G_P8_TX_C_DN
   B4  SATA6G_P8_RX_C_DP  RXA0_DP  @BASEBOARD_FAB2_LIB.BASEBOARD_FAB2(SCH_1):SATA6G_P8_RX_C_DP
   B5  SATA6G_P8_RX_C_DN  RXA0_DN  @BASEBOARD_FAB2_LIB.BASEBOARD_FAB2(SCH_1):SATA6G_P8_RX_C_DN
   C7  SATA6G_P11_TX_C_DP  TXA3_DP  @BASEBOARD_FAB2_LIB.BASEBOARD_FAB2(SCH_1):SATA6G_P11_TX_C_DP
   C8  SATA6G_P11_TX_C_DN  TXA3_DN  @BASEBOARD_FAB2_LIB.BASEBOARD_FAB2(SCH_1):SATA6G_P11_TX_C_DN
   A7  SATA6G_P11_RX_C_DP  RXA3_DP  @BASEBOARD_FAB2_LIB.BASEBOARD_FAB2(SCH_1):SATA6G_P11_RX_C_DP
   A8  SATA6G_P11_RX_C_DN  RXA3_DN  @BASEBOARD_FAB2_LIB.BASEBOARD_FAB2(SCH_1):SATA6G_P11_RX_C_DN
   D7  SATA6G_P10_TX_C_DP  TXA2_DP  @BASEBOARD_FAB2_LIB.BASEBOARD_FAB2(SCH_1):SATA6G_P10_TX_C_DP
   D8  SATA6G_P10_TX_C_DN  TXA2_DN  @BASEBOARD_FAB2_LIB.BASEBOARD_FAB2(SCH_1):SATA6G_P10_TX_C_DN
   B7  SATA6G_P10_RX_C_DP  RXA2_DP  @BASEBOARD_FAB2_LIB.BASEBOARD_FAB2(SCH_1):SATA6G_P10_RX_C_DP
   B8  SATA6G_P10_RX_C_DN  RXA2_DN  @BASEBOARD_FAB2_LIB.BASEBOARD_FAB2(SCH_1):SATA6G_P10_RX_C_DN
   D1  PU_DATAIN1_SATA_2  SIDEBAND5  @BASEBOARD_FAB2_LIB.BASEBOARD_FAB2(SCH_1):PU_DATAIN1_SATA_2
   D2  PD_SATA2_CONTROLLER_TYPE  SIDEBAND6  @BASEBOARD_FAB2_LIB.BASEBOARD_FAB2(SCH_1):PD_SATA2_CONTROLLER_TYPE
   B1  GND            SIDEBAND3  @BASEBOARD_FAB2_LIB.BASEBOARD_FAB2(SCH_1):GND
   C2  GND            SIDEBAND2  @BASEBOARD_FAB2_LIB.BASEBOARD_FAB2(SCH_1):GND
   D9  GND            GND12  @BASEBOARD_FAB2_LIB.BASEBOARD_FAB2(SCH_1):GND
   D6  GND            GND11  @BASEBOARD_FAB2_LIB.BASEBOARD_FAB2(SCH_1):GND
   D3  GND            GND10  @BASEBOARD_FAB2_LIB.BASEBOARD_FAB2(SCH_1):GND
   C9  GND             GND9  @BASEBOARD_FAB2_LIB.BASEBOARD_FAB2(SCH_1):GND
   C6  GND             GND8  @BASEBOARD_FAB2_LIB.BASEBOARD_FAB2(SCH_1):GND
   C3  GND             GND7  @BASEBOARD_FAB2_LIB.BASEBOARD_FAB2(SCH_1):GND
   B9  GND             GND6  @BASEBOARD_FAB2_LIB.BASEBOARD_FAB2(SCH_1):GND
   B6  GND             GND5  @BASEBOARD_FAB2_LIB.BASEBOARD_FAB2(SCH_1):GND
   B3  GND             GND4  @BASEBOARD_FAB2_LIB.BASEBOARD_FAB2(SCH_1):GND
   A9  GND             GND3  @BASEBOARD_FAB2_LIB.BASEBOARD_FAB2(SCH_1):GND
   A6  GND             GND2  @BASEBOARD_FAB2_LIB.BASEBOARD_FAB2(SCH_1):GND
   A3  GND             GND1  @BASEBOARD_FAB2_LIB.BASEBOARD_FAB2(SCH_1):GND

CONN7_E82125014_PIP_TH  I17  J8A3   [CONN7_E82125014_PIP_TH-EMPTY,EA]
    2  SATA6G_S1_TX_C_DP  SATA_TXP  @BASEBOARD_FAB2_LIB.BASEBOARD_FAB2(SCH_1):SATA6G_S1_TX_C_DP
    3  SATA6G_S1_TX_C_DN  SATA_TXN  @BASEBOARD_FAB2_LIB.BASEBOARD_FAB2(SCH_1):SATA6G_S1_TX_C_DN
    6  SATA6G_S1_RX_C_DP  SATA_RXP  @BASEBOARD_FAB2_LIB.BASEBOARD_FAB2(SCH_1):SATA6G_S1_RX_C_DP
    5  SATA6G_S1_RX_C_DN  SATA_RXN  @BASEBOARD_FAB2_LIB.BASEBOARD_FAB2(SCH_1):SATA6G_S1_RX_C_DN
  MH2  GND              MH2  @BASEBOARD_FAB2_LIB.BASEBOARD_FAB2(SCH_1):GND
  MH1  GND              MH1  @BASEBOARD_FAB2_LIB.BASEBOARD_FAB2(SCH_1):GND
    1  GND            GND<2>  @BASEBOARD_FAB2_LIB.BASEBOARD_FAB2(SCH_1):GND
    4  GND            GND<1>  @BASEBOARD_FAB2_LIB.BASEBOARD_FAB2(SCH_1):GND
    7  GND            GND<0>  @BASEBOARD_FAB2_LIB.BASEBOARD_FAB2(SCH_1):GND

CONN4_H73295001_PIP  I25  J8A4   [CONN4_H73295001_PIP-EMPTY,H732A]
    1  P5V_HDD_SATA     IO1  @BASEBOARD_FAB2_LIB.BASEBOARD_FAB2(SCH_1):P5V_HDD_SATA
    4  P12V_HDD_SATA    IO4  @BASEBOARD_FAB2_LIB.BASEBOARD_FAB2(SCH_1):P12V_HDD_SATA
    3  GND              IO3  @BASEBOARD_FAB2_LIB.BASEBOARD_FAB2(SCH_1):GND
    2  GND              IO2  @BASEBOARD_FAB2_LIB.BASEBOARD_FAB2(SCH_1):GND

SCONN24_H46321001_SM  I1   J8B1   [SCONN24_H46321001_SM-SCONN,H46A]
   17  TP_HFI_IO_CONN0_RSVD_17   IO17  @BASEBOARD_FAB2_LIB.BASEBOARD_FAB2(SCH_1):TP_HFI_IO_CONN0_RSVD_17
   24  SMB_OCP_FRU_STBY_LVC3_SDA   IO24  @BASEBOARD_FAB2_LIB.BASEBOARD_FAB2(SCH_1):SMB_OCP_FRU_STBY_LVC3_SDA
   22  SMB_OCP_FRU_STBY_LVC3_SCL   IO22  @BASEBOARD_FAB2_LIB.BASEBOARD_FAB2(SCH_1):SMB_OCP_FRU_STBY_LVC3_SCL
   12  SMB_HFI1_CPU0_LVC2_SDA   IO12  @BASEBOARD_FAB2_LIB.BASEBOARD_FAB2(SCH_1):SMB_HFI1_CPU0_LVC2_SDA
   10  SMB_HFI1_CPU0_LVC2_SCL   IO10  @BASEBOARD_FAB2_LIB.BASEBOARD_FAB2(SCH_1):SMB_HFI1_CPU0_LVC2_SCL
    4  SMB_HFI0_CPU0_LVC2_SDA    IO4  @BASEBOARD_FAB2_LIB.BASEBOARD_FAB2(SCH_1):SMB_HFI0_CPU0_LVC2_SDA
    2  SMB_HFI0_CPU0_LVC2_SCL    IO2  @BASEBOARD_FAB2_LIB.BASEBOARD_FAB2(SCH_1):SMB_HFI0_CPU0_LVC2_SCL
   14  RST_HFI1_CPU0_LVT2_N   IO14  @BASEBOARD_FAB2_LIB.BASEBOARD_FAB2(SCH_1):RST_HFI1_CPU0_LVT2_N
    6  RST_HFI0_CPU0_LVT2_N    IO6  @BASEBOARD_FAB2_LIB.BASEBOARD_FAB2(SCH_1):RST_HFI0_CPU0_LVT2_N
   19  PWRGD_PVPP_ABC   IO19  @BASEBOARD_FAB2_LIB.BASEBOARD_FAB2(SCH_1):PWRGD_PVPP_ABC
   21  PVPP_ABC        IO21  @BASEBOARD_FAB2_LIB.BASEBOARD_FAB2(SCH_1):PVPP_ABC
   20  P3V3            IO20  @BASEBOARD_FAB2_LIB.BASEBOARD_FAB2(SCH_1):P3V3
   18  P3V3            IO18  @BASEBOARD_FAB2_LIB.BASEBOARD_FAB2(SCH_1):P3V3
   13  LED_HFI1_CPU0_N   IO13  @BASEBOARD_FAB2_LIB.BASEBOARD_FAB2(SCH_1):LED_HFI1_CPU0_N
    5  LED_HFI0_CPU0_N    IO5  @BASEBOARD_FAB2_LIB.BASEBOARD_FAB2(SCH_1):LED_HFI0_CPU0_N
   16  IRQ_HFI1_CPU0_LVT2_N   IO16  @BASEBOARD_FAB2_LIB.BASEBOARD_FAB2(SCH_1):IRQ_HFI1_CPU0_LVT2_N
    8  IRQ_HFI0_CPU0_LVT2_N    IO8  @BASEBOARD_FAB2_LIB.BASEBOARD_FAB2(SCH_1):IRQ_HFI0_CPU0_LVT2_N
  MP2  GND              MP2  @BASEBOARD_FAB2_LIB.BASEBOARD_FAB2(SCH_1):GND
  MP1  GND              MP1  @BASEBOARD_FAB2_LIB.BASEBOARD_FAB2(SCH_1):GND
   23  GND             IO23  @BASEBOARD_FAB2_LIB.BASEBOARD_FAB2(SCH_1):GND
   15  GND             IO15  @BASEBOARD_FAB2_LIB.BASEBOARD_FAB2(SCH_1):GND
    9  GND              IO9  @BASEBOARD_FAB2_LIB.BASEBOARD_FAB2(SCH_1):GND
    7  GND              IO7  @BASEBOARD_FAB2_LIB.BASEBOARD_FAB2(SCH_1):GND
    1  GND              IO1  @BASEBOARD_FAB2_LIB.BASEBOARD_FAB2(SCH_1):GND
   11  FM_MODPRST_HFI1_CPU0_LVT2_N   IO11  @BASEBOARD_FAB2_LIB.BASEBOARD_FAB2(SCH_1):FM_MODPRST_HFI1_CPU0_LVT2_N
    3  FM_MODPRST_HFI0_CPU0_LVT2_N    IO3  @BASEBOARD_FAB2_LIB.BASEBOARD_FAB2(SCH_1):FM_MODPRST_HFI0_CPU0_LVT2_N

CONN3_C95678002_PIP  I285  J8C1   [CONN3_C95678002_PIP-CONN,C9567A]
    1  SMB_HOST_STBY_LVC3_SDA    IO1  @BASEBOARD_FAB2_LIB.BASEBOARD_FAB2(SCH_1):SMB_HOST_STBY_LVC3_SDA
    3  SMB_HOST_STBY_LVC3_SCL    IO3  @BASEBOARD_FAB2_LIB.BASEBOARD_FAB2(SCH_1):SMB_HOST_STBY_LVC3_SCL
    2  GND              IO2  @BASEBOARD_FAB2_LIB.BASEBOARD_FAB2(SCH_1):GND

CONN3_C95678002_PIP  I122  J8D4   [CONN3_C95678002_PIP-CONN,C9567A]
    1  SMB_VR_STBY_LVC3_SDA    IO1  @BASEBOARD_FAB2_LIB.BASEBOARD_FAB2(SCH_1):SMB_VR_STBY_LVC3_SDA
    3  SMB_VR_STBY_LVC3_SCL    IO3  @BASEBOARD_FAB2_LIB.BASEBOARD_FAB2(SCH_1):SMB_VR_STBY_LVC3_SCL
    2  GND              IO2  @BASEBOARD_FAB2_LIB.BASEBOARD_FAB2(SCH_1):GND

SCONN11_H67026001_SM  I87  J8E1   [SCONN11_H67026001_SM-CONN,H670A]
    3  SPI_PCH_TPM_MOSI_R    IO3  @BASEBOARD_FAB2_LIB.BASEBOARD_FAB2(SCH_1):SPI_PCH_TPM_MOSI_R
    4  SPI_PCH_TPM_MISO_R    IO4  @BASEBOARD_FAB2_LIB.BASEBOARD_FAB2(SCH_1):SPI_PCH_TPM_MISO_R
    5  SPI_PCH_TPM_CS_R_N    IO5  @BASEBOARD_FAB2_LIB.BASEBOARD_FAB2(SCH_1):SPI_PCH_TPM_CS_R_N
    1  SPI_PCH_TPM_CLK_R    IO1  @BASEBOARD_FAB2_LIB.BASEBOARD_FAB2(SCH_1):SPI_PCH_TPM_CLK_R
    6  SMB_SENSOR_STBY_LVC3_SDA    IO6  @BASEBOARD_FAB2_LIB.BASEBOARD_FAB2(SCH_1):SMB_SENSOR_STBY_LVC3_SDA
   10  SMB_SENSOR_STBY_LVC3_SCL   IO10  @BASEBOARD_FAB2_LIB.BASEBOARD_FAB2(SCH_1):SMB_SENSOR_STBY_LVC3_SCL
    2  RST_PLTRST_BUF_N    IO2  @BASEBOARD_FAB2_LIB.BASEBOARD_FAB2(SCH_1):RST_PLTRST_BUF_N
    7  P3V3_STBY        IO7  @BASEBOARD_FAB2_LIB.BASEBOARD_FAB2(SCH_1):P3V3_STBY
    9  IRQ_SPI_TPM_N_R    IO9  @BASEBOARD_FAB2_LIB.BASEBOARD_FAB2(SCH_1):IRQ_SPI_TPM_N_R
  MP2  GND              MP2  @BASEBOARD_FAB2_LIB.BASEBOARD_FAB2(SCH_1):GND
  MP1  GND              MP1  @BASEBOARD_FAB2_LIB.BASEBOARD_FAB2(SCH_1):GND
   11  GND             IO11  @BASEBOARD_FAB2_LIB.BASEBOARD_FAB2(SCH_1):GND
    8  FM_TPM_PRES_N    IO8  @BASEBOARD_FAB2_LIB.BASEBOARD_FAB2(SCH_1):FM_TPM_PRES_N

SCONN80_E67482007_SM  I119  J8E3   [SCONN80_E67482007_SM-CONN,E674A]
    6  TP_RSVD_B1       IO6  @BASEBOARD_FAB2_LIB.BASEBOARD_FAB2(SCH_1):TP_RSVD_B1
   79  RST_PCIE_CPU_DEV3_R_N   IO79  @BASEBOARD_FAB2_LIB.BASEBOARD_FAB2(SCH_1):RST_PCIE_CPU_DEV3_R_N
   77  RST_PCIE_CPU_DEV2_R_N   IO77  @BASEBOARD_FAB2_LIB.BASEBOARD_FAB2(SCH_1):RST_PCIE_CPU_DEV2_R_N
   75  RST_PCIE_CPU_DEV1_R_N   IO75  @BASEBOARD_FAB2_LIB.BASEBOARD_FAB2(SCH_1):RST_PCIE_CPU_DEV1_R_N
   10  P3E_OCP_CPU0_PE3_C_TXP<7>   IO10  @BASEBOARD_FAB2_LIB.BASEBOARD_FAB2(SCH_1):P3E_OCP_CPU0_PE3_C_TXP<7>
   18  P3E_OCP_CPU0_PE3_C_TXP<6>   IO18  @BASEBOARD_FAB2_LIB.BASEBOARD_FAB2(SCH_1):P3E_OCP_CPU0_PE3_C_TXP<6>
   26  P3E_OCP_CPU0_PE3_C_TXP<5>   IO26  @BASEBOARD_FAB2_LIB.BASEBOARD_FAB2(SCH_1):P3E_OCP_CPU0_PE3_C_TXP<5>
   34  P3E_OCP_CPU0_PE3_C_TXP<4>   IO34  @BASEBOARD_FAB2_LIB.BASEBOARD_FAB2(SCH_1):P3E_OCP_CPU0_PE3_C_TXP<4>
   42  P3E_OCP_CPU0_PE3_C_TXP<3>   IO42  @BASEBOARD_FAB2_LIB.BASEBOARD_FAB2(SCH_1):P3E_OCP_CPU0_PE3_C_TXP<3>
   50  P3E_OCP_CPU0_PE3_C_TXP<2>   IO50  @BASEBOARD_FAB2_LIB.BASEBOARD_FAB2(SCH_1):P3E_OCP_CPU0_PE3_C_TXP<2>
   58  P3E_OCP_CPU0_PE3_C_TXP<1>   IO58  @BASEBOARD_FAB2_LIB.BASEBOARD_FAB2(SCH_1):P3E_OCP_CPU0_PE3_C_TXP<1>
   66  P3E_OCP_CPU0_PE3_C_TXP<0>   IO66  @BASEBOARD_FAB2_LIB.BASEBOARD_FAB2(SCH_1):P3E_OCP_CPU0_PE3_C_TXP<0>
   12  P3E_OCP_CPU0_PE3_C_TXN<7>   IO12  @BASEBOARD_FAB2_LIB.BASEBOARD_FAB2(SCH_1):P3E_OCP_CPU0_PE3_C_TXN<7>
   20  P3E_OCP_CPU0_PE3_C_TXN<6>   IO20  @BASEBOARD_FAB2_LIB.BASEBOARD_FAB2(SCH_1):P3E_OCP_CPU0_PE3_C_TXN<6>
   28  P3E_OCP_CPU0_PE3_C_TXN<5>   IO28  @BASEBOARD_FAB2_LIB.BASEBOARD_FAB2(SCH_1):P3E_OCP_CPU0_PE3_C_TXN<5>
   36  P3E_OCP_CPU0_PE3_C_TXN<4>   IO36  @BASEBOARD_FAB2_LIB.BASEBOARD_FAB2(SCH_1):P3E_OCP_CPU0_PE3_C_TXN<4>
   44  P3E_OCP_CPU0_PE3_C_TXN<3>   IO44  @BASEBOARD_FAB2_LIB.BASEBOARD_FAB2(SCH_1):P3E_OCP_CPU0_PE3_C_TXN<3>
   52  P3E_OCP_CPU0_PE3_C_TXN<2>   IO52  @BASEBOARD_FAB2_LIB.BASEBOARD_FAB2(SCH_1):P3E_OCP_CPU0_PE3_C_TXN<2>
   60  P3E_OCP_CPU0_PE3_C_TXN<1>   IO60  @BASEBOARD_FAB2_LIB.BASEBOARD_FAB2(SCH_1):P3E_OCP_CPU0_PE3_C_TXN<1>
   68  P3E_OCP_CPU0_PE3_C_TXN<0>   IO68  @BASEBOARD_FAB2_LIB.BASEBOARD_FAB2(SCH_1):P3E_OCP_CPU0_PE3_C_TXN<0>
    5  P3E_CPU0_PE3_OCP_RXP<7>    IO5  @BASEBOARD_FAB2_LIB.BASEBOARD_FAB2(SCH_1):P3E_CPU0_PE3_OCP_RXP<7>
   15  P3E_CPU0_PE3_OCP_RXP<6>   IO15  @BASEBOARD_FAB2_LIB.BASEBOARD_FAB2(SCH_1):P3E_CPU0_PE3_OCP_RXP<6>
   23  P3E_CPU0_PE3_OCP_RXP<5>   IO23  @BASEBOARD_FAB2_LIB.BASEBOARD_FAB2(SCH_1):P3E_CPU0_PE3_OCP_RXP<5>
   31  P3E_CPU0_PE3_OCP_RXP<4>   IO31  @BASEBOARD_FAB2_LIB.BASEBOARD_FAB2(SCH_1):P3E_CPU0_PE3_OCP_RXP<4>
   37  P3E_CPU0_PE3_OCP_RXP<3>   IO37  @BASEBOARD_FAB2_LIB.BASEBOARD_FAB2(SCH_1):P3E_CPU0_PE3_OCP_RXP<3>
   45  P3E_CPU0_PE3_OCP_RXP<2>   IO45  @BASEBOARD_FAB2_LIB.BASEBOARD_FAB2(SCH_1):P3E_CPU0_PE3_OCP_RXP<2>
   53  P3E_CPU0_PE3_OCP_RXP<1>   IO53  @BASEBOARD_FAB2_LIB.BASEBOARD_FAB2(SCH_1):P3E_CPU0_PE3_OCP_RXP<1>
   61  P3E_CPU0_PE3_OCP_RXP<0>   IO61  @BASEBOARD_FAB2_LIB.BASEBOARD_FAB2(SCH_1):P3E_CPU0_PE3_OCP_RXP<0>
    7  P3E_CPU0_PE3_OCP_RXN<7>    IO7  @BASEBOARD_FAB2_LIB.BASEBOARD_FAB2(SCH_1):P3E_CPU0_PE3_OCP_RXN<7>
   13  P3E_CPU0_PE3_OCP_RXN<6>   IO13  @BASEBOARD_FAB2_LIB.BASEBOARD_FAB2(SCH_1):P3E_CPU0_PE3_OCP_RXN<6>
   21  P3E_CPU0_PE3_OCP_RXN<5>   IO21  @BASEBOARD_FAB2_LIB.BASEBOARD_FAB2(SCH_1):P3E_CPU0_PE3_OCP_RXN<5>
   29  P3E_CPU0_PE3_OCP_RXN<4>   IO29  @BASEBOARD_FAB2_LIB.BASEBOARD_FAB2(SCH_1):P3E_CPU0_PE3_OCP_RXN<4>
   39  P3E_CPU0_PE3_OCP_RXN<3>   IO39  @BASEBOARD_FAB2_LIB.BASEBOARD_FAB2(SCH_1):P3E_CPU0_PE3_OCP_RXN<3>
   47  P3E_CPU0_PE3_OCP_RXN<2>   IO47  @BASEBOARD_FAB2_LIB.BASEBOARD_FAB2(SCH_1):P3E_CPU0_PE3_OCP_RXN<2>
   55  P3E_CPU0_PE3_OCP_RXN<1>   IO55  @BASEBOARD_FAB2_LIB.BASEBOARD_FAB2(SCH_1):P3E_CPU0_PE3_OCP_RXN<1>
   63  P3E_CPU0_PE3_OCP_RXN<0>   IO63  @BASEBOARD_FAB2_LIB.BASEBOARD_FAB2(SCH_1):P3E_CPU0_PE3_OCP_RXN<0>
    4  P12V_STBY        IO4  @BASEBOARD_FAB2_LIB.BASEBOARD_FAB2(SCH_1):P12V_STBY
    2  P12V_STBY        IO2  @BASEBOARD_FAB2_LIB.BASEBOARD_FAB2(SCH_1):P12V_STBY
   78  GND             IO78  @BASEBOARD_FAB2_LIB.BASEBOARD_FAB2(SCH_1):GND
   73  GND             IO73  @BASEBOARD_FAB2_LIB.BASEBOARD_FAB2(SCH_1):GND
   72  GND             IO72  @BASEBOARD_FAB2_LIB.BASEBOARD_FAB2(SCH_1):GND
   70  GND             IO70  @BASEBOARD_FAB2_LIB.BASEBOARD_FAB2(SCH_1):GND
   67  GND             IO67  @BASEBOARD_FAB2_LIB.BASEBOARD_FAB2(SCH_1):GND
   65  GND             IO65  @BASEBOARD_FAB2_LIB.BASEBOARD_FAB2(SCH_1):GND
   64  GND             IO64  @BASEBOARD_FAB2_LIB.BASEBOARD_FAB2(SCH_1):GND
   62  GND             IO62  @BASEBOARD_FAB2_LIB.BASEBOARD_FAB2(SCH_1):GND
   59  GND             IO59  @BASEBOARD_FAB2_LIB.BASEBOARD_FAB2(SCH_1):GND
   57  GND             IO57  @BASEBOARD_FAB2_LIB.BASEBOARD_FAB2(SCH_1):GND
   56  GND             IO56  @BASEBOARD_FAB2_LIB.BASEBOARD_FAB2(SCH_1):GND
   54  GND             IO54  @BASEBOARD_FAB2_LIB.BASEBOARD_FAB2(SCH_1):GND
   51  GND             IO51  @BASEBOARD_FAB2_LIB.BASEBOARD_FAB2(SCH_1):GND
   49  GND             IO49  @BASEBOARD_FAB2_LIB.BASEBOARD_FAB2(SCH_1):GND
   48  GND             IO48  @BASEBOARD_FAB2_LIB.BASEBOARD_FAB2(SCH_1):GND
   46  GND             IO46  @BASEBOARD_FAB2_LIB.BASEBOARD_FAB2(SCH_1):GND
   43  GND             IO43  @BASEBOARD_FAB2_LIB.BASEBOARD_FAB2(SCH_1):GND
   41  GND             IO41  @BASEBOARD_FAB2_LIB.BASEBOARD_FAB2(SCH_1):GND
   40  GND             IO40  @BASEBOARD_FAB2_LIB.BASEBOARD_FAB2(SCH_1):GND
   38  GND             IO38  @BASEBOARD_FAB2_LIB.BASEBOARD_FAB2(SCH_1):GND
   35  GND             IO35  @BASEBOARD_FAB2_LIB.BASEBOARD_FAB2(SCH_1):GND
   33  GND             IO33  @BASEBOARD_FAB2_LIB.BASEBOARD_FAB2(SCH_1):GND
   32  GND             IO32  @BASEBOARD_FAB2_LIB.BASEBOARD_FAB2(SCH_1):GND
   30  GND             IO30  @BASEBOARD_FAB2_LIB.BASEBOARD_FAB2(SCH_1):GND
   27  GND             IO27  @BASEBOARD_FAB2_LIB.BASEBOARD_FAB2(SCH_1):GND
   25  GND             IO25  @BASEBOARD_FAB2_LIB.BASEBOARD_FAB2(SCH_1):GND
   24  GND             IO24  @BASEBOARD_FAB2_LIB.BASEBOARD_FAB2(SCH_1):GND
   22  GND             IO22  @BASEBOARD_FAB2_LIB.BASEBOARD_FAB2(SCH_1):GND
   19  GND             IO19  @BASEBOARD_FAB2_LIB.BASEBOARD_FAB2(SCH_1):GND
   17  GND             IO17  @BASEBOARD_FAB2_LIB.BASEBOARD_FAB2(SCH_1):GND
   16  GND             IO16  @BASEBOARD_FAB2_LIB.BASEBOARD_FAB2(SCH_1):GND
   14  GND             IO14  @BASEBOARD_FAB2_LIB.BASEBOARD_FAB2(SCH_1):GND
   11  GND             IO11  @BASEBOARD_FAB2_LIB.BASEBOARD_FAB2(SCH_1):GND
    9  GND              IO9  @BASEBOARD_FAB2_LIB.BASEBOARD_FAB2(SCH_1):GND
    8  GND              IO8  @BASEBOARD_FAB2_LIB.BASEBOARD_FAB2(SCH_1):GND
    3  GND              IO3  @BASEBOARD_FAB2_LIB.BASEBOARD_FAB2(SCH_1):GND
   80  FM_OCP_MEZZB_PRES_N   IO80  @BASEBOARD_FAB2_LIB.BASEBOARD_FAB2(SCH_1):FM_OCP_MEZZB_PRES_N
    1  FM_MEZZ_PRSNTB1_N    IO1  @BASEBOARD_FAB2_LIB.BASEBOARD_FAB2(SCH_1):FM_MEZZ_PRSNTB1_N
   74  CLK_100M_MEZZ4_DP   IO74  @BASEBOARD_FAB2_LIB.BASEBOARD_FAB2(SCH_1):CLK_100M_MEZZ4_DP
   76  CLK_100M_MEZZ4_DN   IO76  @BASEBOARD_FAB2_LIB.BASEBOARD_FAB2(SCH_1):CLK_100M_MEZZ4_DN
   69  CLK_100M_MEZZ3_DP   IO69  @BASEBOARD_FAB2_LIB.BASEBOARD_FAB2(SCH_1):CLK_100M_MEZZ3_DP
   71  CLK_100M_MEZZ3_DN   IO71  @BASEBOARD_FAB2_LIB.BASEBOARD_FAB2(SCH_1):CLK_100M_MEZZ3_DN

SCONN64_H87568002_A_SMT  I27  J8E4   [SCONN64_H87568002_A_SMT-CONN,HA]
   50  TP_SHARED_KR_MDIO_0   IO50  @BASEBOARD_FAB2_LIB.BASEBOARD_FAB2(SCH_1):TP_SHARED_KR_MDIO_0
   49  TP_SHARED_KR_MDC_0   IO49  @BASEBOARD_FAB2_LIB.BASEBOARD_FAB2(SCH_1):TP_SHARED_KR_MDC_0
   36  TP_RSVD<0>      IO36  @BASEBOARD_FAB2_LIB.BASEBOARD_FAB2(SCH_1):TP_RSVD<0>
    3  TP_EXT_MDIO_I2C_SEL    IO3  @BASEBOARD_FAB2_LIB.BASEBOARD_FAB2(SCH_1):TP_EXT_MDIO_I2C_SEL
   30  SMB_PCH_MEZZ_LOM3_SDA   IO30  @BASEBOARD_FAB2_LIB.BASEBOARD_FAB2(SCH_1):SMB_PCH_MEZZ_LOM3_SDA
   29  SMB_PCH_MEZZ_LOM3_SCL   IO29  @BASEBOARD_FAB2_LIB.BASEBOARD_FAB2(SCH_1):SMB_PCH_MEZZ_LOM3_SCL
   62  SMB_PCH_MEZZ_LOM2_SDA   IO62  @BASEBOARD_FAB2_LIB.BASEBOARD_FAB2(SCH_1):SMB_PCH_MEZZ_LOM2_SDA
   61  SMB_PCH_MEZZ_LOM2_SCL   IO61  @BASEBOARD_FAB2_LIB.BASEBOARD_FAB2(SCH_1):SMB_PCH_MEZZ_LOM2_SCL
   27  SMB_PCH_MEZZ_LOM1_SDA   IO27  @BASEBOARD_FAB2_LIB.BASEBOARD_FAB2(SCH_1):SMB_PCH_MEZZ_LOM1_SDA
   26  SMB_PCH_MEZZ_LOM1_SCL   IO26  @BASEBOARD_FAB2_LIB.BASEBOARD_FAB2(SCH_1):SMB_PCH_MEZZ_LOM1_SCL
   21  SMB_PCH_MEZZ_LOM0_SDA   IO21  @BASEBOARD_FAB2_LIB.BASEBOARD_FAB2(SCH_1):SMB_PCH_MEZZ_LOM0_SDA
   20  SMB_PCH_MEZZ_LOM0_SCL   IO20  @BASEBOARD_FAB2_LIB.BASEBOARD_FAB2(SCH_1):SMB_PCH_MEZZ_LOM0_SCL
    2  SMB_OCP_FRU_STBY_LVC3_SDA    IO2  @BASEBOARD_FAB2_LIB.BASEBOARD_FAB2(SCH_1):SMB_OCP_FRU_STBY_LVC3_SDA
    1  SMB_OCP_FRU_STBY_LVC3_SCL    IO1  @BASEBOARD_FAB2_LIB.BASEBOARD_FAB2(SCH_1):SMB_OCP_FRU_STBY_LVC3_SCL
   35  P12V_STBY       IO35  @BASEBOARD_FAB2_LIB.BASEBOARD_FAB2(SCH_1):P12V_STBY
   34  P12V_STBY       IO34  @BASEBOARD_FAB2_LIB.BASEBOARD_FAB2(SCH_1):P12V_STBY
   33  P12V_STBY       IO33  @BASEBOARD_FAB2_LIB.BASEBOARD_FAB2(SCH_1):P12V_STBY
   56  LED_GBE_P3_1    IO56  @BASEBOARD_FAB2_LIB.BASEBOARD_FAB2(SCH_1):LED_GBE_P3_1
   55  LED_GBE_P3_0    IO55  @BASEBOARD_FAB2_LIB.BASEBOARD_FAB2(SCH_1):LED_GBE_P3_0
   15  LED_GBE_P2_1    IO15  @BASEBOARD_FAB2_LIB.BASEBOARD_FAB2(SCH_1):LED_GBE_P2_1
   14  LED_GBE_P2_0    IO14  @BASEBOARD_FAB2_LIB.BASEBOARD_FAB2(SCH_1):LED_GBE_P2_0
    9  LED_GBE_P1_1     IO9  @BASEBOARD_FAB2_LIB.BASEBOARD_FAB2(SCH_1):LED_GBE_P1_1
    8  LED_GBE_P1_0     IO8  @BASEBOARD_FAB2_LIB.BASEBOARD_FAB2(SCH_1):LED_GBE_P1_0
   44  LED_GBE_P0_1    IO44  @BASEBOARD_FAB2_LIB.BASEBOARD_FAB2(SCH_1):LED_GBE_P0_1
   43  LED_GBE_P0_0    IO43  @BASEBOARD_FAB2_LIB.BASEBOARD_FAB2(SCH_1):LED_GBE_P0_0
   11  KR_P3_OCP_TX_DP   IO11  @BASEBOARD_FAB2_LIB.BASEBOARD_FAB2(SCH_1):KR_P3_OCP_TX_DP
   12  KR_P3_OCP_TX_DN   IO12  @BASEBOARD_FAB2_LIB.BASEBOARD_FAB2(SCH_1):KR_P3_OCP_TX_DN
   23  KR_P3_OCP_RX_DP   IO23  @BASEBOARD_FAB2_LIB.BASEBOARD_FAB2(SCH_1):KR_P3_OCP_RX_DP
   24  KR_P3_OCP_RX_DN   IO24  @BASEBOARD_FAB2_LIB.BASEBOARD_FAB2(SCH_1):KR_P3_OCP_RX_DN
    5  KR_P2_OCP_TX_DP    IO5  @BASEBOARD_FAB2_LIB.BASEBOARD_FAB2(SCH_1):KR_P2_OCP_TX_DP
    6  KR_P2_OCP_TX_DN    IO6  @BASEBOARD_FAB2_LIB.BASEBOARD_FAB2(SCH_1):KR_P2_OCP_TX_DN
   17  KR_P2_OCP_RX_DP   IO17  @BASEBOARD_FAB2_LIB.BASEBOARD_FAB2(SCH_1):KR_P2_OCP_RX_DP
   18  KR_P2_OCP_RX_DN   IO18  @BASEBOARD_FAB2_LIB.BASEBOARD_FAB2(SCH_1):KR_P2_OCP_RX_DN
   46  KR_P1_OCP_TX_DP   IO46  @BASEBOARD_FAB2_LIB.BASEBOARD_FAB2(SCH_1):KR_P1_OCP_TX_DP
   47  KR_P1_OCP_TX_DN   IO47  @BASEBOARD_FAB2_LIB.BASEBOARD_FAB2(SCH_1):KR_P1_OCP_TX_DN
   58  KR_P1_OCP_RX_DP   IO58  @BASEBOARD_FAB2_LIB.BASEBOARD_FAB2(SCH_1):KR_P1_OCP_RX_DP
   59  KR_P1_OCP_RX_DN   IO59  @BASEBOARD_FAB2_LIB.BASEBOARD_FAB2(SCH_1):KR_P1_OCP_RX_DN
   40  KR_P0_OCP_TX_DP   IO40  @BASEBOARD_FAB2_LIB.BASEBOARD_FAB2(SCH_1):KR_P0_OCP_TX_DP
   41  KR_P0_OCP_TX_DN   IO41  @BASEBOARD_FAB2_LIB.BASEBOARD_FAB2(SCH_1):KR_P0_OCP_TX_DN
   52  KR_P0_OCP_RX_DP   IO52  @BASEBOARD_FAB2_LIB.BASEBOARD_FAB2(SCH_1):KR_P0_OCP_RX_DP
   53  KR_P0_OCP_RX_DN   IO53  @BASEBOARD_FAB2_LIB.BASEBOARD_FAB2(SCH_1):KR_P0_OCP_RX_DN
   63  GND             IO63  @BASEBOARD_FAB2_LIB.BASEBOARD_FAB2(SCH_1):GND
   60  GND             IO60  @BASEBOARD_FAB2_LIB.BASEBOARD_FAB2(SCH_1):GND
   57  GND             IO57  @BASEBOARD_FAB2_LIB.BASEBOARD_FAB2(SCH_1):GND
   54  GND             IO54  @BASEBOARD_FAB2_LIB.BASEBOARD_FAB2(SCH_1):GND
   51  GND             IO51  @BASEBOARD_FAB2_LIB.BASEBOARD_FAB2(SCH_1):GND
   48  GND             IO48  @BASEBOARD_FAB2_LIB.BASEBOARD_FAB2(SCH_1):GND
   45  GND             IO45  @BASEBOARD_FAB2_LIB.BASEBOARD_FAB2(SCH_1):GND
   42  GND             IO42  @BASEBOARD_FAB2_LIB.BASEBOARD_FAB2(SCH_1):GND
   39  GND             IO39  @BASEBOARD_FAB2_LIB.BASEBOARD_FAB2(SCH_1):GND
   28  GND             IO28  @BASEBOARD_FAB2_LIB.BASEBOARD_FAB2(SCH_1):GND
   25  GND             IO25  @BASEBOARD_FAB2_LIB.BASEBOARD_FAB2(SCH_1):GND
   22  GND             IO22  @BASEBOARD_FAB2_LIB.BASEBOARD_FAB2(SCH_1):GND
   19  GND             IO19  @BASEBOARD_FAB2_LIB.BASEBOARD_FAB2(SCH_1):GND
   16  GND             IO16  @BASEBOARD_FAB2_LIB.BASEBOARD_FAB2(SCH_1):GND
   13  GND             IO13  @BASEBOARD_FAB2_LIB.BASEBOARD_FAB2(SCH_1):GND
   10  GND             IO10  @BASEBOARD_FAB2_LIB.BASEBOARD_FAB2(SCH_1):GND
    7  GND              IO7  @BASEBOARD_FAB2_LIB.BASEBOARD_FAB2(SCH_1):GND
    4  GND              IO4  @BASEBOARD_FAB2_LIB.BASEBOARD_FAB2(SCH_1):GND
   64  FM_OCP_MEZZC_PRES_N   IO64  @BASEBOARD_FAB2_LIB.BASEBOARD_FAB2(SCH_1):FM_OCP_MEZZC_PRES_N
   32  FM_GBE3_LVC3_MOD_ABS   IO32  @BASEBOARD_FAB2_LIB.BASEBOARD_FAB2(SCH_1):FM_GBE3_LVC3_MOD_ABS
   31  FM_GBE2_LVC3_MOD_ABS   IO31  @BASEBOARD_FAB2_LIB.BASEBOARD_FAB2(SCH_1):FM_GBE2_LVC3_MOD_ABS
   38  FM_GBE1_LVC3_MOD_ABS   IO38  @BASEBOARD_FAB2_LIB.BASEBOARD_FAB2(SCH_1):FM_GBE1_LVC3_MOD_ABS
   37  FM_GBE0_LVC3_MOD_ABS   IO37  @BASEBOARD_FAB2_LIB.BASEBOARD_FAB2(SCH_1):FM_GBE0_LVC3_MOD_ABS

SCONN75K_H17033002_SMT1  I53  J8F1   [SCONN75K_H17033002_SMT1-SCONN,A]
   38  TP_M2_DEVSLP   DEVSLP  @BASEBOARD_FAB2_LIB.BASEBOARD_FAB2(SCH_1):TP_M2_DEVSLP
   68  TP_M2_32M_SUSCLK  SUSCLK  @BASEBOARD_FAB2_LIB.BASEBOARD_FAB2(SCH_1):TP_M2_32M_SUSCLK
   10  TP_LED_M2_ACT_N  DAS_DSS_N  @BASEBOARD_FAB2_LIB.BASEBOARD_FAB2(SCH_1):TP_LED_M2_ACT_N
   50  RST_PCIE_M2_DEV_N  PERST_N_NC  @BASEBOARD_FAB2_LIB.BASEBOARD_FAB2(SCH_1):RST_PCIE_M2_DEV_N
   52  PU_M2_CLK_REQ_N  CLKREQ_N_NC  @BASEBOARD_FAB2_LIB.BASEBOARD_FAB2(SCH_1):PU_M2_CLK_REQ_N
   74  P3V3           3_3V<8>  @BASEBOARD_FAB2_LIB.BASEBOARD_FAB2(SCH_1):P3V3
   72  P3V3           3_3V<7>  @BASEBOARD_FAB2_LIB.BASEBOARD_FAB2(SCH_1):P3V3
   70  P3V3           3_3V<6>  @BASEBOARD_FAB2_LIB.BASEBOARD_FAB2(SCH_1):P3V3
   18  P3V3           3_3V<5>  @BASEBOARD_FAB2_LIB.BASEBOARD_FAB2(SCH_1):P3V3
   16  P3V3           3_3V<4>  @BASEBOARD_FAB2_LIB.BASEBOARD_FAB2(SCH_1):P3V3
   14  P3V3           3_3V<3>  @BASEBOARD_FAB2_LIB.BASEBOARD_FAB2(SCH_1):P3V3
   12  P3V3           3_3V<2>  @BASEBOARD_FAB2_LIB.BASEBOARD_FAB2(SCH_1):P3V3
    4  P3V3           3_3V<1>  @BASEBOARD_FAB2_LIB.BASEBOARD_FAB2(SCH_1):P3V3
    2  P3V3           3_3V<0>  @BASEBOARD_FAB2_LIB.BASEBOARD_FAB2(SCH_1):P3V3
   13  P3E_PCH_M2_TX_C_DP<3>  PETP3  @BASEBOARD_FAB2_LIB.BASEBOARD_FAB2(SCH_1):P3E_PCH_M2_TX_C_DP<3>
   25  P3E_PCH_M2_TX_C_DP<2>  PETP2  @BASEBOARD_FAB2_LIB.BASEBOARD_FAB2(SCH_1):P3E_PCH_M2_TX_C_DP<2>
   37  P3E_PCH_M2_TX_C_DP<1>  PETP1  @BASEBOARD_FAB2_LIB.BASEBOARD_FAB2(SCH_1):P3E_PCH_M2_TX_C_DP<1>
   11  P3E_PCH_M2_TX_C_DN<3>  PETN3  @BASEBOARD_FAB2_LIB.BASEBOARD_FAB2(SCH_1):P3E_PCH_M2_TX_C_DN<3>
   23  P3E_PCH_M2_TX_C_DN<2>  PETN2  @BASEBOARD_FAB2_LIB.BASEBOARD_FAB2(SCH_1):P3E_PCH_M2_TX_C_DN<2>
   35  P3E_PCH_M2_TX_C_DN<1>  PETN1  @BASEBOARD_FAB2_LIB.BASEBOARD_FAB2(SCH_1):P3E_PCH_M2_TX_C_DN<1>
   49  P3E_PCH_M2_SATA6G_TX_R_DP  PETP0_SATA_AP  @BASEBOARD_FAB2_LIB.BASEBOARD_FAB2(SCH_1):P3E_PCH_M2_SATA6G_TX_R_DP
   47  P3E_PCH_M2_SATA6G_TX_R_DN  PETN0_SATA_AN  @BASEBOARD_FAB2_LIB.BASEBOARD_FAB2(SCH_1):P3E_PCH_M2_SATA6G_TX_R_DN
   41  P3E_PCH_M2_SATA6G_RX_R_DP  PERN0_SATA_BP  @BASEBOARD_FAB2_LIB.BASEBOARD_FAB2(SCH_1):P3E_PCH_M2_SATA6G_RX_R_DP
   43  P3E_PCH_M2_SATA6G_RX_R_DN  PERP0_SATA_BN  @BASEBOARD_FAB2_LIB.BASEBOARD_FAB2(SCH_1):P3E_PCH_M2_SATA6G_RX_R_DN
    7  P3E_PCH_M2_RX_DP<3>  PERP3  @BASEBOARD_FAB2_LIB.BASEBOARD_FAB2(SCH_1):P3E_PCH_M2_RX_DP<3>
   19  P3E_PCH_M2_RX_DP<2>  PERP2  @BASEBOARD_FAB2_LIB.BASEBOARD_FAB2(SCH_1):P3E_PCH_M2_RX_DP<2>
   31  P3E_PCH_M2_RX_DP<1>  PERP1  @BASEBOARD_FAB2_LIB.BASEBOARD_FAB2(SCH_1):P3E_PCH_M2_RX_DP<1>
    5  P3E_PCH_M2_RX_DN<3>  PERN3  @BASEBOARD_FAB2_LIB.BASEBOARD_FAB2(SCH_1):P3E_PCH_M2_RX_DN<3>
   17  P3E_PCH_M2_RX_DN<2>  PERN2  @BASEBOARD_FAB2_LIB.BASEBOARD_FAB2(SCH_1):P3E_PCH_M2_RX_DN<2>
   29  P3E_PCH_M2_RX_DN<1>  PERN1  @BASEBOARD_FAB2_LIB.BASEBOARD_FAB2(SCH_1):P3E_PCH_M2_RX_DN<1>
   34  NC_M2<9>       NC<9>  @BASEBOARD_FAB2_LIB.BASEBOARD_FAB2(SCH_1):NC_M2<9>
   32  NC_M2<8>       NC<8>  @BASEBOARD_FAB2_LIB.BASEBOARD_FAB2(SCH_1):NC_M2<8>
   30  NC_M2<7>       NC<7>  @BASEBOARD_FAB2_LIB.BASEBOARD_FAB2(SCH_1):NC_M2<7>
   28  NC_M2<6>       NC<6>  @BASEBOARD_FAB2_LIB.BASEBOARD_FAB2(SCH_1):NC_M2<6>
   26  NC_M2<5>       NC<5>  @BASEBOARD_FAB2_LIB.BASEBOARD_FAB2(SCH_1):NC_M2<5>
   24  NC_M2<4>       NC<4>  @BASEBOARD_FAB2_LIB.BASEBOARD_FAB2(SCH_1):NC_M2<4>
   22  NC_M2<3>       NC<3>  @BASEBOARD_FAB2_LIB.BASEBOARD_FAB2(SCH_1):NC_M2<3>
   20  NC_M2<2>       NC<2>  @BASEBOARD_FAB2_LIB.BASEBOARD_FAB2(SCH_1):NC_M2<2>
    8  NC_M2<1>       NC<1>  @BASEBOARD_FAB2_LIB.BASEBOARD_FAB2(SCH_1):NC_M2<1>
   67  NC_M2<18>      NC<18>  @BASEBOARD_FAB2_LIB.BASEBOARD_FAB2(SCH_1):NC_M2<18>
   58  NC_M2<17>      NC<17>  @BASEBOARD_FAB2_LIB.BASEBOARD_FAB2(SCH_1):NC_M2<17>
   56  NC_M2<16>      NC<16>  @BASEBOARD_FAB2_LIB.BASEBOARD_FAB2(SCH_1):NC_M2<16>
   48  NC_M2<15>      NC<15>  @BASEBOARD_FAB2_LIB.BASEBOARD_FAB2(SCH_1):NC_M2<15>
   46  NC_M2<14>      NC<14>  @BASEBOARD_FAB2_LIB.BASEBOARD_FAB2(SCH_1):NC_M2<14>
   44  NC_M2<13>      NC<13>  @BASEBOARD_FAB2_LIB.BASEBOARD_FAB2(SCH_1):NC_M2<13>
   42  NC_M2<12>      NC<12>  @BASEBOARD_FAB2_LIB.BASEBOARD_FAB2(SCH_1):NC_M2<12>
   40  NC_M2<11>      NC<11>  @BASEBOARD_FAB2_LIB.BASEBOARD_FAB2(SCH_1):NC_M2<11>
   36  NC_M2<10>      NC<10>  @BASEBOARD_FAB2_LIB.BASEBOARD_FAB2(SCH_1):NC_M2<10>
    6  NC_M2<0>       NC<0>  @BASEBOARD_FAB2_LIB.BASEBOARD_FAB2(SCH_1):NC_M2<0>
  MP2  GND              MP2  @BASEBOARD_FAB2_LIB.BASEBOARD_FAB2(SCH_1):GND
  MP1  GND              MP1  @BASEBOARD_FAB2_LIB.BASEBOARD_FAB2(SCH_1):GND
   75  GND            GND<13>  @BASEBOARD_FAB2_LIB.BASEBOARD_FAB2(SCH_1):GND
   73  GND            GND<12>  @BASEBOARD_FAB2_LIB.BASEBOARD_FAB2(SCH_1):GND
   71  GND            GND<11>  @BASEBOARD_FAB2_LIB.BASEBOARD_FAB2(SCH_1):GND
   57  GND            GND<10>  @BASEBOARD_FAB2_LIB.BASEBOARD_FAB2(SCH_1):GND
   51  GND            GND<9>  @BASEBOARD_FAB2_LIB.BASEBOARD_FAB2(SCH_1):GND
   45  GND            GND<8>  @BASEBOARD_FAB2_LIB.BASEBOARD_FAB2(SCH_1):GND
   39  GND            GND<7>  @BASEBOARD_FAB2_LIB.BASEBOARD_FAB2(SCH_1):GND
   33  GND            GND<6>  @BASEBOARD_FAB2_LIB.BASEBOARD_FAB2(SCH_1):GND
   27  GND            GND<5>  @BASEBOARD_FAB2_LIB.BASEBOARD_FAB2(SCH_1):GND
   21  GND            GND<4>  @BASEBOARD_FAB2_LIB.BASEBOARD_FAB2(SCH_1):GND
   15  GND            GND<3>  @BASEBOARD_FAB2_LIB.BASEBOARD_FAB2(SCH_1):GND
    9  GND            GND<2>  @BASEBOARD_FAB2_LIB.BASEBOARD_FAB2(SCH_1):GND
    3  GND            GND<1>  @BASEBOARD_FAB2_LIB.BASEBOARD_FAB2(SCH_1):GND
    1  GND            GND<0>  @BASEBOARD_FAB2_LIB.BASEBOARD_FAB2(SCH_1):GND
   54  FM_PE_M2_WAKE_N  PEWAKE_N_NC  @BASEBOARD_FAB2_LIB.BASEBOARD_FAB2(SCH_1):FM_PE_M2_WAKE_N
   69  FM_M2_SSD_PEDET  PEDET  @BASEBOARD_FAB2_LIB.BASEBOARD_FAB2(SCH_1):FM_M2_SSD_PEDET
   55  CLK_100M_M2_DP  REFCLKP  @BASEBOARD_FAB2_LIB.BASEBOARD_FAB2(SCH_1):CLK_100M_M2_DP
   53  CLK_100M_M2_DN  REFCLKN  @BASEBOARD_FAB2_LIB.BASEBOARD_FAB2(SCH_1):CLK_100M_M2_DN

SCONN200_H68296001_SM  I243  J8G1   [SCONN200_H68296001_SM-CONN,H68A]
  162  P3E_CPU0_PE2_SS_RXP<9>  IO162  @BASEBOARD_FAB2_LIB.BASEBOARD_FAB2(SCH_1):P3E_CPU0_PE2_SS_RXP<9>
  156  P3E_CPU0_PE2_SS_RXP<8>  IO156  @BASEBOARD_FAB2_LIB.BASEBOARD_FAB2(SCH_1):P3E_CPU0_PE2_SS_RXP<8>
  150  P3E_CPU0_PE2_SS_RXP<7>  IO150  @BASEBOARD_FAB2_LIB.BASEBOARD_FAB2(SCH_1):P3E_CPU0_PE2_SS_RXP<7>
  142  P3E_CPU0_PE2_SS_RXP<6>  IO142  @BASEBOARD_FAB2_LIB.BASEBOARD_FAB2(SCH_1):P3E_CPU0_PE2_SS_RXP<6>
  138  P3E_CPU0_PE2_SS_RXP<5>  IO138  @BASEBOARD_FAB2_LIB.BASEBOARD_FAB2(SCH_1):P3E_CPU0_PE2_SS_RXP<5>
  132  P3E_CPU0_PE2_SS_RXP<4>  IO132  @BASEBOARD_FAB2_LIB.BASEBOARD_FAB2(SCH_1):P3E_CPU0_PE2_SS_RXP<4>
  126  P3E_CPU0_PE2_SS_RXP<3>  IO126  @BASEBOARD_FAB2_LIB.BASEBOARD_FAB2(SCH_1):P3E_CPU0_PE2_SS_RXP<3>
  120  P3E_CPU0_PE2_SS_RXP<2>  IO120  @BASEBOARD_FAB2_LIB.BASEBOARD_FAB2(SCH_1):P3E_CPU0_PE2_SS_RXP<2>
  114  P3E_CPU0_PE2_SS_RXP<1>  IO114  @BASEBOARD_FAB2_LIB.BASEBOARD_FAB2(SCH_1):P3E_CPU0_PE2_SS_RXP<1>
  198  P3E_CPU0_PE2_SS_RXP<15>  IO198  @BASEBOARD_FAB2_LIB.BASEBOARD_FAB2(SCH_1):P3E_CPU0_PE2_SS_RXP<15>
  192  P3E_CPU0_PE2_SS_RXP<14>  IO192  @BASEBOARD_FAB2_LIB.BASEBOARD_FAB2(SCH_1):P3E_CPU0_PE2_SS_RXP<14>
  184  P3E_CPU0_PE2_SS_RXP<13>  IO184  @BASEBOARD_FAB2_LIB.BASEBOARD_FAB2(SCH_1):P3E_CPU0_PE2_SS_RXP<13>
  180  P3E_CPU0_PE2_SS_RXP<12>  IO180  @BASEBOARD_FAB2_LIB.BASEBOARD_FAB2(SCH_1):P3E_CPU0_PE2_SS_RXP<12>
  174  P3E_CPU0_PE2_SS_RXP<11>  IO174  @BASEBOARD_FAB2_LIB.BASEBOARD_FAB2(SCH_1):P3E_CPU0_PE2_SS_RXP<11>
  168  P3E_CPU0_PE2_SS_RXP<10>  IO168  @BASEBOARD_FAB2_LIB.BASEBOARD_FAB2(SCH_1):P3E_CPU0_PE2_SS_RXP<10>
  108  P3E_CPU0_PE2_SS_RXP<0>  IO108  @BASEBOARD_FAB2_LIB.BASEBOARD_FAB2(SCH_1):P3E_CPU0_PE2_SS_RXP<0>
  160  P3E_CPU0_PE2_SS_RXN<9>  IO160  @BASEBOARD_FAB2_LIB.BASEBOARD_FAB2(SCH_1):P3E_CPU0_PE2_SS_RXN<9>
  154  P3E_CPU0_PE2_SS_RXN<8>  IO154  @BASEBOARD_FAB2_LIB.BASEBOARD_FAB2(SCH_1):P3E_CPU0_PE2_SS_RXN<8>
  148  P3E_CPU0_PE2_SS_RXN<7>  IO148  @BASEBOARD_FAB2_LIB.BASEBOARD_FAB2(SCH_1):P3E_CPU0_PE2_SS_RXN<7>
  144  P3E_CPU0_PE2_SS_RXN<6>  IO144  @BASEBOARD_FAB2_LIB.BASEBOARD_FAB2(SCH_1):P3E_CPU0_PE2_SS_RXN<6>
  136  P3E_CPU0_PE2_SS_RXN<5>  IO136  @BASEBOARD_FAB2_LIB.BASEBOARD_FAB2(SCH_1):P3E_CPU0_PE2_SS_RXN<5>
  130  P3E_CPU0_PE2_SS_RXN<4>  IO130  @BASEBOARD_FAB2_LIB.BASEBOARD_FAB2(SCH_1):P3E_CPU0_PE2_SS_RXN<4>
  124  P3E_CPU0_PE2_SS_RXN<3>  IO124  @BASEBOARD_FAB2_LIB.BASEBOARD_FAB2(SCH_1):P3E_CPU0_PE2_SS_RXN<3>
  118  P3E_CPU0_PE2_SS_RXN<2>  IO118  @BASEBOARD_FAB2_LIB.BASEBOARD_FAB2(SCH_1):P3E_CPU0_PE2_SS_RXN<2>
  112  P3E_CPU0_PE2_SS_RXN<1>  IO112  @BASEBOARD_FAB2_LIB.BASEBOARD_FAB2(SCH_1):P3E_CPU0_PE2_SS_RXN<1>
  196  P3E_CPU0_PE2_SS_RXN<15>  IO196  @BASEBOARD_FAB2_LIB.BASEBOARD_FAB2(SCH_1):P3E_CPU0_PE2_SS_RXN<15>
  190  P3E_CPU0_PE2_SS_RXN<14>  IO190  @BASEBOARD_FAB2_LIB.BASEBOARD_FAB2(SCH_1):P3E_CPU0_PE2_SS_RXN<14>
  186  P3E_CPU0_PE2_SS_RXN<13>  IO186  @BASEBOARD_FAB2_LIB.BASEBOARD_FAB2(SCH_1):P3E_CPU0_PE2_SS_RXN<13>
  178  P3E_CPU0_PE2_SS_RXN<12>  IO178  @BASEBOARD_FAB2_LIB.BASEBOARD_FAB2(SCH_1):P3E_CPU0_PE2_SS_RXN<12>
  172  P3E_CPU0_PE2_SS_RXN<11>  IO172  @BASEBOARD_FAB2_LIB.BASEBOARD_FAB2(SCH_1):P3E_CPU0_PE2_SS_RXN<11>
  166  P3E_CPU0_PE2_SS_RXN<10>  IO166  @BASEBOARD_FAB2_LIB.BASEBOARD_FAB2(SCH_1):P3E_CPU0_PE2_SS_RXN<10>
  106  P3E_CPU0_PE2_SS_RXN<0>  IO106  @BASEBOARD_FAB2_LIB.BASEBOARD_FAB2(SCH_1):P3E_CPU0_PE2_SS_RXN<0>
  159  P3E_CPU0_PE2_SS_C_TXP<9>  IO159  @BASEBOARD_FAB2_LIB.BASEBOARD_FAB2(SCH_1):P3E_CPU0_PE2_SS_C_TXP<9>
  153  P3E_CPU0_PE2_SS_C_TXP<8>  IO153  @BASEBOARD_FAB2_LIB.BASEBOARD_FAB2(SCH_1):P3E_CPU0_PE2_SS_C_TXP<8>
  147  P3E_CPU0_PE2_SS_C_TXP<7>  IO147  @BASEBOARD_FAB2_LIB.BASEBOARD_FAB2(SCH_1):P3E_CPU0_PE2_SS_C_TXP<7>
  141  P3E_CPU0_PE2_SS_C_TXP<6>  IO141  @BASEBOARD_FAB2_LIB.BASEBOARD_FAB2(SCH_1):P3E_CPU0_PE2_SS_C_TXP<6>
  135  P3E_CPU0_PE2_SS_C_TXP<5>  IO135  @BASEBOARD_FAB2_LIB.BASEBOARD_FAB2(SCH_1):P3E_CPU0_PE2_SS_C_TXP<5>
  129  P3E_CPU0_PE2_SS_C_TXP<4>  IO129  @BASEBOARD_FAB2_LIB.BASEBOARD_FAB2(SCH_1):P3E_CPU0_PE2_SS_C_TXP<4>
  123  P3E_CPU0_PE2_SS_C_TXP<3>  IO123  @BASEBOARD_FAB2_LIB.BASEBOARD_FAB2(SCH_1):P3E_CPU0_PE2_SS_C_TXP<3>
  117  P3E_CPU0_PE2_SS_C_TXP<2>  IO117  @BASEBOARD_FAB2_LIB.BASEBOARD_FAB2(SCH_1):P3E_CPU0_PE2_SS_C_TXP<2>
  109  P3E_CPU0_PE2_SS_C_TXP<1>  IO109  @BASEBOARD_FAB2_LIB.BASEBOARD_FAB2(SCH_1):P3E_CPU0_PE2_SS_C_TXP<1>
  195  P3E_CPU0_PE2_SS_C_TXP<15>  IO195  @BASEBOARD_FAB2_LIB.BASEBOARD_FAB2(SCH_1):P3E_CPU0_PE2_SS_C_TXP<15>
  187  P3E_CPU0_PE2_SS_C_TXP<14>  IO187  @BASEBOARD_FAB2_LIB.BASEBOARD_FAB2(SCH_1):P3E_CPU0_PE2_SS_C_TXP<14>
  183  P3E_CPU0_PE2_SS_C_TXP<13>  IO183  @BASEBOARD_FAB2_LIB.BASEBOARD_FAB2(SCH_1):P3E_CPU0_PE2_SS_C_TXP<13>
  177  P3E_CPU0_PE2_SS_C_TXP<12>  IO177  @BASEBOARD_FAB2_LIB.BASEBOARD_FAB2(SCH_1):P3E_CPU0_PE2_SS_C_TXP<12>
  169  P3E_CPU0_PE2_SS_C_TXP<11>  IO169  @BASEBOARD_FAB2_LIB.BASEBOARD_FAB2(SCH_1):P3E_CPU0_PE2_SS_C_TXP<11>
  165  P3E_CPU0_PE2_SS_C_TXP<10>  IO165  @BASEBOARD_FAB2_LIB.BASEBOARD_FAB2(SCH_1):P3E_CPU0_PE2_SS_C_TXP<10>
  105  P3E_CPU0_PE2_SS_C_TXP<0>  IO105  @BASEBOARD_FAB2_LIB.BASEBOARD_FAB2(SCH_1):P3E_CPU0_PE2_SS_C_TXP<0>
  157  P3E_CPU0_PE2_SS_C_TXN<9>  IO157  @BASEBOARD_FAB2_LIB.BASEBOARD_FAB2(SCH_1):P3E_CPU0_PE2_SS_C_TXN<9>
  151  P3E_CPU0_PE2_SS_C_TXN<8>  IO151  @BASEBOARD_FAB2_LIB.BASEBOARD_FAB2(SCH_1):P3E_CPU0_PE2_SS_C_TXN<8>
  145  P3E_CPU0_PE2_SS_C_TXN<7>  IO145  @BASEBOARD_FAB2_LIB.BASEBOARD_FAB2(SCH_1):P3E_CPU0_PE2_SS_C_TXN<7>
  139  P3E_CPU0_PE2_SS_C_TXN<6>  IO139  @BASEBOARD_FAB2_LIB.BASEBOARD_FAB2(SCH_1):P3E_CPU0_PE2_SS_C_TXN<6>
  133  P3E_CPU0_PE2_SS_C_TXN<5>  IO133  @BASEBOARD_FAB2_LIB.BASEBOARD_FAB2(SCH_1):P3E_CPU0_PE2_SS_C_TXN<5>
  127  P3E_CPU0_PE2_SS_C_TXN<4>  IO127  @BASEBOARD_FAB2_LIB.BASEBOARD_FAB2(SCH_1):P3E_CPU0_PE2_SS_C_TXN<4>
  121  P3E_CPU0_PE2_SS_C_TXN<3>  IO121  @BASEBOARD_FAB2_LIB.BASEBOARD_FAB2(SCH_1):P3E_CPU0_PE2_SS_C_TXN<3>
  115  P3E_CPU0_PE2_SS_C_TXN<2>  IO115  @BASEBOARD_FAB2_LIB.BASEBOARD_FAB2(SCH_1):P3E_CPU0_PE2_SS_C_TXN<2>
  111  P3E_CPU0_PE2_SS_C_TXN<1>  IO111  @BASEBOARD_FAB2_LIB.BASEBOARD_FAB2(SCH_1):P3E_CPU0_PE2_SS_C_TXN<1>
  193  P3E_CPU0_PE2_SS_C_TXN<15>  IO193  @BASEBOARD_FAB2_LIB.BASEBOARD_FAB2(SCH_1):P3E_CPU0_PE2_SS_C_TXN<15>
  189  P3E_CPU0_PE2_SS_C_TXN<14>  IO189  @BASEBOARD_FAB2_LIB.BASEBOARD_FAB2(SCH_1):P3E_CPU0_PE2_SS_C_TXN<14>
  181  P3E_CPU0_PE2_SS_C_TXN<13>  IO181  @BASEBOARD_FAB2_LIB.BASEBOARD_FAB2(SCH_1):P3E_CPU0_PE2_SS_C_TXN<13>
  175  P3E_CPU0_PE2_SS_C_TXN<12>  IO175  @BASEBOARD_FAB2_LIB.BASEBOARD_FAB2(SCH_1):P3E_CPU0_PE2_SS_C_TXN<12>
  171  P3E_CPU0_PE2_SS_C_TXN<11>  IO171  @BASEBOARD_FAB2_LIB.BASEBOARD_FAB2(SCH_1):P3E_CPU0_PE2_SS_C_TXN<11>
  163  P3E_CPU0_PE2_SS_C_TXN<10>  IO163  @BASEBOARD_FAB2_LIB.BASEBOARD_FAB2(SCH_1):P3E_CPU0_PE2_SS_C_TXN<10>
  103  P3E_CPU0_PE2_SS_C_TXN<0>  IO103  @BASEBOARD_FAB2_LIB.BASEBOARD_FAB2(SCH_1):P3E_CPU0_PE2_SS_C_TXN<0>
  102  P3E_CPU0_PE1_SS_R_RXN<7>  IO102  @BASEBOARD_FAB2_LIB.BASEBOARD_FAB2(SCH_1):P3E_CPU0_PE1_SS_R_RXN<7>
  200  GND            IO200  @BASEBOARD_FAB2_LIB.BASEBOARD_FAB2(SCH_1):GND
  197  GND            IO197  @BASEBOARD_FAB2_LIB.BASEBOARD_FAB2(SCH_1):GND
  194  GND            IO194  @BASEBOARD_FAB2_LIB.BASEBOARD_FAB2(SCH_1):GND
  191  GND            IO191  @BASEBOARD_FAB2_LIB.BASEBOARD_FAB2(SCH_1):GND
  188  GND            IO188  @BASEBOARD_FAB2_LIB.BASEBOARD_FAB2(SCH_1):GND
  185  GND            IO185  @BASEBOARD_FAB2_LIB.BASEBOARD_FAB2(SCH_1):GND
  182  GND            IO182  @BASEBOARD_FAB2_LIB.BASEBOARD_FAB2(SCH_1):GND
  179  GND            IO179  @BASEBOARD_FAB2_LIB.BASEBOARD_FAB2(SCH_1):GND
  176  GND            IO176  @BASEBOARD_FAB2_LIB.BASEBOARD_FAB2(SCH_1):GND
  173  GND            IO173  @BASEBOARD_FAB2_LIB.BASEBOARD_FAB2(SCH_1):GND
  170  GND            IO170  @BASEBOARD_FAB2_LIB.BASEBOARD_FAB2(SCH_1):GND
  167  GND            IO167  @BASEBOARD_FAB2_LIB.BASEBOARD_FAB2(SCH_1):GND
  164  GND            IO164  @BASEBOARD_FAB2_LIB.BASEBOARD_FAB2(SCH_1):GND
  161  GND            IO161  @BASEBOARD_FAB2_LIB.BASEBOARD_FAB2(SCH_1):GND
  158  GND            IO158  @BASEBOARD_FAB2_LIB.BASEBOARD_FAB2(SCH_1):GND
  155  GND            IO155  @BASEBOARD_FAB2_LIB.BASEBOARD_FAB2(SCH_1):GND
  152  GND            IO152  @BASEBOARD_FAB2_LIB.BASEBOARD_FAB2(SCH_1):GND
  149  GND            IO149  @BASEBOARD_FAB2_LIB.BASEBOARD_FAB2(SCH_1):GND
  146  GND            IO146  @BASEBOARD_FAB2_LIB.BASEBOARD_FAB2(SCH_1):GND
  143  GND            IO143  @BASEBOARD_FAB2_LIB.BASEBOARD_FAB2(SCH_1):GND
  140  GND            IO140  @BASEBOARD_FAB2_LIB.BASEBOARD_FAB2(SCH_1):GND
  137  GND            IO137  @BASEBOARD_FAB2_LIB.BASEBOARD_FAB2(SCH_1):GND
  134  GND            IO134  @BASEBOARD_FAB2_LIB.BASEBOARD_FAB2(SCH_1):GND
  131  GND            IO131  @BASEBOARD_FAB2_LIB.BASEBOARD_FAB2(SCH_1):GND
  128  GND            IO128  @BASEBOARD_FAB2_LIB.BASEBOARD_FAB2(SCH_1):GND
  125  GND            IO125  @BASEBOARD_FAB2_LIB.BASEBOARD_FAB2(SCH_1):GND
  122  GND            IO122  @BASEBOARD_FAB2_LIB.BASEBOARD_FAB2(SCH_1):GND
  119  GND            IO119  @BASEBOARD_FAB2_LIB.BASEBOARD_FAB2(SCH_1):GND
  116  GND            IO116  @BASEBOARD_FAB2_LIB.BASEBOARD_FAB2(SCH_1):GND
  113  GND            IO113  @BASEBOARD_FAB2_LIB.BASEBOARD_FAB2(SCH_1):GND
  110  GND            IO110  @BASEBOARD_FAB2_LIB.BASEBOARD_FAB2(SCH_1):GND
  107  GND            IO107  @BASEBOARD_FAB2_LIB.BASEBOARD_FAB2(SCH_1):GND
  104  GND            IO104  @BASEBOARD_FAB2_LIB.BASEBOARD_FAB2(SCH_1):GND
  101  GND            IO101  @BASEBOARD_FAB2_LIB.BASEBOARD_FAB2(SCH_1):GND
  199  FM_PRSNT_2_6_N  IO199  @BASEBOARD_FAB2_LIB.BASEBOARD_FAB2(SCH_1):FM_PRSNT_2_6_N

SCONN200_H68296001_SM  I258  J8G1   [SCONN200_H68296001_SM-CONN,H68A]
   15  SMB_SLOTX24_STBY_LVC3_SDA_R2   IO15  @BASEBOARD_FAB2_LIB.BASEBOARD_FAB2(SCH_1):SMB_SLOTX24_STBY_LVC3_SDA_R2
   17  SMB_SLOTX24_STBY_LVC3_SCL_R2   IO17  @BASEBOARD_FAB2_LIB.BASEBOARD_FAB2(SCH_1):SMB_SLOTX24_STBY_LVC3_SCL_R2
   29  RST_PCIE_RISER1_PERST_R_N   IO29  @BASEBOARD_FAB2_LIB.BASEBOARD_FAB2(SCH_1):RST_PCIE_RISER1_PERST_R_N
   25  P3V3_STBY       IO25  @BASEBOARD_FAB2_LIB.BASEBOARD_FAB2(SCH_1):P3V3_STBY
   24  P3V3            IO24  @BASEBOARD_FAB2_LIB.BASEBOARD_FAB2(SCH_1):P3V3
   23  P3V3            IO23  @BASEBOARD_FAB2_LIB.BASEBOARD_FAB2(SCH_1):P3V3
   22  P3V3            IO22  @BASEBOARD_FAB2_LIB.BASEBOARD_FAB2(SCH_1):P3V3
   21  P3V3            IO21  @BASEBOARD_FAB2_LIB.BASEBOARD_FAB2(SCH_1):P3V3
  100  P3E_CPU0_PE1_SS_R_RXP<7>  IO100  @BASEBOARD_FAB2_LIB.BASEBOARD_FAB2(SCH_1):P3E_CPU0_PE1_SS_R_RXP<7>
   94  P3E_CPU0_PE1_SS_R_RXP<6>   IO94  @BASEBOARD_FAB2_LIB.BASEBOARD_FAB2(SCH_1):P3E_CPU0_PE1_SS_R_RXP<6>
   88  P3E_CPU0_PE1_SS_R_RXP<5>   IO88  @BASEBOARD_FAB2_LIB.BASEBOARD_FAB2(SCH_1):P3E_CPU0_PE1_SS_R_RXP<5>
   82  P3E_CPU0_PE1_SS_R_RXP<4>   IO82  @BASEBOARD_FAB2_LIB.BASEBOARD_FAB2(SCH_1):P3E_CPU0_PE1_SS_R_RXP<4>
   76  P3E_CPU0_PE1_SS_R_RXP<3>   IO76  @BASEBOARD_FAB2_LIB.BASEBOARD_FAB2(SCH_1):P3E_CPU0_PE1_SS_R_RXP<3>
   70  P3E_CPU0_PE1_SS_R_RXP<2>   IO70  @BASEBOARD_FAB2_LIB.BASEBOARD_FAB2(SCH_1):P3E_CPU0_PE1_SS_R_RXP<2>
   60  P3E_CPU0_PE1_SS_R_RXP<1>   IO60  @BASEBOARD_FAB2_LIB.BASEBOARD_FAB2(SCH_1):P3E_CPU0_PE1_SS_R_RXP<1>
   54  P3E_CPU0_PE1_SS_R_RXP<0>   IO54  @BASEBOARD_FAB2_LIB.BASEBOARD_FAB2(SCH_1):P3E_CPU0_PE1_SS_R_RXP<0>
   96  P3E_CPU0_PE1_SS_R_RXN<6>   IO96  @BASEBOARD_FAB2_LIB.BASEBOARD_FAB2(SCH_1):P3E_CPU0_PE1_SS_R_RXN<6>
   90  P3E_CPU0_PE1_SS_R_RXN<5>   IO90  @BASEBOARD_FAB2_LIB.BASEBOARD_FAB2(SCH_1):P3E_CPU0_PE1_SS_R_RXN<5>
   84  P3E_CPU0_PE1_SS_R_RXN<4>   IO84  @BASEBOARD_FAB2_LIB.BASEBOARD_FAB2(SCH_1):P3E_CPU0_PE1_SS_R_RXN<4>
   78  P3E_CPU0_PE1_SS_R_RXN<3>   IO78  @BASEBOARD_FAB2_LIB.BASEBOARD_FAB2(SCH_1):P3E_CPU0_PE1_SS_R_RXN<3>
   72  P3E_CPU0_PE1_SS_R_RXN<2>   IO72  @BASEBOARD_FAB2_LIB.BASEBOARD_FAB2(SCH_1):P3E_CPU0_PE1_SS_R_RXN<2>
   62  P3E_CPU0_PE1_SS_R_RXN<1>   IO62  @BASEBOARD_FAB2_LIB.BASEBOARD_FAB2(SCH_1):P3E_CPU0_PE1_SS_R_RXN<1>
   56  P3E_CPU0_PE1_SS_R_RXN<0>   IO56  @BASEBOARD_FAB2_LIB.BASEBOARD_FAB2(SCH_1):P3E_CPU0_PE1_SS_R_RXN<0>
   97  P3E_CPU0_PE1_SS_C_TXP<7>   IO97  @BASEBOARD_FAB2_LIB.BASEBOARD_FAB2(SCH_1):P3E_CPU0_PE1_SS_C_TXP<7>
   91  P3E_CPU0_PE1_SS_C_TXP<6>   IO91  @BASEBOARD_FAB2_LIB.BASEBOARD_FAB2(SCH_1):P3E_CPU0_PE1_SS_C_TXP<6>
   85  P3E_CPU0_PE1_SS_C_TXP<5>   IO85  @BASEBOARD_FAB2_LIB.BASEBOARD_FAB2(SCH_1):P3E_CPU0_PE1_SS_C_TXP<5>
   79  P3E_CPU0_PE1_SS_C_TXP<4>   IO79  @BASEBOARD_FAB2_LIB.BASEBOARD_FAB2(SCH_1):P3E_CPU0_PE1_SS_C_TXP<4>
   73  P3E_CPU0_PE1_SS_C_TXP<3>   IO73  @BASEBOARD_FAB2_LIB.BASEBOARD_FAB2(SCH_1):P3E_CPU0_PE1_SS_C_TXP<3>
   67  P3E_CPU0_PE1_SS_C_TXP<2>   IO67  @BASEBOARD_FAB2_LIB.BASEBOARD_FAB2(SCH_1):P3E_CPU0_PE1_SS_C_TXP<2>
   57  P3E_CPU0_PE1_SS_C_TXP<1>   IO57  @BASEBOARD_FAB2_LIB.BASEBOARD_FAB2(SCH_1):P3E_CPU0_PE1_SS_C_TXP<1>
   51  P3E_CPU0_PE1_SS_C_TXP<0>   IO51  @BASEBOARD_FAB2_LIB.BASEBOARD_FAB2(SCH_1):P3E_CPU0_PE1_SS_C_TXP<0>
   99  P3E_CPU0_PE1_SS_C_TXN<7>   IO99  @BASEBOARD_FAB2_LIB.BASEBOARD_FAB2(SCH_1):P3E_CPU0_PE1_SS_C_TXN<7>
   93  P3E_CPU0_PE1_SS_C_TXN<6>   IO93  @BASEBOARD_FAB2_LIB.BASEBOARD_FAB2(SCH_1):P3E_CPU0_PE1_SS_C_TXN<6>
   87  P3E_CPU0_PE1_SS_C_TXN<5>   IO87  @BASEBOARD_FAB2_LIB.BASEBOARD_FAB2(SCH_1):P3E_CPU0_PE1_SS_C_TXN<5>
   81  P3E_CPU0_PE1_SS_C_TXN<4>   IO81  @BASEBOARD_FAB2_LIB.BASEBOARD_FAB2(SCH_1):P3E_CPU0_PE1_SS_C_TXN<4>
   75  P3E_CPU0_PE1_SS_C_TXN<3>   IO75  @BASEBOARD_FAB2_LIB.BASEBOARD_FAB2(SCH_1):P3E_CPU0_PE1_SS_C_TXN<3>
   69  P3E_CPU0_PE1_SS_C_TXN<2>   IO69  @BASEBOARD_FAB2_LIB.BASEBOARD_FAB2(SCH_1):P3E_CPU0_PE1_SS_C_TXN<2>
   59  P3E_CPU0_PE1_SS_C_TXN<1>   IO59  @BASEBOARD_FAB2_LIB.BASEBOARD_FAB2(SCH_1):P3E_CPU0_PE1_SS_C_TXN<1>
   53  P3E_CPU0_PE1_SS_C_TXN<0>   IO53  @BASEBOARD_FAB2_LIB.BASEBOARD_FAB2(SCH_1):P3E_CPU0_PE1_SS_C_TXN<0>
   12  P12V            IO12  @BASEBOARD_FAB2_LIB.BASEBOARD_FAB2(SCH_1):P12V
   11  P12V            IO11  @BASEBOARD_FAB2_LIB.BASEBOARD_FAB2(SCH_1):P12V
   10  P12V            IO10  @BASEBOARD_FAB2_LIB.BASEBOARD_FAB2(SCH_1):P12V
    9  P12V             IO9  @BASEBOARD_FAB2_LIB.BASEBOARD_FAB2(SCH_1):P12V
    8  P12V             IO8  @BASEBOARD_FAB2_LIB.BASEBOARD_FAB2(SCH_1):P12V
    7  P12V             IO7  @BASEBOARD_FAB2_LIB.BASEBOARD_FAB2(SCH_1):P12V
    6  P12V             IO6  @BASEBOARD_FAB2_LIB.BASEBOARD_FAB2(SCH_1):P12V
    5  P12V             IO5  @BASEBOARD_FAB2_LIB.BASEBOARD_FAB2(SCH_1):P12V
    4  P12V             IO4  @BASEBOARD_FAB2_LIB.BASEBOARD_FAB2(SCH_1):P12V
    3  P12V             IO3  @BASEBOARD_FAB2_LIB.BASEBOARD_FAB2(SCH_1):P12V
    2  P12V             IO2  @BASEBOARD_FAB2_LIB.BASEBOARD_FAB2(SCH_1):P12V
    1  P12V             IO1  @BASEBOARD_FAB2_LIB.BASEBOARD_FAB2(SCH_1):P12V
   16  IRQ_OOB_MGMT_RISER_ALERT_N   IO16  @BASEBOARD_FAB2_LIB.BASEBOARD_FAB2(SCH_1):IRQ_OOB_MGMT_RISER_ALERT_N
  MH2  GND              MH2  @BASEBOARD_FAB2_LIB.BASEBOARD_FAB2(SCH_1):GND
  MH1  GND              MH1  @BASEBOARD_FAB2_LIB.BASEBOARD_FAB2(SCH_1):GND
   98  GND             IO98  @BASEBOARD_FAB2_LIB.BASEBOARD_FAB2(SCH_1):GND
   95  GND             IO95  @BASEBOARD_FAB2_LIB.BASEBOARD_FAB2(SCH_1):GND
   92  GND             IO92  @BASEBOARD_FAB2_LIB.BASEBOARD_FAB2(SCH_1):GND
   89  GND             IO89  @BASEBOARD_FAB2_LIB.BASEBOARD_FAB2(SCH_1):GND
   86  GND             IO86  @BASEBOARD_FAB2_LIB.BASEBOARD_FAB2(SCH_1):GND
   83  GND             IO83  @BASEBOARD_FAB2_LIB.BASEBOARD_FAB2(SCH_1):GND
   80  GND             IO80  @BASEBOARD_FAB2_LIB.BASEBOARD_FAB2(SCH_1):GND
   77  GND             IO77  @BASEBOARD_FAB2_LIB.BASEBOARD_FAB2(SCH_1):GND
   74  GND             IO74  @BASEBOARD_FAB2_LIB.BASEBOARD_FAB2(SCH_1):GND
   71  GND             IO71  @BASEBOARD_FAB2_LIB.BASEBOARD_FAB2(SCH_1):GND
   68  GND             IO68  @BASEBOARD_FAB2_LIB.BASEBOARD_FAB2(SCH_1):GND
   65  GND             IO65  @BASEBOARD_FAB2_LIB.BASEBOARD_FAB2(SCH_1):GND
   64  GND             IO64  @BASEBOARD_FAB2_LIB.BASEBOARD_FAB2(SCH_1):GND
   61  GND             IO61  @BASEBOARD_FAB2_LIB.BASEBOARD_FAB2(SCH_1):GND
   58  GND             IO58  @BASEBOARD_FAB2_LIB.BASEBOARD_FAB2(SCH_1):GND
   55  GND             IO55  @BASEBOARD_FAB2_LIB.BASEBOARD_FAB2(SCH_1):GND
   52  GND             IO52  @BASEBOARD_FAB2_LIB.BASEBOARD_FAB2(SCH_1):GND
   49  GND             IO49  @BASEBOARD_FAB2_LIB.BASEBOARD_FAB2(SCH_1):GND
   46  GND             IO46  @BASEBOARD_FAB2_LIB.BASEBOARD_FAB2(SCH_1):GND
   43  GND             IO43  @BASEBOARD_FAB2_LIB.BASEBOARD_FAB2(SCH_1):GND
   40  GND             IO40  @BASEBOARD_FAB2_LIB.BASEBOARD_FAB2(SCH_1):GND
   37  GND             IO37  @BASEBOARD_FAB2_LIB.BASEBOARD_FAB2(SCH_1):GND
   34  GND             IO34  @BASEBOARD_FAB2_LIB.BASEBOARD_FAB2(SCH_1):GND
   31  GND             IO31  @BASEBOARD_FAB2_LIB.BASEBOARD_FAB2(SCH_1):GND
   26  GND             IO26  @BASEBOARD_FAB2_LIB.BASEBOARD_FAB2(SCH_1):GND
   14  GND             IO14  @BASEBOARD_FAB2_LIB.BASEBOARD_FAB2(SCH_1):GND
   13  GND             IO13  @BASEBOARD_FAB2_LIB.BASEBOARD_FAB2(SCH_1):GND
   18  FM_SLT_CFG1     IO18  @BASEBOARD_FAB2_LIB.BASEBOARD_FAB2(SCH_1):FM_SLT_CFG1
   19  FM_SLT_CFG0     IO19  @BASEBOARD_FAB2_LIB.BASEBOARD_FAB2(SCH_1):FM_SLT_CFG0
   20  FM_PWRBRK_SLOT_N   IO20  @BASEBOARD_FAB2_LIB.BASEBOARD_FAB2(SCH_1):FM_PWRBRK_SLOT_N
   66  FM_PRSNT_2_5_N   IO66  @BASEBOARD_FAB2_LIB.BASEBOARD_FAB2(SCH_1):FM_PRSNT_2_5_N
   63  FM_PRSNT_2_4_N   IO63  @BASEBOARD_FAB2_LIB.BASEBOARD_FAB2(SCH_1):FM_PRSNT_2_4_N
   32  FM_PRSNT_2_3_N   IO32  @BASEBOARD_FAB2_LIB.BASEBOARD_FAB2(SCH_1):FM_PRSNT_2_3_N
   30  FM_PRSNT_2_2_N   IO30  @BASEBOARD_FAB2_LIB.BASEBOARD_FAB2(SCH_1):FM_PRSNT_2_2_N
   27  FM_PRSNT_2_1_N   IO27  @BASEBOARD_FAB2_LIB.BASEBOARD_FAB2(SCH_1):FM_PRSNT_2_1_N
   28  FM_PE_SLOTX24_WAKE_N   IO28  @BASEBOARD_FAB2_LIB.BASEBOARD_FAB2(SCH_1):FM_PE_SLOTX24_WAKE_N
   48  CLK_100M_PCH_SLOTX24_S5_DP   IO48  @BASEBOARD_FAB2_LIB.BASEBOARD_FAB2(SCH_1):CLK_100M_PCH_SLOTX24_S5_DP
   50  CLK_100M_PCH_SLOTX24_S5_DN   IO50  @BASEBOARD_FAB2_LIB.BASEBOARD_FAB2(SCH_1):CLK_100M_PCH_SLOTX24_S5_DN
   45  CLK_100M_PCH_SLOTX24_S4_DP   IO45  @BASEBOARD_FAB2_LIB.BASEBOARD_FAB2(SCH_1):CLK_100M_PCH_SLOTX24_S4_DP
   47  CLK_100M_PCH_SLOTX24_S4_DN   IO47  @BASEBOARD_FAB2_LIB.BASEBOARD_FAB2(SCH_1):CLK_100M_PCH_SLOTX24_S4_DN
   42  CLK_100M_PCH_SLOTX24_S3_DP   IO42  @BASEBOARD_FAB2_LIB.BASEBOARD_FAB2(SCH_1):CLK_100M_PCH_SLOTX24_S3_DP
   44  CLK_100M_PCH_SLOTX24_S3_DN   IO44  @BASEBOARD_FAB2_LIB.BASEBOARD_FAB2(SCH_1):CLK_100M_PCH_SLOTX24_S3_DN
   39  CLK_100M_PCH_SLOTX24_S2_DP   IO39  @BASEBOARD_FAB2_LIB.BASEBOARD_FAB2(SCH_1):CLK_100M_PCH_SLOTX24_S2_DP
   41  CLK_100M_PCH_SLOTX24_S2_DN   IO41  @BASEBOARD_FAB2_LIB.BASEBOARD_FAB2(SCH_1):CLK_100M_PCH_SLOTX24_S2_DN
   36  CLK_100M_PCH_SLOTX24_S1_DP   IO36  @BASEBOARD_FAB2_LIB.BASEBOARD_FAB2(SCH_1):CLK_100M_PCH_SLOTX24_S1_DP
   38  CLK_100M_PCH_SLOTX24_S1_DN   IO38  @BASEBOARD_FAB2_LIB.BASEBOARD_FAB2(SCH_1):CLK_100M_PCH_SLOTX24_S1_DN
   33  CLK_100M_PCH_SLOTX24_S0_DP   IO33  @BASEBOARD_FAB2_LIB.BASEBOARD_FAB2(SCH_1):CLK_100M_PCH_SLOTX24_S0_DP
   35  CLK_100M_PCH_SLOTX24_S0_DN   IO35  @BASEBOARD_FAB2_LIB.BASEBOARD_FAB2(SCH_1):CLK_100M_PCH_SLOTX24_S0_DN

CONN12_C73564003  I124  J8G2   [CONN12_C73564003_PIP-CONN,C735A]
    8  TP_JUMPER_BLOCK_1_8    IO8  @BASEBOARD_FAB2_LIB.BASEBOARD_FAB2(SCH_1):TP_JUMPER_BLOCK_1_8
    7  TP_JUMPER_BLOCK_1_7    IO7  @BASEBOARD_FAB2_LIB.BASEBOARD_FAB2(SCH_1):TP_JUMPER_BLOCK_ 1_7
    2  TP_JUMPER_BLOCK_1_2    IO2  @BASEBOARD_FAB2_LIB.BASEBOARD_FAB2(SCH_1):TP_JUMPER_BLOCK_1_2
    1  TP_JUMPER_BLOCK_1_1    IO1  @BASEBOARD_FAB2_LIB.BASEBOARD_FAB2(SCH_1):TP_JUMPER_BLOCK_1_1
    3  RST_BMC_SRST_N    IO3  @BASEBOARD_FAB2_LIB.BASEBOARD_FAB2(SCH_1):RST_BMC_SRST_N
   12  GND             IO12  @BASEBOARD_FAB2_LIB.BASEBOARD_FAB2(SCH_1):GND
   11  GND             IO11  @BASEBOARD_FAB2_LIB.BASEBOARD_FAB2(SCH_1):GND
    6  GND              IO6  @BASEBOARD_FAB2_LIB.BASEBOARD_FAB2(SCH_1):GND
    5  GND              IO5  @BASEBOARD_FAB2_LIB.BASEBOARD_FAB2(SCH_1):GND
    4  FM_IE_DISABLE_N    IO4  @BASEBOARD_FAB2_LIB.BASEBOARD_FAB2(SCH_1):FM_IE_DISABLE_N
   10  FM_DIS_ADR_DLY   IO10  @BASEBOARD_FAB2_LIB.BASEBOARD_FAB2(SCH_1):FM_DIS_ADR_DLY
    9  FM_CPLD_UART_CH_LOCK_N    IO9  @BASEBOARD_FAB2_LIB.BASEBOARD_FAB2(SCH_1):FM_CPLD_UART_CH_LOCK_N

CONN4_D42317002_PIP  I131  J9A1   [CONN4_D42317002_PIP-CONN,D4231A]
    2  PU_KEY_CONN_PIN2_R    IO2  @BASEBOARD_FAB2_LIB.BASEBOARD_FAB2(SCH_1):PU_KEY_CONN_PIN2_R
    3  GND              IO3  @BASEBOARD_FAB2_LIB.BASEBOARD_FAB2(SCH_1):GND
    1  GND              IO1  @BASEBOARD_FAB2_LIB.BASEBOARD_FAB2(SCH_1):GND
    4  FM_PCH_SATA_RAID_KEY_R    IO4  @BASEBOARD_FAB2_LIB.BASEBOARD_FAB2(SCH_1):FM_PCH_SATA_RAID_KEY_R

CONN14_H54902001_PIP  I171  J9A2   [CONN14_H54902001_PIP-CONN,H549A]
    9  SPA_MID_DBG_TX    IO9  @BASEBOARD_FAB2_LIB.BASEBOARD_FAB2(SCH_1):SPA_MID_DBG_TX
   10  SPA_5V_SIN_SW   IO10  @BASEBOARD_FAB2_LIB.BASEBOARD_FAB2(SCH_1):SPA_5V_SIN_SW
   14  P5V_STBY_DGB_FS   IO14  @BASEBOARD_FAB2_LIB.BASEBOARD_FAB2(SCH_1):P5V_STBY_DGB_FS
    8  LED_POSTCODE_7_R    IO8  @BASEBOARD_FAB2_LIB.BASEBOARD_FAB2(SCH_1):LED_POSTCODE_7_R
    7  LED_POSTCODE_6_R    IO7  @BASEBOARD_FAB2_LIB.BASEBOARD_FAB2(SCH_1):LED_POSTCODE_6_R
    6  LED_POSTCODE_5_R    IO6  @BASEBOARD_FAB2_LIB.BASEBOARD_FAB2(SCH_1):LED_POSTCODE_5_R
    5  LED_POSTCODE_4_R    IO5  @BASEBOARD_FAB2_LIB.BASEBOARD_FAB2(SCH_1):LED_POSTCODE_4_R
    4  LED_POSTCODE_3_R    IO4  @BASEBOARD_FAB2_LIB.BASEBOARD_FAB2(SCH_1):LED_POSTCODE_3_R
    3  LED_POSTCODE_2_R    IO3  @BASEBOARD_FAB2_LIB.BASEBOARD_FAB2(SCH_1):LED_POSTCODE_2_R
    2  LED_POSTCODE_1_R    IO2  @BASEBOARD_FAB2_LIB.BASEBOARD_FAB2(SCH_1):LED_POSTCODE_1_R
    1  LED_POSTCODE_0_R    IO1  @BASEBOARD_FAB2_LIB.BASEBOARD_FAB2(SCH_1):LED_POSTCODE_0_R
   13  GND             IO13  @BASEBOARD_FAB2_LIB.BASEBOARD_FAB2(SCH_1):GND
   12  FM_UART_SWITCH_N   IO12  @BASEBOARD_FAB2_LIB.BASEBOARD_FAB2(SCH_1):FM_UART_SWITCH_N
   11  FM_DEBUG_RST_BTN_N   IO11  @BASEBOARD_FAB2_LIB.BASEBOARD_FAB2(SCH_1):FM_DEBUG_RST_BTN_N

SCONN60_C21100002  I26  J9A3   [SCONN60_C21100002_SMLF-CONN,C2A]
   54  XDP_TRST_N      IO54  @BASEBOARD_FAB2_LIB.BASEBOARD_FAB2(SCH_1):XDP_TRST_N
   58  XDP_TMS         IO58  @BASEBOARD_FAB2_LIB.BASEBOARD_FAB2(SCH_1):XDP_TMS
   52  XDP_TDO         IO52  @BASEBOARD_FAB2_LIB.BASEBOARD_FAB2(SCH_1):XDP_TDO
   56  XDP_TDI         IO56  @BASEBOARD_FAB2_LIB.BASEBOARD_FAB2(SCH_1):XDP_TDI
   47  XDP_SYSPWROK    IO47  @BASEBOARD_FAB2_LIB.BASEBOARD_FAB2(SCH_1):XDP_SYSPWROK
    6  XDP_SPI_PCH_MOSI_BOOT_HALT_N    IO6  @BASEBOARD_FAB2_LIB.BASEBOARD_FAB2(SCH_1):XDP_SPI_PCH_MOSI_BOOT_HALT_N
   48  XDP_RST_CO_N    IO48  @BASEBOARD_FAB2_LIB.BASEBOARD_FAB2(SCH_1):XDP_RST_CO_N
   39  XDP_RSMRST_N    IO39  @BASEBOARD_FAB2_LIB.BASEBOARD_FAB2(SCH_1):XDP_RSMRST_N
   41  XDP_PWRGD_RST_N   IO41  @BASEBOARD_FAB2_LIB.BASEBOARD_FAB2(SCH_1):XDP_PWRGD_RST_N
   60  XDP_PRESENT_N   IO60  @BASEBOARD_FAB2_LIB.BASEBOARD_FAB2(SCH_1):XDP_PRESENT_N
    3  XDP_PREQ_N       IO3  @BASEBOARD_FAB2_LIB.BASEBOARD_FAB2(SCH_1):XDP_PREQ_N
    5  XDP_PRDY_N       IO5  @BASEBOARD_FAB2_LIB.BASEBOARD_FAB2(SCH_1):XDP_PRDY_N
   55  XDP_PCH_TCK1    IO55  @BASEBOARD_FAB2_LIB.BASEBOARD_FAB2(SCH_1):XDP_PCH_TCK1
   24  XDP_OBSFN_B1_MBP7_N   IO24  @BASEBOARD_FAB2_LIB.BASEBOARD_FAB2(SCH_1):XDP_OBSFN_B1_MBP7_N
   22  XDP_OBSFN_B0_MBP6_N   IO22  @BASEBOARD_FAB2_LIB.BASEBOARD_FAB2(SCH_1):XDP_OBSFN_B0_MBP6_N
   46  XDP_ITP_PMODE   IO46  @BASEBOARD_FAB2_LIB.BASEBOARD_FAB2(SCH_1):XDP_ITP_PMODE
    1  XDP_DEBUG_CONSENT_N    IO1  @BASEBOARD_FAB2_LIB.BASEBOARD_FAB2(SCH_1):XDP_DEBUG_CONSENT_N
   57  XDP_CPU_TCK0    IO57  @BASEBOARD_FAB2_LIB.BASEBOARD_FAB2(SCH_1):XDP_CPU_TCK0
   45  XDP_CPU_PWR_DEBUG_N   IO45  @BASEBOARD_FAB2_LIB.BASEBOARD_FAB2(SCH_1):XDP_CPU_PWR_DEBUG_N
   23  TP_XDP_OBSFN_B1   IO23  @BASEBOARD_FAB2_LIB.BASEBOARD_FAB2(SCH_1):TP_XDP_OBSFN_B1
   21  TP_XDP_OBSFN_B0   IO21  @BASEBOARD_FAB2_LIB.BASEBOARD_FAB2(SCH_1):TP_XDP_OBSFN_B0
   35  TP_XDP_OBSDATA_B3   IO35  @BASEBOARD_FAB2_LIB.BASEBOARD_FAB2(SCH_1):TP_XDP_OBSDATA_B3
   33  TP_XDP_OBSDATA_B2   IO33  @BASEBOARD_FAB2_LIB.BASEBOARD_FAB2(SCH_1):TP_XDP_OBSDATA_B2
   29  TP_XDP_OBSDATA_B1   IO29  @BASEBOARD_FAB2_LIB.BASEBOARD_FAB2(SCH_1):TP_XDP_OBSDATA_B1
   27  TP_XDP_OBSDATA_B0   IO27  @BASEBOARD_FAB2_LIB.BASEBOARD_FAB2(SCH_1):TP_XDP_OBSDATA_B0
   17  TP_XDP_OBSDATA_A3   IO17  @BASEBOARD_FAB2_LIB.BASEBOARD_FAB2(SCH_1):TP_XDP_OBSDATA_A3
   15  TP_XDP_OBSDATA_A2   IO15  @BASEBOARD_FAB2_LIB.BASEBOARD_FAB2(SCH_1):TP_XDP_OBSDATA_A2
   11  TP_XDP_OBSDATA_A1   IO11  @BASEBOARD_FAB2_LIB.BASEBOARD_FAB2(SCH_1):TP_XDP_OBSDATA_A1
    9  TP_XDP_OBSDATA_A0    IO9  @BASEBOARD_FAB2_LIB.BASEBOARD_FAB2(SCH_1):TP_XDP_OBSDATA_A0
    4  TP_XDP_CPU_OBSFN_C0    IO4  @BASEBOARD_FAB2_LIB.BASEBOARD_FAB2(SCH_1):TP_XDP_CPU_OBSFN_C0
   36  TP_XDP_CPU_OBSDATA_D3   IO36  @BASEBOARD_FAB2_LIB.BASEBOARD_FAB2(SCH_1):TP_XDP_CPU_OBSDATA_D3
   34  TP_XDP_CPU_OBSDATA_D2   IO34  @BASEBOARD_FAB2_LIB.BASEBOARD_FAB2(SCH_1):TP_XDP_CPU_OBSDATA_D2
   30  TP_XDP_CPU_OBSDATA_D1   IO30  @BASEBOARD_FAB2_LIB.BASEBOARD_FAB2(SCH_1):TP_XDP_CPU_OBSDATA_D1
   28  TP_XDP_CPU_OBSDATA_D0   IO28  @BASEBOARD_FAB2_LIB.BASEBOARD_FAB2(SCH_1):TP_XDP_CPU_OBSDATA_D0
   18  TP_XDP_CPU_OBSDATA_C3   IO18  @BASEBOARD_FAB2_LIB.BASEBOARD_FAB2(SCH_1):TP_XDP_CPU_OBSDATA_C3
   16  TP_XDP_CPU_OBSDATA_C2   IO16  @BASEBOARD_FAB2_LIB.BASEBOARD_FAB2(SCH_1):TP_XDP_CPU_OBSDATA_C2
   12  TP_XDP_CPU_OBSDATA_C1   IO12  @BASEBOARD_FAB2_LIB.BASEBOARD_FAB2(SCH_1):TP_XDP_CPU_OBSDATA_C1
   10  TP_XDP_CPU_OBSDATA_C0   IO10  @BASEBOARD_FAB2_LIB.BASEBOARD_FAB2(SCH_1):TP_XDP_CPU_OBSDATA_C0
   51  SMB_HOST_STBY_LVC3_SDA   IO51  @BASEBOARD_FAB2_LIB.BASEBOARD_FAB2(SCH_1):SMB_HOST_STBY_LVC3_SDA
   53  SMB_HOST_STBY_LVC3_SCL   IO53  @BASEBOARD_FAB2_LIB.BASEBOARD_FAB2(SCH_1):SMB_HOST_STBY_LVC3_SCL
   44  P1V05_PCH_STBY   IO44  @BASEBOARD_FAB2_LIB.BASEBOARD_FAB2(SCH_1):P1V05_PCH_STBY
   43  P1V05_PCH_STBY   IO43  @BASEBOARD_FAB2_LIB.BASEBOARD_FAB2(SCH_1):P1V05_PCH_STBY
   59  GND             IO59  @BASEBOARD_FAB2_LIB.BASEBOARD_FAB2(SCH_1):GND
   50  GND             IO50  @BASEBOARD_FAB2_LIB.BASEBOARD_FAB2(SCH_1):GND
   49  GND             IO49  @BASEBOARD_FAB2_LIB.BASEBOARD_FAB2(SCH_1):GND
   38  GND             IO38  @BASEBOARD_FAB2_LIB.BASEBOARD_FAB2(SCH_1):GND
   37  GND             IO37  @BASEBOARD_FAB2_LIB.BASEBOARD_FAB2(SCH_1):GND
   32  GND             IO32  @BASEBOARD_FAB2_LIB.BASEBOARD_FAB2(SCH_1):GND
   31  GND             IO31  @BASEBOARD_FAB2_LIB.BASEBOARD_FAB2(SCH_1):GND
   26  GND             IO26  @BASEBOARD_FAB2_LIB.BASEBOARD_FAB2(SCH_1):GND
   25  GND             IO25  @BASEBOARD_FAB2_LIB.BASEBOARD_FAB2(SCH_1):GND
   20  GND             IO20  @BASEBOARD_FAB2_LIB.BASEBOARD_FAB2(SCH_1):GND
   19  GND             IO19  @BASEBOARD_FAB2_LIB.BASEBOARD_FAB2(SCH_1):GND
   14  GND             IO14  @BASEBOARD_FAB2_LIB.BASEBOARD_FAB2(SCH_1):GND
   13  GND             IO13  @BASEBOARD_FAB2_LIB.BASEBOARD_FAB2(SCH_1):GND
    8  GND              IO8  @BASEBOARD_FAB2_LIB.BASEBOARD_FAB2(SCH_1):GND
    7  GND              IO7  @BASEBOARD_FAB2_LIB.BASEBOARD_FAB2(SCH_1):GND
    2  GND              IO2  @BASEBOARD_FAB2_LIB.BASEBOARD_FAB2(SCH_1):GND
   40  CLK_100M_PCH_XDP_DP   IO40  @BASEBOARD_FAB2_LIB.BASEBOARD_FAB2(SCH_1):CLK_100M_PCH_XDP_DP
   42  CLK_100M_PCH_XDP_DN   IO42  @BASEBOARD_FAB2_LIB.BASEBOARD_FAB2(SCH_1):CLK_100M_PCH_XDP_DN

CONN9_H51826001_PIP2  I69  J9B1   [CONN9_H51826001_PIP2-CONN,H518A]
    9  USB3_P01_FB_TXP  STDA_SSTXP  @BASEBOARD_FAB2_LIB.BASEBOARD_FAB2(SCH_1):USB3_P01_FB_TXP
    8  USB3_P01_FB_TXN  STDA_SSTXN  @BASEBOARD_FAB2_LIB.BASEBOARD_FAB2(SCH_1):USB3_P01_FB_TXN
    6  USB3_P01_FB_RXP  STDA_SSRXP  @BASEBOARD_FAB2_LIB.BASEBOARD_FAB2(SCH_1):USB3_P01_FB_RXP
    5  USB3_P01_FB_RXN  STDA_SSRXN  @BASEBOARD_FAB2_LIB.BASEBOARD_FAB2(SCH_1):USB3_P01_FB_RXN
    3  USB2_P01_ESD_DP     DP  @BASEBOARD_FAB2_LIB.BASEBOARD_FAB2(SCH_1):USB2_P01_ESD_DP
    2  USB2_P01_ESD_DN     DN  @BASEBOARD_FAB2_LIB.BASEBOARD_FAB2(SCH_1):USB2_P01_ESD_DN
    1  P5V_USB         VBUS  @BASEBOARD_FAB2_LIB.BASEBOARD_FAB2(SCH_1):P5V_USB
  MH4  GND              MH4  @BASEBOARD_FAB2_LIB.BASEBOARD_FAB2(SCH_1):GND
  MH3  GND              MH3  @BASEBOARD_FAB2_LIB.BASEBOARD_FAB2(SCH_1):GND
  MH2  GND              MH2  @BASEBOARD_FAB2_LIB.BASEBOARD_FAB2(SCH_1):GND
  MH1  GND              MH1  @BASEBOARD_FAB2_LIB.BASEBOARD_FAB2(SCH_1):GND
    7  GND            GND_DRAIN  @BASEBOARD_FAB2_LIB.BASEBOARD_FAB2(SCH_1):GND
    4  GND              GND  @BASEBOARD_FAB2_LIB.BASEBOARD_FAB2(SCH_1):GND

CONN3_C95678002_PIP  I281  J9B2   [CONN3_C95678002_PIP-CONN,C9567A]
    1  SMB_SMLINK0_STBY_LVC3_SDA    IO1  @BASEBOARD_FAB2_LIB.BASEBOARD_FAB2(SCH_1):SMB_SMLINK0_STBY_LVC3_SDA
    3  SMB_SMLINK0_STBY_LVC3_SCL    IO3  @BASEBOARD_FAB2_LIB.BASEBOARD_FAB2(SCH_1):SMB_SMLINK0_STBY_LVC3_SCL
    2  GND              IO2  @BASEBOARD_FAB2_LIB.BASEBOARD_FAB2(SCH_1):GND

SCONN120_A28699018_SM  I336  J9B3   [SCONN120_A28699018_SM-SCONN,A2A]
   37  SMB_OCP_LAN_STBY_LVC3_SDA   IO37  @BASEBOARD_FAB2_LIB.BASEBOARD_FAB2(SCH_1):SMB_OCP_LAN_STBY_LVC3_SDA
   35  SMB_OCP_LAN_STBY_LVC3_SCL   IO35  @BASEBOARD_FAB2_LIB.BASEBOARD_FAB2(SCH_1):SMB_OCP_LAN_STBY_LVC3_SCL
   32  SMB_OCP_FRU_STBY_LVC3_SDA   IO32  @BASEBOARD_FAB2_LIB.BASEBOARD_FAB2(SCH_1):SMB_OCP_FRU_STBY_LVC3_SDA
   30  SMB_OCP_FRU_STBY_LVC3_SCL   IO30  @BASEBOARD_FAB2_LIB.BASEBOARD_FAB2(SCH_1):SMB_OCP_FRU_STBY_LVC3_SCL
   33  RST_PCIE_CPU_DEV0_R_N   IO33  @BASEBOARD_FAB2_LIB.BASEBOARD_FAB2(SCH_1):RST_PCIE_CPU_DEV0_R_N
   31  RMII_BMC_OCP_TXEN   IO31  @BASEBOARD_FAB2_LIB.BASEBOARD_FAB2(SCH_1):RMII_BMC_OCP_TXEN
   42  RMII_BMC_OCP_TXD1   IO42  @BASEBOARD_FAB2_LIB.BASEBOARD_FAB2(SCH_1):RMII_BMC_OCP_TXD1
   40  RMII_BMC_OCP_TXD0   IO40  @BASEBOARD_FAB2_LIB.BASEBOARD_FAB2(SCH_1):RMII_BMC_OCP_TXD0
   36  RMII_BMC_OCP_RXER_R   IO36  @BASEBOARD_FAB2_LIB.BASEBOARD_FAB2(SCH_1):RMII_BMC_OCP_RXER_R
   45  RMII_BMC_OCP_RXD1_R   IO45  @BASEBOARD_FAB2_LIB.BASEBOARD_FAB2(SCH_1):RMII_BMC_OCP_RXD1_R
   43  RMII_BMC_OCP_RXD0_R   IO43  @BASEBOARD_FAB2_LIB.BASEBOARD_FAB2(SCH_1):RMII_BMC_OCP_RXD0_R
   27  RMII_BMC_OCP_CRSDV_R   IO27  @BASEBOARD_FAB2_LIB.BASEBOARD_FAB2(SCH_1):RMII_BMC_OCP_CRSDV_R
    7  P5V_STBY         IO7  @BASEBOARD_FAB2_LIB.BASEBOARD_FAB2(SCH_1):P5V_STBY
    5  P5V_STBY         IO5  @BASEBOARD_FAB2_LIB.BASEBOARD_FAB2(SCH_1):P5V_STBY
    3  P5V_STBY         IO3  @BASEBOARD_FAB2_LIB.BASEBOARD_FAB2(SCH_1):P5V_STBY
   13  P3V3_STBY       IO13  @BASEBOARD_FAB2_LIB.BASEBOARD_FAB2(SCH_1):P3V3_STBY
   12  P3V3_STBY       IO12  @BASEBOARD_FAB2_LIB.BASEBOARD_FAB2(SCH_1):P3V3_STBY
   25  P3V3            IO25  @BASEBOARD_FAB2_LIB.BASEBOARD_FAB2(SCH_1):P3V3
   24  P3V3            IO24  @BASEBOARD_FAB2_LIB.BASEBOARD_FAB2(SCH_1):P3V3
   23  P3V3            IO23  @BASEBOARD_FAB2_LIB.BASEBOARD_FAB2(SCH_1):P3V3
   22  P3V3            IO22  @BASEBOARD_FAB2_LIB.BASEBOARD_FAB2(SCH_1):P3V3
   21  P3V3            IO21  @BASEBOARD_FAB2_LIB.BASEBOARD_FAB2(SCH_1):P3V3
   20  P3V3            IO20  @BASEBOARD_FAB2_LIB.BASEBOARD_FAB2(SCH_1):P3V3
   19  P3V3            IO19  @BASEBOARD_FAB2_LIB.BASEBOARD_FAB2(SCH_1):P3V3
   18  P3V3            IO18  @BASEBOARD_FAB2_LIB.BASEBOARD_FAB2(SCH_1):P3V3
  104  P3E_OCP_CPU0_PE3_C_TXP<9>  IO104  @BASEBOARD_FAB2_LIB.BASEBOARD_FAB2(SCH_1):P3E_OCP_CPU0_PE3_C_TXP<9>
  112  P3E_OCP_CPU0_PE3_C_TXP<8>  IO112  @BASEBOARD_FAB2_LIB.BASEBOARD_FAB2(SCH_1):P3E_OCP_CPU0_PE3_C_TXP<8>
   56  P3E_OCP_CPU0_PE3_C_TXP<15>   IO56  @BASEBOARD_FAB2_LIB.BASEBOARD_FAB2(SCH_1):P3E_OCP_CPU0_PE3_C_TXP<15>
   64  P3E_OCP_CPU0_PE3_C_TXP<14>   IO64  @BASEBOARD_FAB2_LIB.BASEBOARD_FAB2(SCH_1):P3E_OCP_CPU0_PE3_C_TXP<14>
   72  P3E_OCP_CPU0_PE3_C_TXP<13>   IO72  @BASEBOARD_FAB2_LIB.BASEBOARD_FAB2(SCH_1):P3E_OCP_CPU0_PE3_C_TXP<13>
   80  P3E_OCP_CPU0_PE3_C_TXP<12>   IO80  @BASEBOARD_FAB2_LIB.BASEBOARD_FAB2(SCH_1):P3E_OCP_CPU0_PE3_C_TXP<12>
   88  P3E_OCP_CPU0_PE3_C_TXP<11>   IO88  @BASEBOARD_FAB2_LIB.BASEBOARD_FAB2(SCH_1):P3E_OCP_CPU0_PE3_C_TXP<11>
   96  P3E_OCP_CPU0_PE3_C_TXP<10>   IO96  @BASEBOARD_FAB2_LIB.BASEBOARD_FAB2(SCH_1):P3E_OCP_CPU0_PE3_C_TXP<10>
  106  P3E_OCP_CPU0_PE3_C_TXN<9>  IO106  @BASEBOARD_FAB2_LIB.BASEBOARD_FAB2(SCH_1):P3E_OCP_CPU0_PE3_C_TXN<9>
  114  P3E_OCP_CPU0_PE3_C_TXN<8>  IO114  @BASEBOARD_FAB2_LIB.BASEBOARD_FAB2(SCH_1):P3E_OCP_CPU0_PE3_C_TXN<8>
   58  P3E_OCP_CPU0_PE3_C_TXN<15>   IO58  @BASEBOARD_FAB2_LIB.BASEBOARD_FAB2(SCH_1):P3E_OCP_CPU0_PE3_C_TXN<15>
   66  P3E_OCP_CPU0_PE3_C_TXN<14>   IO66  @BASEBOARD_FAB2_LIB.BASEBOARD_FAB2(SCH_1):P3E_OCP_CPU0_PE3_C_TXN<14>
   74  P3E_OCP_CPU0_PE3_C_TXN<13>   IO74  @BASEBOARD_FAB2_LIB.BASEBOARD_FAB2(SCH_1):P3E_OCP_CPU0_PE3_C_TXN<13>
   82  P3E_OCP_CPU0_PE3_C_TXN<12>   IO82  @BASEBOARD_FAB2_LIB.BASEBOARD_FAB2(SCH_1):P3E_OCP_CPU0_PE3_C_TXN<12>
   90  P3E_OCP_CPU0_PE3_C_TXN<11>   IO90  @BASEBOARD_FAB2_LIB.BASEBOARD_FAB2(SCH_1):P3E_OCP_CPU0_PE3_C_TXN<11>
   98  P3E_OCP_CPU0_PE3_C_TXN<10>   IO98  @BASEBOARD_FAB2_LIB.BASEBOARD_FAB2(SCH_1):P3E_OCP_CPU0_PE3_C_TXN<10>
  107  P3E_CPU0_PE3_OCP_RXP<9>  IO107  @BASEBOARD_FAB2_LIB.BASEBOARD_FAB2(SCH_1):P3E_CPU0_PE3_OCP_RXP<9>
  115  P3E_CPU0_PE3_OCP_RXP<8>  IO115  @BASEBOARD_FAB2_LIB.BASEBOARD_FAB2(SCH_1):P3E_CPU0_PE3_OCP_RXP<8>
   59  P3E_CPU0_PE3_OCP_RXP<15>   IO59  @BASEBOARD_FAB2_LIB.BASEBOARD_FAB2(SCH_1):P3E_CPU0_PE3_OCP_RXP<15>
   67  P3E_CPU0_PE3_OCP_RXP<14>   IO67  @BASEBOARD_FAB2_LIB.BASEBOARD_FAB2(SCH_1):P3E_CPU0_PE3_OCP_RXP<14>
   75  P3E_CPU0_PE3_OCP_RXP<13>   IO75  @BASEBOARD_FAB2_LIB.BASEBOARD_FAB2(SCH_1):P3E_CPU0_PE3_OCP_RXP<13>
   83  P3E_CPU0_PE3_OCP_RXP<12>   IO83  @BASEBOARD_FAB2_LIB.BASEBOARD_FAB2(SCH_1):P3E_CPU0_PE3_OCP_RXP<12>
   91  P3E_CPU0_PE3_OCP_RXP<11>   IO91  @BASEBOARD_FAB2_LIB.BASEBOARD_FAB2(SCH_1):P3E_CPU0_PE3_OCP_RXP<11>
   99  P3E_CPU0_PE3_OCP_RXP<10>   IO99  @BASEBOARD_FAB2_LIB.BASEBOARD_FAB2(SCH_1):P3E_CPU0_PE3_OCP_RXP<10>
  109  P3E_CPU0_PE3_OCP_RXN<9>  IO109  @BASEBOARD_FAB2_LIB.BASEBOARD_FAB2(SCH_1):P3E_CPU0_PE3_OCP_RXN<9>
  117  P3E_CPU0_PE3_OCP_RXN<8>  IO117  @BASEBOARD_FAB2_LIB.BASEBOARD_FAB2(SCH_1):P3E_CPU0_PE3_OCP_RXN<8>
   61  P3E_CPU0_PE3_OCP_RXN<15>   IO61  @BASEBOARD_FAB2_LIB.BASEBOARD_FAB2(SCH_1):P3E_CPU0_PE3_OCP_RXN<15>
   69  P3E_CPU0_PE3_OCP_RXN<14>   IO69  @BASEBOARD_FAB2_LIB.BASEBOARD_FAB2(SCH_1):P3E_CPU0_PE3_OCP_RXN<14>
   77  P3E_CPU0_PE3_OCP_RXN<13>   IO77  @BASEBOARD_FAB2_LIB.BASEBOARD_FAB2(SCH_1):P3E_CPU0_PE3_OCP_RXN<13>
   85  P3E_CPU0_PE3_OCP_RXN<12>   IO85  @BASEBOARD_FAB2_LIB.BASEBOARD_FAB2(SCH_1):P3E_CPU0_PE3_OCP_RXN<12>
   93  P3E_CPU0_PE3_OCP_RXN<11>   IO93  @BASEBOARD_FAB2_LIB.BASEBOARD_FAB2(SCH_1):P3E_CPU0_PE3_OCP_RXN<11>
  101  P3E_CPU0_PE3_OCP_RXN<10>  IO101  @BASEBOARD_FAB2_LIB.BASEBOARD_FAB2(SCH_1):P3E_CPU0_PE3_OCP_RXN<10>
    6  P12V_STBY        IO6  @BASEBOARD_FAB2_LIB.BASEBOARD_FAB2(SCH_1):P12V_STBY
    4  P12V_STBY        IO4  @BASEBOARD_FAB2_LIB.BASEBOARD_FAB2(SCH_1):P12V_STBY
    2  P12V_STBY        IO2  @BASEBOARD_FAB2_LIB.BASEBOARD_FAB2(SCH_1):P12V_STBY
   28  IRQ_MEZZ_LAN_ALERT_N   IO28  @BASEBOARD_FAB2_LIB.BASEBOARD_FAB2(SCH_1):IRQ_MEZZ_LAN_ALERT_N
  119  GND            IO119  @BASEBOARD_FAB2_LIB.BASEBOARD_FAB2(SCH_1):GND
  118  GND            IO118  @BASEBOARD_FAB2_LIB.BASEBOARD_FAB2(SCH_1):GND
  116  GND            IO116  @BASEBOARD_FAB2_LIB.BASEBOARD_FAB2(SCH_1):GND
  113  GND            IO113  @BASEBOARD_FAB2_LIB.BASEBOARD_FAB2(SCH_1):GND
  111  GND            IO111  @BASEBOARD_FAB2_LIB.BASEBOARD_FAB2(SCH_1):GND
  110  GND            IO110  @BASEBOARD_FAB2_LIB.BASEBOARD_FAB2(SCH_1):GND
  108  GND            IO108  @BASEBOARD_FAB2_LIB.BASEBOARD_FAB2(SCH_1):GND
  105  GND            IO105  @BASEBOARD_FAB2_LIB.BASEBOARD_FAB2(SCH_1):GND
  103  GND            IO103  @BASEBOARD_FAB2_LIB.BASEBOARD_FAB2(SCH_1):GND
  102  GND            IO102  @BASEBOARD_FAB2_LIB.BASEBOARD_FAB2(SCH_1):GND
  100  GND            IO100  @BASEBOARD_FAB2_LIB.BASEBOARD_FAB2(SCH_1):GND
   97  GND             IO97  @BASEBOARD_FAB2_LIB.BASEBOARD_FAB2(SCH_1):GND
   95  GND             IO95  @BASEBOARD_FAB2_LIB.BASEBOARD_FAB2(SCH_1):GND
   94  GND             IO94  @BASEBOARD_FAB2_LIB.BASEBOARD_FAB2(SCH_1):GND
   92  GND             IO92  @BASEBOARD_FAB2_LIB.BASEBOARD_FAB2(SCH_1):GND
   89  GND             IO89  @BASEBOARD_FAB2_LIB.BASEBOARD_FAB2(SCH_1):GND
   87  GND             IO87  @BASEBOARD_FAB2_LIB.BASEBOARD_FAB2(SCH_1):GND
   86  GND             IO86  @BASEBOARD_FAB2_LIB.BASEBOARD_FAB2(SCH_1):GND
   84  GND             IO84  @BASEBOARD_FAB2_LIB.BASEBOARD_FAB2(SCH_1):GND
   81  GND             IO81  @BASEBOARD_FAB2_LIB.BASEBOARD_FAB2(SCH_1):GND
   79  GND             IO79  @BASEBOARD_FAB2_LIB.BASEBOARD_FAB2(SCH_1):GND
   78  GND             IO78  @BASEBOARD_FAB2_LIB.BASEBOARD_FAB2(SCH_1):GND
   76  GND             IO76  @BASEBOARD_FAB2_LIB.BASEBOARD_FAB2(SCH_1):GND
   73  GND             IO73  @BASEBOARD_FAB2_LIB.BASEBOARD_FAB2(SCH_1):GND
   71  GND             IO71  @BASEBOARD_FAB2_LIB.BASEBOARD_FAB2(SCH_1):GND
   70  GND             IO70  @BASEBOARD_FAB2_LIB.BASEBOARD_FAB2(SCH_1):GND
   68  GND             IO68  @BASEBOARD_FAB2_LIB.BASEBOARD_FAB2(SCH_1):GND
   65  GND             IO65  @BASEBOARD_FAB2_LIB.BASEBOARD_FAB2(SCH_1):GND
   63  GND             IO63  @BASEBOARD_FAB2_LIB.BASEBOARD_FAB2(SCH_1):GND
   62  GND             IO62  @BASEBOARD_FAB2_LIB.BASEBOARD_FAB2(SCH_1):GND
   60  GND             IO60  @BASEBOARD_FAB2_LIB.BASEBOARD_FAB2(SCH_1):GND
   57  GND             IO57  @BASEBOARD_FAB2_LIB.BASEBOARD_FAB2(SCH_1):GND
   55  GND             IO55  @BASEBOARD_FAB2_LIB.BASEBOARD_FAB2(SCH_1):GND
   54  GND             IO54  @BASEBOARD_FAB2_LIB.BASEBOARD_FAB2(SCH_1):GND
   52  GND             IO52  @BASEBOARD_FAB2_LIB.BASEBOARD_FAB2(SCH_1):GND
   49  GND             IO49  @BASEBOARD_FAB2_LIB.BASEBOARD_FAB2(SCH_1):GND
   47  GND             IO47  @BASEBOARD_FAB2_LIB.BASEBOARD_FAB2(SCH_1):GND
   46  GND             IO46  @BASEBOARD_FAB2_LIB.BASEBOARD_FAB2(SCH_1):GND
   44  GND             IO44  @BASEBOARD_FAB2_LIB.BASEBOARD_FAB2(SCH_1):GND
   41  GND             IO41  @BASEBOARD_FAB2_LIB.BASEBOARD_FAB2(SCH_1):GND
   39  GND             IO39  @BASEBOARD_FAB2_LIB.BASEBOARD_FAB2(SCH_1):GND
   38  GND             IO38  @BASEBOARD_FAB2_LIB.BASEBOARD_FAB2(SCH_1):GND
   26  GND             IO26  @BASEBOARD_FAB2_LIB.BASEBOARD_FAB2(SCH_1):GND
   17  GND             IO17  @BASEBOARD_FAB2_LIB.BASEBOARD_FAB2(SCH_1):GND
   16  GND             IO16  @BASEBOARD_FAB2_LIB.BASEBOARD_FAB2(SCH_1):GND
   15  GND             IO15  @BASEBOARD_FAB2_LIB.BASEBOARD_FAB2(SCH_1):GND
   14  GND             IO14  @BASEBOARD_FAB2_LIB.BASEBOARD_FAB2(SCH_1):GND
   11  GND             IO11  @BASEBOARD_FAB2_LIB.BASEBOARD_FAB2(SCH_1):GND
   10  GND             IO10  @BASEBOARD_FAB2_LIB.BASEBOARD_FAB2(SCH_1):GND
    9  GND              IO9  @BASEBOARD_FAB2_LIB.BASEBOARD_FAB2(SCH_1):GND
    8  GND              IO8  @BASEBOARD_FAB2_LIB.BASEBOARD_FAB2(SCH_1):GND
   34  FM_PE_OCP_WAKE_N   IO34  @BASEBOARD_FAB2_LIB.BASEBOARD_FAB2(SCH_1):FM_PE_OCP_WAKE_N
  120  FM_OCP_MEZZA_PRES_N  IO120  @BASEBOARD_FAB2_LIB.BASEBOARD_FAB2(SCH_1):FM_OCP_MEZZA_PRES_N
    1  FM_MEZZA_PRSNT1_N    IO1  @BASEBOARD_FAB2_LIB.BASEBOARD_FAB2(SCH_1):FM_MEZZA_PRSNT1_N
   29  CLK_50M_CKMNG_OCP   IO29  @BASEBOARD_FAB2_LIB.BASEBOARD_FAB2(SCH_1):CLK_50M_CKMNG_OCP
   51  CLK_100M_MEZZ2_DP   IO51  @BASEBOARD_FAB2_LIB.BASEBOARD_FAB2(SCH_1):CLK_100M_MEZZ2_DP
   53  CLK_100M_MEZZ2_DN   IO53  @BASEBOARD_FAB2_LIB.BASEBOARD_FAB2(SCH_1):CLK_100M_MEZZ2_DN
   48  CLK_100M_MEZZ1_DP   IO48  @BASEBOARD_FAB2_LIB.BASEBOARD_FAB2(SCH_1):CLK_100M_MEZZ1_DP
   50  CLK_100M_MEZZ1_DN   IO50  @BASEBOARD_FAB2_LIB.BASEBOARD_FAB2(SCH_1):CLK_100M_MEZZ1_DN

SCONN10_C12536004  I175  J9B4   [SCONN10_C12536004_SMLF-CONN,C1A]
    8  TP_JTAG_MCP_IO8_RSVD    IO8  @BASEBOARD_FAB2_LIB.BASEBOARD_FAB2(SCH_1):TP_JTAG_MCP_IO8_RSVD
    7  PWRGD_CPU0_G_R    IO7  @BASEBOARD_FAB2_LIB.BASEBOARD_FAB2(SCH_1):PWRGD_CPU0_G_R
    4  P1V8_MCP_CPU0    IO4  @BASEBOARD_FAB2_LIB.BASEBOARD_FAB2(SCH_1):P1V8_MCP_CPU0
    6  JTAG_MCP_TRST_N    IO6  @BASEBOARD_FAB2_LIB.BASEBOARD_FAB2(SCH_1):JTAG_MCP_TRST_N
    5  JTAG_MCP_TMS_R    IO5  @BASEBOARD_FAB2_LIB.BASEBOARD_FAB2(SCH_1):JTAG_MCP_TMS_R
    1  JTAG_MCP_TCK_R    IO1  @BASEBOARD_FAB2_LIB.BASEBOARD_FAB2(SCH_1):JTAG_MCP_TCK_R
    3  JTAG_MCP_MUX_TDO    IO3  @BASEBOARD_FAB2_LIB.BASEBOARD_FAB2(SCH_1):JTAG_MCP_MUX_TDO
    9  JTAG_MCP_MUX_TDI    IO9  @BASEBOARD_FAB2_LIB.BASEBOARD_FAB2(SCH_1):JTAG_MCP_MUX_TDI
   10  GND             IO10  @BASEBOARD_FAB2_LIB.BASEBOARD_FAB2(SCH_1):GND
    2  GND              IO2  @BASEBOARD_FAB2_LIB.BASEBOARD_FAB2(SCH_1):GND

CONN12_C73564003  I128  J9G1   [CONN12_C73564003_PIP-CONN,C735A]
    2  TP_RST_RTCRST_N    IO2  @BASEBOARD_FAB2_LIB.BASEBOARD_FAB2(SCH_1):TP_RST_RTCRST_N
    8  TP_JUMPER_BLOCK_2_8    IO8  @BASEBOARD_FAB2_LIB.BASEBOARD_FAB2(SCH_1):TP_JUMPER_BLOCK_2_8
   12  TP_JUMPER_BLOCK_2_12   IO12  @BASEBOARD_FAB2_LIB.BASEBOARD_FAB2(SCH_1):TP_JUMPER_BLOCK_2_12
   10  TP_JUMPER_BLOCK_2_10   IO10  @BASEBOARD_FAB2_LIB.BASEBOARD_FAB2(SCH_1):TP_JUMPER_BLOCK_2_10
    7  TP_IE_DEBUG_MODE    IO7  @BASEBOARD_FAB2_LIB.BASEBOARD_FAB2(SCH_1):TP_IE_DEBUG_MODE
    1  TP_BMC_DISABLE    IO1  @BASEBOARD_FAB2_LIB.BASEBOARD_FAB2(SCH_1):TP_BMC_DISABLE
    4  RST_RTCRST_N     IO4  @BASEBOARD_FAB2_LIB.BASEBOARD_FAB2(SCH_1):RST_RTCRST_N
    6  PD_RST_RTCRST_N    IO6  @BASEBOARD_FAB2_LIB.BASEBOARD_FAB2(SCH_1):PD_RST_RTCRST_N
   11  PD_IE_DEBUG_MODE   IO11  @BASEBOARD_FAB2_LIB.BASEBOARD_FAB2(SCH_1):PD_IE_DEBUG_MODE
    9  FM_UART_PRES_N    IO9  @BASEBOARD_FAB2_LIB.BASEBOARD_FAB2(SCH_1):FM_UART_PRES_N
    3  FM_ROMA<0>       IO3  @BASEBOARD_FAB2_LIB.BASEBOARD_FAB2(SCH_1):FM_ROMA<0>
    5  FM_BMC_DISABLE    IO5  @BASEBOARD_FAB2_LIB.BASEBOARD_FAB2(SCH_1):FM_BMC_DISABLE

SCONN288_H44441003_PIP  I168  J9L1   [SCONN288_H44441003_PIP-SCONN,HA]
   77  PVTT_KLM       VTT<1>  @BASEBOARD_FAB2_LIB.BASEBOARD_FAB2(SCH_1):PVTT_KLM
  221  PVTT_KLM       VTT<0>  @BASEBOARD_FAB2_LIB.BASEBOARD_FAB2(SCH_1):PVTT_KLM
  142  PVPP_KLM       VPP<4>  @BASEBOARD_FAB2_LIB.BASEBOARD_FAB2(SCH_1):PVPP_KLM
  143  PVPP_KLM       VPP<3>  @BASEBOARD_FAB2_LIB.BASEBOARD_FAB2(SCH_1):PVPP_KLM
  288  PVPP_KLM       VPP<2>  @BASEBOARD_FAB2_LIB.BASEBOARD_FAB2(SCH_1):PVPP_KLM
  286  PVPP_KLM       VPP<1>  @BASEBOARD_FAB2_LIB.BASEBOARD_FAB2(SCH_1):PVPP_KLM
  287  PVPP_KLM       VPP<0>  @BASEBOARD_FAB2_LIB.BASEBOARD_FAB2(SCH_1):PVPP_KLM
   59  PVDDQ_KLM      VDD<25>  @BASEBOARD_FAB2_LIB.BASEBOARD_FAB2(SCH_1):PVDDQ_KLM
   61  PVDDQ_KLM      VDD<24>  @BASEBOARD_FAB2_LIB.BASEBOARD_FAB2(SCH_1):PVDDQ_KLM
   64  PVDDQ_KLM      VDD<23>  @BASEBOARD_FAB2_LIB.BASEBOARD_FAB2(SCH_1):PVDDQ_KLM
   67  PVDDQ_KLM      VDD<22>  @BASEBOARD_FAB2_LIB.BASEBOARD_FAB2(SCH_1):PVDDQ_KLM
   70  PVDDQ_KLM      VDD<21>  @BASEBOARD_FAB2_LIB.BASEBOARD_FAB2(SCH_1):PVDDQ_KLM
   73  PVDDQ_KLM      VDD<20>  @BASEBOARD_FAB2_LIB.BASEBOARD_FAB2(SCH_1):PVDDQ_KLM
   76  PVDDQ_KLM      VDD<19>  @BASEBOARD_FAB2_LIB.BASEBOARD_FAB2(SCH_1):PVDDQ_KLM
   80  PVDDQ_KLM      VDD<18>  @BASEBOARD_FAB2_LIB.BASEBOARD_FAB2(SCH_1):PVDDQ_KLM
   83  PVDDQ_KLM      VDD<17>  @BASEBOARD_FAB2_LIB.BASEBOARD_FAB2(SCH_1):PVDDQ_KLM
   85  PVDDQ_KLM      VDD<16>  @BASEBOARD_FAB2_LIB.BASEBOARD_FAB2(SCH_1):PVDDQ_KLM
   88  PVDDQ_KLM      VDD<15>  @BASEBOARD_FAB2_LIB.BASEBOARD_FAB2(SCH_1):PVDDQ_KLM
   90  PVDDQ_KLM      VDD<14>  @BASEBOARD_FAB2_LIB.BASEBOARD_FAB2(SCH_1):PVDDQ_KLM
   92  PVDDQ_KLM      VDD<13>  @BASEBOARD_FAB2_LIB.BASEBOARD_FAB2(SCH_1):PVDDQ_KLM
  204  PVDDQ_KLM      VDD<12>  @BASEBOARD_FAB2_LIB.BASEBOARD_FAB2(SCH_1):PVDDQ_KLM
  206  PVDDQ_KLM      VDD<11>  @BASEBOARD_FAB2_LIB.BASEBOARD_FAB2(SCH_1):PVDDQ_KLM
  209  PVDDQ_KLM      VDD<10>  @BASEBOARD_FAB2_LIB.BASEBOARD_FAB2(SCH_1):PVDDQ_KLM
  212  PVDDQ_KLM      VDD<9>  @BASEBOARD_FAB2_LIB.BASEBOARD_FAB2(SCH_1):PVDDQ_KLM
  215  PVDDQ_KLM      VDD<8>  @BASEBOARD_FAB2_LIB.BASEBOARD_FAB2(SCH_1):PVDDQ_KLM
  217  PVDDQ_KLM      VDD<7>  @BASEBOARD_FAB2_LIB.BASEBOARD_FAB2(SCH_1):PVDDQ_KLM
  220  PVDDQ_KLM      VDD<6>  @BASEBOARD_FAB2_LIB.BASEBOARD_FAB2(SCH_1):PVDDQ_KLM
  223  PVDDQ_KLM      VDD<5>  @BASEBOARD_FAB2_LIB.BASEBOARD_FAB2(SCH_1):PVDDQ_KLM
  226  PVDDQ_KLM      VDD<4>  @BASEBOARD_FAB2_LIB.BASEBOARD_FAB2(SCH_1):PVDDQ_KLM
  229  PVDDQ_KLM      VDD<3>  @BASEBOARD_FAB2_LIB.BASEBOARD_FAB2(SCH_1):PVDDQ_KLM
  231  PVDDQ_KLM      VDD<2>  @BASEBOARD_FAB2_LIB.BASEBOARD_FAB2(SCH_1):PVDDQ_KLM
  233  PVDDQ_KLM      VDD<1>  @BASEBOARD_FAB2_LIB.BASEBOARD_FAB2(SCH_1):PVDDQ_KLM
  236  PVDDQ_KLM      VDD<0>  @BASEBOARD_FAB2_LIB.BASEBOARD_FAB2(SCH_1):PVDDQ_KLM
    1  P12V_NVDIMM_KLM  12V<1>  @BASEBOARD_FAB2_LIB.BASEBOARD_FAB2(SCH_1):P12V_NVDIMM_KLM
  145  P12V_NVDIMM_KLM  12V<0>  @BASEBOARD_FAB2_LIB.BASEBOARD_FAB2(SCH_1):P12V_NVDIMM_KLM

SCONN288_H44441003_PIP  I25  J9L1   [SCONN288_H44441003_PIP-SCONN,HA]
    2  GND            VSS<93>  @BASEBOARD_FAB2_LIB.BASEBOARD_FAB2(SCH_1):GND
    4  GND            VSS<92>  @BASEBOARD_FAB2_LIB.BASEBOARD_FAB2(SCH_1):GND
    6  GND            VSS<91>  @BASEBOARD_FAB2_LIB.BASEBOARD_FAB2(SCH_1):GND
    9  GND            VSS<90>  @BASEBOARD_FAB2_LIB.BASEBOARD_FAB2(SCH_1):GND
   11  GND            VSS<89>  @BASEBOARD_FAB2_LIB.BASEBOARD_FAB2(SCH_1):GND
   13  GND            VSS<88>  @BASEBOARD_FAB2_LIB.BASEBOARD_FAB2(SCH_1):GND
   15  GND            VSS<87>  @BASEBOARD_FAB2_LIB.BASEBOARD_FAB2(SCH_1):GND
   17  GND            VSS<86>  @BASEBOARD_FAB2_LIB.BASEBOARD_FAB2(SCH_1):GND
   20  GND            VSS<85>  @BASEBOARD_FAB2_LIB.BASEBOARD_FAB2(SCH_1):GND
   22  GND            VSS<84>  @BASEBOARD_FAB2_LIB.BASEBOARD_FAB2(SCH_1):GND
   24  GND            VSS<83>  @BASEBOARD_FAB2_LIB.BASEBOARD_FAB2(SCH_1):GND
   26  GND            VSS<82>  @BASEBOARD_FAB2_LIB.BASEBOARD_FAB2(SCH_1):GND
   28  GND            VSS<81>  @BASEBOARD_FAB2_LIB.BASEBOARD_FAB2(SCH_1):GND
   31  GND            VSS<80>  @BASEBOARD_FAB2_LIB.BASEBOARD_FAB2(SCH_1):GND
   33  GND            VSS<79>  @BASEBOARD_FAB2_LIB.BASEBOARD_FAB2(SCH_1):GND
   35  GND            VSS<78>  @BASEBOARD_FAB2_LIB.BASEBOARD_FAB2(SCH_1):GND
   37  GND            VSS<77>  @BASEBOARD_FAB2_LIB.BASEBOARD_FAB2(SCH_1):GND
   39  GND            VSS<76>  @BASEBOARD_FAB2_LIB.BASEBOARD_FAB2(SCH_1):GND
   42  GND            VSS<75>  @BASEBOARD_FAB2_LIB.BASEBOARD_FAB2(SCH_1):GND
   44  GND            VSS<74>  @BASEBOARD_FAB2_LIB.BASEBOARD_FAB2(SCH_1):GND
   46  GND            VSS<73>  @BASEBOARD_FAB2_LIB.BASEBOARD_FAB2(SCH_1):GND
   48  GND            VSS<72>  @BASEBOARD_FAB2_LIB.BASEBOARD_FAB2(SCH_1):GND
   50  GND            VSS<71>  @BASEBOARD_FAB2_LIB.BASEBOARD_FAB2(SCH_1):GND
   53  GND            VSS<70>  @BASEBOARD_FAB2_LIB.BASEBOARD_FAB2(SCH_1):GND
   55  GND            VSS<69>  @BASEBOARD_FAB2_LIB.BASEBOARD_FAB2(SCH_1):GND
   57  GND            VSS<68>  @BASEBOARD_FAB2_LIB.BASEBOARD_FAB2(SCH_1):GND
   94  GND            VSS<67>  @BASEBOARD_FAB2_LIB.BASEBOARD_FAB2(SCH_1):GND
   96  GND            VSS<66>  @BASEBOARD_FAB2_LIB.BASEBOARD_FAB2(SCH_1):GND
   98  GND            VSS<65>  @BASEBOARD_FAB2_LIB.BASEBOARD_FAB2(SCH_1):GND
  101  GND            VSS<64>  @BASEBOARD_FAB2_LIB.BASEBOARD_FAB2(SCH_1):GND
  103  GND            VSS<63>  @BASEBOARD_FAB2_LIB.BASEBOARD_FAB2(SCH_1):GND
  105  GND            VSS<62>  @BASEBOARD_FAB2_LIB.BASEBOARD_FAB2(SCH_1):GND
  107  GND            VSS<61>  @BASEBOARD_FAB2_LIB.BASEBOARD_FAB2(SCH_1):GND
  109  GND            VSS<60>  @BASEBOARD_FAB2_LIB.BASEBOARD_FAB2(SCH_1):GND
  112  GND            VSS<59>  @BASEBOARD_FAB2_LIB.BASEBOARD_FAB2(SCH_1):GND
  114  GND            VSS<58>  @BASEBOARD_FAB2_LIB.BASEBOARD_FAB2(SCH_1):GND
  116  GND            VSS<57>  @BASEBOARD_FAB2_LIB.BASEBOARD_FAB2(SCH_1):GND
  118  GND            VSS<56>  @BASEBOARD_FAB2_LIB.BASEBOARD_FAB2(SCH_1):GND
  120  GND            VSS<55>  @BASEBOARD_FAB2_LIB.BASEBOARD_FAB2(SCH_1):GND
  123  GND            VSS<54>  @BASEBOARD_FAB2_LIB.BASEBOARD_FAB2(SCH_1):GND
  125  GND            VSS<53>  @BASEBOARD_FAB2_LIB.BASEBOARD_FAB2(SCH_1):GND
  127  GND            VSS<52>  @BASEBOARD_FAB2_LIB.BASEBOARD_FAB2(SCH_1):GND
  129  GND            VSS<51>  @BASEBOARD_FAB2_LIB.BASEBOARD_FAB2(SCH_1):GND
  131  GND            VSS<50>  @BASEBOARD_FAB2_LIB.BASEBOARD_FAB2(SCH_1):GND
  134  GND            VSS<49>  @BASEBOARD_FAB2_LIB.BASEBOARD_FAB2(SCH_1):GND
  136  GND            VSS<48>  @BASEBOARD_FAB2_LIB.BASEBOARD_FAB2(SCH_1):GND
  138  GND            VSS<47>  @BASEBOARD_FAB2_LIB.BASEBOARD_FAB2(SCH_1):GND
  147  GND            VSS<46>  @BASEBOARD_FAB2_LIB.BASEBOARD_FAB2(SCH_1):GND
  149  GND            VSS<45>  @BASEBOARD_FAB2_LIB.BASEBOARD_FAB2(SCH_1):GND
  151  GND            VSS<44>  @BASEBOARD_FAB2_LIB.BASEBOARD_FAB2(SCH_1):GND
  154  GND            VSS<43>  @BASEBOARD_FAB2_LIB.BASEBOARD_FAB2(SCH_1):GND
  156  GND            VSS<42>  @BASEBOARD_FAB2_LIB.BASEBOARD_FAB2(SCH_1):GND
  158  GND            VSS<41>  @BASEBOARD_FAB2_LIB.BASEBOARD_FAB2(SCH_1):GND
  160  GND            VSS<40>  @BASEBOARD_FAB2_LIB.BASEBOARD_FAB2(SCH_1):GND
  162  GND            VSS<39>  @BASEBOARD_FAB2_LIB.BASEBOARD_FAB2(SCH_1):GND
  165  GND            VSS<38>  @BASEBOARD_FAB2_LIB.BASEBOARD_FAB2(SCH_1):GND
  167  GND            VSS<37>  @BASEBOARD_FAB2_LIB.BASEBOARD_FAB2(SCH_1):GND
  169  GND            VSS<36>  @BASEBOARD_FAB2_LIB.BASEBOARD_FAB2(SCH_1):GND
  171  GND            VSS<35>  @BASEBOARD_FAB2_LIB.BASEBOARD_FAB2(SCH_1):GND
  173  GND            VSS<34>  @BASEBOARD_FAB2_LIB.BASEBOARD_FAB2(SCH_1):GND
  176  GND            VSS<33>  @BASEBOARD_FAB2_LIB.BASEBOARD_FAB2(SCH_1):GND
  178  GND            VSS<32>  @BASEBOARD_FAB2_LIB.BASEBOARD_FAB2(SCH_1):GND
  180  GND            VSS<31>  @BASEBOARD_FAB2_LIB.BASEBOARD_FAB2(SCH_1):GND
  182  GND            VSS<30>  @BASEBOARD_FAB2_LIB.BASEBOARD_FAB2(SCH_1):GND
  184  GND            VSS<29>  @BASEBOARD_FAB2_LIB.BASEBOARD_FAB2(SCH_1):GND
  187  GND            VSS<28>  @BASEBOARD_FAB2_LIB.BASEBOARD_FAB2(SCH_1):GND
  189  GND            VSS<27>  @BASEBOARD_FAB2_LIB.BASEBOARD_FAB2(SCH_1):GND
  191  GND            VSS<26>  @BASEBOARD_FAB2_LIB.BASEBOARD_FAB2(SCH_1):GND
  193  GND            VSS<25>  @BASEBOARD_FAB2_LIB.BASEBOARD_FAB2(SCH_1):GND
  195  GND            VSS<24>  @BASEBOARD_FAB2_LIB.BASEBOARD_FAB2(SCH_1):GND
  198  GND            VSS<23>  @BASEBOARD_FAB2_LIB.BASEBOARD_FAB2(SCH_1):GND
  200  GND            VSS<22>  @BASEBOARD_FAB2_LIB.BASEBOARD_FAB2(SCH_1):GND
  202  GND            VSS<21>  @BASEBOARD_FAB2_LIB.BASEBOARD_FAB2(SCH_1):GND
  239  GND            VSS<20>  @BASEBOARD_FAB2_LIB.BASEBOARD_FAB2(SCH_1):GND
  241  GND            VSS<19>  @BASEBOARD_FAB2_LIB.BASEBOARD_FAB2(SCH_1):GND
  243  GND            VSS<18>  @BASEBOARD_FAB2_LIB.BASEBOARD_FAB2(SCH_1):GND
  246  GND            VSS<17>  @BASEBOARD_FAB2_LIB.BASEBOARD_FAB2(SCH_1):GND
  248  GND            VSS<16>  @BASEBOARD_FAB2_LIB.BASEBOARD_FAB2(SCH_1):GND
  250  GND            VSS<15>  @BASEBOARD_FAB2_LIB.BASEBOARD_FAB2(SCH_1):GND
  252  GND            VSS<14>  @BASEBOARD_FAB2_LIB.BASEBOARD_FAB2(SCH_1):GND
  254  GND            VSS<13>  @BASEBOARD_FAB2_LIB.BASEBOARD_FAB2(SCH_1):GND
  257  GND            VSS<12>  @BASEBOARD_FAB2_LIB.BASEBOARD_FAB2(SCH_1):GND
  259  GND            VSS<11>  @BASEBOARD_FAB2_LIB.BASEBOARD_FAB2(SCH_1):GND
  261  GND            VSS<10>  @BASEBOARD_FAB2_LIB.BASEBOARD_FAB2(SCH_1):GND
  263  GND            VSS<9>  @BASEBOARD_FAB2_LIB.BASEBOARD_FAB2(SCH_1):GND
  265  GND            VSS<8>  @BASEBOARD_FAB2_LIB.BASEBOARD_FAB2(SCH_1):GND
  268  GND            VSS<7>  @BASEBOARD_FAB2_LIB.BASEBOARD_FAB2(SCH_1):GND
  270  GND            VSS<6>  @BASEBOARD_FAB2_LIB.BASEBOARD_FAB2(SCH_1):GND
  272  GND            VSS<5>  @BASEBOARD_FAB2_LIB.BASEBOARD_FAB2(SCH_1):GND
  274  GND            VSS<4>  @BASEBOARD_FAB2_LIB.BASEBOARD_FAB2(SCH_1):GND
  276  GND            VSS<3>  @BASEBOARD_FAB2_LIB.BASEBOARD_FAB2(SCH_1):GND
  279  GND            VSS<2>  @BASEBOARD_FAB2_LIB.BASEBOARD_FAB2(SCH_1):GND
  281  GND            VSS<1>  @BASEBOARD_FAB2_LIB.BASEBOARD_FAB2(SCH_1):GND
  283  GND            VSS<0>  @BASEBOARD_FAB2_LIB.BASEBOARD_FAB2(SCH_1):GND

SCONN288_H44441003_PIP  I87  J9L1   [SCONN288_H44441003_PIP-SCONN,HA]
    7  M_M_DQS_DP<9>  DQS9P  @BASEBOARD_FAB2_LIB.BASEBOARD_FAB2(SCH_1):M_M_DQS_DP<9>
  197  M_M_DQS_DP<8>  DQS8P  @BASEBOARD_FAB2_LIB.BASEBOARD_FAB2(SCH_1):M_M_DQS_DP<8>
  278  M_M_DQS_DP<7>  DQS7P  @BASEBOARD_FAB2_LIB.BASEBOARD_FAB2(SCH_1):M_M_DQS_DP<7>
  267  M_M_DQS_DP<6>  DQS6P  @BASEBOARD_FAB2_LIB.BASEBOARD_FAB2(SCH_1):M_M_DQS_DP<6>
  256  M_M_DQS_DP<5>  DQS5P  @BASEBOARD_FAB2_LIB.BASEBOARD_FAB2(SCH_1):M_M_DQS_DP<5>
  245  M_M_DQS_DP<4>  DQS4P  @BASEBOARD_FAB2_LIB.BASEBOARD_FAB2(SCH_1):M_M_DQS_DP<4>
  186  M_M_DQS_DP<3>  DQS3P  @BASEBOARD_FAB2_LIB.BASEBOARD_FAB2(SCH_1):M_M_DQS_DP<3>
  175  M_M_DQS_DP<2>  DQS2P  @BASEBOARD_FAB2_LIB.BASEBOARD_FAB2(SCH_1):M_M_DQS_DP<2>
  164  M_M_DQS_DP<1>  DQS1P  @BASEBOARD_FAB2_LIB.BASEBOARD_FAB2(SCH_1):M_M_DQS_DP<1>
   51  M_M_DQS_DP<17>  DQS17P  @BASEBOARD_FAB2_LIB.BASEBOARD_FAB2(SCH_1):M_M_DQS_DP<17>
  132  M_M_DQS_DP<16>  DQS16P  @BASEBOARD_FAB2_LIB.BASEBOARD_FAB2(SCH_1):M_M_DQS_DP<16>
  121  M_M_DQS_DP<15>  DQS15P  @BASEBOARD_FAB2_LIB.BASEBOARD_FAB2(SCH_1):M_M_DQS_DP<15>
  110  M_M_DQS_DP<14>  DQS14P  @BASEBOARD_FAB2_LIB.BASEBOARD_FAB2(SCH_1):M_M_DQS_DP<14>
   99  M_M_DQS_DP<13>  DQS13P  @BASEBOARD_FAB2_LIB.BASEBOARD_FAB2(SCH_1):M_M_DQS_DP<13>
   40  M_M_DQS_DP<12>  DQS12P  @BASEBOARD_FAB2_LIB.BASEBOARD_FAB2(SCH_1):M_M_DQS_DP<12>
   29  M_M_DQS_DP<11>  DQS11P  @BASEBOARD_FAB2_LIB.BASEBOARD_FAB2(SCH_1):M_M_DQS_DP<11>
   18  M_M_DQS_DP<10>  DQS10P  @BASEBOARD_FAB2_LIB.BASEBOARD_FAB2(SCH_1):M_M_DQS_DP<10>
  153  M_M_DQS_DP<0>  DQS0P  @BASEBOARD_FAB2_LIB.BASEBOARD_FAB2(SCH_1):M_M_DQS_DP<0>
    8  M_M_DQS_DN<9>  DQS9N  @BASEBOARD_FAB2_LIB.BASEBOARD_FAB2(SCH_1):M_M_DQS_DN<9>
  196  M_M_DQS_DN<8>  DQS8N  @BASEBOARD_FAB2_LIB.BASEBOARD_FAB2(SCH_1):M_M_DQS_DN<8>
  277  M_M_DQS_DN<7>  DQS7N  @BASEBOARD_FAB2_LIB.BASEBOARD_FAB2(SCH_1):M_M_DQS_DN<7>
  266  M_M_DQS_DN<6>  DQS6N  @BASEBOARD_FAB2_LIB.BASEBOARD_FAB2(SCH_1):M_M_DQS_DN<6>
  255  M_M_DQS_DN<5>  DQS5N  @BASEBOARD_FAB2_LIB.BASEBOARD_FAB2(SCH_1):M_M_DQS_DN<5>
  244  M_M_DQS_DN<4>  DQS4N  @BASEBOARD_FAB2_LIB.BASEBOARD_FAB2(SCH_1):M_M_DQS_DN<4>
  185  M_M_DQS_DN<3>  DQS3N  @BASEBOARD_FAB2_LIB.BASEBOARD_FAB2(SCH_1):M_M_DQS_DN<3>
  174  M_M_DQS_DN<2>  DQS2N  @BASEBOARD_FAB2_LIB.BASEBOARD_FAB2(SCH_1):M_M_DQS_DN<2>
  163  M_M_DQS_DN<1>  DQS1N  @BASEBOARD_FAB2_LIB.BASEBOARD_FAB2(SCH_1):M_M_DQS_DN<1>
   52  M_M_DQS_DN<17>  DQS17N  @BASEBOARD_FAB2_LIB.BASEBOARD_FAB2(SCH_1):M_M_DQS_DN<17>
  133  M_M_DQS_DN<16>  DQS16N  @BASEBOARD_FAB2_LIB.BASEBOARD_FAB2(SCH_1):M_M_DQS_DN<16>
  122  M_M_DQS_DN<15>  DQS15N  @BASEBOARD_FAB2_LIB.BASEBOARD_FAB2(SCH_1):M_M_DQS_DN<15>
  111  M_M_DQS_DN<14>  DQS14N  @BASEBOARD_FAB2_LIB.BASEBOARD_FAB2(SCH_1):M_M_DQS_DN<14>
  100  M_M_DQS_DN<13>  DQS13N  @BASEBOARD_FAB2_LIB.BASEBOARD_FAB2(SCH_1):M_M_DQS_DN<13>
   41  M_M_DQS_DN<12>  DQS12N  @BASEBOARD_FAB2_LIB.BASEBOARD_FAB2(SCH_1):M_M_DQS_DN<12>
   30  M_M_DQS_DN<11>  DQS11N  @BASEBOARD_FAB2_LIB.BASEBOARD_FAB2(SCH_1):M_M_DQS_DN<11>
   19  M_M_DQS_DN<10>  DQS10N  @BASEBOARD_FAB2_LIB.BASEBOARD_FAB2(SCH_1):M_M_DQS_DN<10>
  152  M_M_DQS_DN<0>  DQS0N  @BASEBOARD_FAB2_LIB.BASEBOARD_FAB2(SCH_1):M_M_DQS_DN<0>

SCONN288_H44441003_PIP  I111  J9L1   [SCONN288_H44441003_PIP-SCONN,HA]
  144  TP_CH_M_DIMM_M1_RFU_2  RFU<2>  @BASEBOARD_FAB2_LIB.BASEBOARD_FAB2(SCH_1):TP_CH_M_DIMM_M1_RFU_2
  227  TP_CH_M_DIMM_M1_RFU_1  RFU<1>  @BASEBOARD_FAB2_LIB.BASEBOARD_FAB2(SCH_1):TP_CH_M_DIMM_M1_RFU_1
  205  TP_CH_M_DIMM_M1_RFU_0  RFU<0>  @BASEBOARD_FAB2_LIB.BASEBOARD_FAB2(SCH_1):TP_CH_M_DIMM_M1_RFU_0
  285  SMB_DDR_KLM_VPP_SDA    SDA  @BASEBOARD_FAB2_LIB.BASEBOARD_FAB2(SCH_1):SMB_DDR_KLM_VPP_SDA
  141  SMB_DDR_KLM_VPP_SCL    SCL  @BASEBOARD_FAB2_LIB.BASEBOARD_FAB2(SCH_1):SMB_DDR_KLM_VPP_SCL
  284  PVPP_KLM       VDDSPD  @BASEBOARD_FAB2_LIB.BASEBOARD_FAB2(SCH_1):PVPP_KLM
  238  PVPP_KLM       SA<2>  @BASEBOARD_FAB2_LIB.BASEBOARD_FAB2(SCH_1):PVPP_KLM
  139  PVPP_KLM       SA<0>  @BASEBOARD_FAB2_LIB.BASEBOARD_FAB2(SCH_1):PVPP_KLM
  146  M_M_VREF       VREFCA  @BASEBOARD_FAB2_LIB.BASEBOARD_FAB2(SCH_1):M_M_VREF
  222  M_M_PAR          PAR  @BASEBOARD_FAB2_LIB.BASEBOARD_FAB2(SCH_1):M_M_PAR
   91  M_M_ODT<3>     ODT<1>  @BASEBOARD_FAB2_LIB.BASEBOARD_FAB2(SCH_1):M_M_ODT<3>
   87  M_M_ODT<2>     ODT<0>  @BASEBOARD_FAB2_LIB.BASEBOARD_FAB2(SCH_1):M_M_ODT<2>
   66  M_M_MA<9>         A9  @BASEBOARD_FAB2_LIB.BASEBOARD_FAB2(SCH_1):M_M_MA<9>
   68  M_M_MA<8>         A8  @BASEBOARD_FAB2_LIB.BASEBOARD_FAB2(SCH_1):M_M_MA<8>
  211  M_M_MA<7>         A7  @BASEBOARD_FAB2_LIB.BASEBOARD_FAB2(SCH_1):M_M_MA<7>
   69  M_M_MA<6>         A6  @BASEBOARD_FAB2_LIB.BASEBOARD_FAB2(SCH_1):M_M_MA<6>
  213  M_M_MA<5>         A5  @BASEBOARD_FAB2_LIB.BASEBOARD_FAB2(SCH_1):M_M_MA<5>
  214  M_M_MA<4>         A4  @BASEBOARD_FAB2_LIB.BASEBOARD_FAB2(SCH_1):M_M_MA<4>
   71  M_M_MA<3>         A3  @BASEBOARD_FAB2_LIB.BASEBOARD_FAB2(SCH_1):M_M_MA<3>
  216  M_M_MA<2>         A2  @BASEBOARD_FAB2_LIB.BASEBOARD_FAB2(SCH_1):M_M_MA<2>
   72  M_M_MA<1>         A1  @BASEBOARD_FAB2_LIB.BASEBOARD_FAB2(SCH_1):M_M_MA<1>
  234  M_M_MA<17>       A17  @BASEBOARD_FAB2_LIB.BASEBOARD_FAB2(SCH_1):M_M_MA<17>
   82  M_M_MA<16>     A16_RAS_N  @BASEBOARD_FAB2_LIB.BASEBOARD_FAB2(SCH_1):M_M_MA<16>
   86  M_M_MA<15>     A15_CAS_N  @BASEBOARD_FAB2_LIB.BASEBOARD_FAB2(SCH_1):M_M_MA<15>
  228  M_M_MA<14>     A14_WE_N  @BASEBOARD_FAB2_LIB.BASEBOARD_FAB2(SCH_1):M_M_MA<14>
  232  M_M_MA<13>       A13  @BASEBOARD_FAB2_LIB.BASEBOARD_FAB2(SCH_1):M_M_MA<13>
   65  M_M_MA<12>       A12  @BASEBOARD_FAB2_LIB.BASEBOARD_FAB2(SCH_1):M_M_MA<12>
  210  M_M_MA<11>       A11  @BASEBOARD_FAB2_LIB.BASEBOARD_FAB2(SCH_1):M_M_MA<11>
  225  M_M_MA<10>       A10  @BASEBOARD_FAB2_LIB.BASEBOARD_FAB2(SCH_1):M_M_MA<10>
   79  M_M_MA<0>         A0  @BASEBOARD_FAB2_LIB.BASEBOARD_FAB2(SCH_1):M_M_MA<0>
  199  M_M_ECC<7>     CB<7>  @BASEBOARD_FAB2_LIB.BASEBOARD_FAB2(SCH_1):M_M_ECC<7>
   54  M_M_ECC<6>     CB<6>  @BASEBOARD_FAB2_LIB.BASEBOARD_FAB2(SCH_1):M_M_ECC<6>
  192  M_M_ECC<5>     CB<5>  @BASEBOARD_FAB2_LIB.BASEBOARD_FAB2(SCH_1):M_M_ECC<5>
   47  M_M_ECC<4>     CB<4>  @BASEBOARD_FAB2_LIB.BASEBOARD_FAB2(SCH_1):M_M_ECC<4>
  201  M_M_ECC<3>     CB<3>  @BASEBOARD_FAB2_LIB.BASEBOARD_FAB2(SCH_1):M_M_ECC<3>
   56  M_M_ECC<2>     CB<2>  @BASEBOARD_FAB2_LIB.BASEBOARD_FAB2(SCH_1):M_M_ECC<2>
  194  M_M_ECC<1>     CB<1>  @BASEBOARD_FAB2_LIB.BASEBOARD_FAB2(SCH_1):M_M_ECC<1>
   49  M_M_ECC<0>     CB<0>  @BASEBOARD_FAB2_LIB.BASEBOARD_FAB2(SCH_1):M_M_ECC<0>
  161  M_M_DQ<9>      DQ<9>  @BASEBOARD_FAB2_LIB.BASEBOARD_FAB2(SCH_1):M_M_DQ<9>
   16  M_M_DQ<8>      DQ<8>  @BASEBOARD_FAB2_LIB.BASEBOARD_FAB2(SCH_1):M_M_DQ<8>
  155  M_M_DQ<7>      DQ<7>  @BASEBOARD_FAB2_LIB.BASEBOARD_FAB2(SCH_1):M_M_DQ<7>
   10  M_M_DQ<6>      DQ<6>  @BASEBOARD_FAB2_LIB.BASEBOARD_FAB2(SCH_1):M_M_DQ<6>
  280  M_M_DQ<63>     DQ<63>  @BASEBOARD_FAB2_LIB.BASEBOARD_FAB2(SCH_1):M_M_DQ<63>
  135  M_M_DQ<62>     DQ<62>  @BASEBOARD_FAB2_LIB.BASEBOARD_FAB2(SCH_1):M_M_DQ<62>
  273  M_M_DQ<61>     DQ<61>  @BASEBOARD_FAB2_LIB.BASEBOARD_FAB2(SCH_1):M_M_DQ<61>
  128  M_M_DQ<60>     DQ<60>  @BASEBOARD_FAB2_LIB.BASEBOARD_FAB2(SCH_1):M_M_DQ<60>
  148  M_M_DQ<5>      DQ<5>  @BASEBOARD_FAB2_LIB.BASEBOARD_FAB2(SCH_1):M_M_DQ<5>
  282  M_M_DQ<59>     DQ<59>  @BASEBOARD_FAB2_LIB.BASEBOARD_FAB2(SCH_1):M_M_DQ<59>
  137  M_M_DQ<58>     DQ<58>  @BASEBOARD_FAB2_LIB.BASEBOARD_FAB2(SCH_1):M_M_DQ<58>
  275  M_M_DQ<57>     DQ<57>  @BASEBOARD_FAB2_LIB.BASEBOARD_FAB2(SCH_1):M_M_DQ<57>
  130  M_M_DQ<56>     DQ<56>  @BASEBOARD_FAB2_LIB.BASEBOARD_FAB2(SCH_1):M_M_DQ<56>
  269  M_M_DQ<55>     DQ<55>  @BASEBOARD_FAB2_LIB.BASEBOARD_FAB2(SCH_1):M_M_DQ<55>
  124  M_M_DQ<54>     DQ<54>  @BASEBOARD_FAB2_LIB.BASEBOARD_FAB2(SCH_1):M_M_DQ<54>
  262  M_M_DQ<53>     DQ<53>  @BASEBOARD_FAB2_LIB.BASEBOARD_FAB2(SCH_1):M_M_DQ<53>
  117  M_M_DQ<52>     DQ<52>  @BASEBOARD_FAB2_LIB.BASEBOARD_FAB2(SCH_1):M_M_DQ<52>
  271  M_M_DQ<51>     DQ<51>  @BASEBOARD_FAB2_LIB.BASEBOARD_FAB2(SCH_1):M_M_DQ<51>
  126  M_M_DQ<50>     DQ<50>  @BASEBOARD_FAB2_LIB.BASEBOARD_FAB2(SCH_1):M_M_DQ<50>
    3  M_M_DQ<4>      DQ<4>  @BASEBOARD_FAB2_LIB.BASEBOARD_FAB2(SCH_1):M_M_DQ<4>
  264  M_M_DQ<49>     DQ<49>  @BASEBOARD_FAB2_LIB.BASEBOARD_FAB2(SCH_1):M_M_DQ<49>
  119  M_M_DQ<48>     DQ<48>  @BASEBOARD_FAB2_LIB.BASEBOARD_FAB2(SCH_1):M_M_DQ<48>
  258  M_M_DQ<47>     DQ<47>  @BASEBOARD_FAB2_LIB.BASEBOARD_FAB2(SCH_1):M_M_DQ<47>
  113  M_M_DQ<46>     DQ<46>  @BASEBOARD_FAB2_LIB.BASEBOARD_FAB2(SCH_1):M_M_DQ<46>
  251  M_M_DQ<45>     DQ<45>  @BASEBOARD_FAB2_LIB.BASEBOARD_FAB2(SCH_1):M_M_DQ<45>
  106  M_M_DQ<44>     DQ<44>  @BASEBOARD_FAB2_LIB.BASEBOARD_FAB2(SCH_1):M_M_DQ<44>
  260  M_M_DQ<43>     DQ<43>  @BASEBOARD_FAB2_LIB.BASEBOARD_FAB2(SCH_1):M_M_DQ<43>
  115  M_M_DQ<42>     DQ<42>  @BASEBOARD_FAB2_LIB.BASEBOARD_FAB2(SCH_1):M_M_DQ<42>
  253  M_M_DQ<41>     DQ<41>  @BASEBOARD_FAB2_LIB.BASEBOARD_FAB2(SCH_1):M_M_DQ<41>
  108  M_M_DQ<40>     DQ<40>  @BASEBOARD_FAB2_LIB.BASEBOARD_FAB2(SCH_1):M_M_DQ<40>
  157  M_M_DQ<3>      DQ<3>  @BASEBOARD_FAB2_LIB.BASEBOARD_FAB2(SCH_1):M_M_DQ<3>
  247  M_M_DQ<39>     DQ<39>  @BASEBOARD_FAB2_LIB.BASEBOARD_FAB2(SCH_1):M_M_DQ<39>
  102  M_M_DQ<38>     DQ<38>  @BASEBOARD_FAB2_LIB.BASEBOARD_FAB2(SCH_1):M_M_DQ<38>
  240  M_M_DQ<37>     DQ<37>  @BASEBOARD_FAB2_LIB.BASEBOARD_FAB2(SCH_1):M_M_DQ<37>
   95  M_M_DQ<36>     DQ<36>  @BASEBOARD_FAB2_LIB.BASEBOARD_FAB2(SCH_1):M_M_DQ<36>
  249  M_M_DQ<35>     DQ<35>  @BASEBOARD_FAB2_LIB.BASEBOARD_FAB2(SCH_1):M_M_DQ<35>
  104  M_M_DQ<34>     DQ<34>  @BASEBOARD_FAB2_LIB.BASEBOARD_FAB2(SCH_1):M_M_DQ<34>
  242  M_M_DQ<33>     DQ<33>  @BASEBOARD_FAB2_LIB.BASEBOARD_FAB2(SCH_1):M_M_DQ<33>
   97  M_M_DQ<32>     DQ<32>  @BASEBOARD_FAB2_LIB.BASEBOARD_FAB2(SCH_1):M_M_DQ<32>
  188  M_M_DQ<31>     DQ<31>  @BASEBOARD_FAB2_LIB.BASEBOARD_FAB2(SCH_1):M_M_DQ<31>
   43  M_M_DQ<30>     DQ<30>  @BASEBOARD_FAB2_LIB.BASEBOARD_FAB2(SCH_1):M_M_DQ<30>
   12  M_M_DQ<2>      DQ<2>  @BASEBOARD_FAB2_LIB.BASEBOARD_FAB2(SCH_1):M_M_DQ<2>
  181  M_M_DQ<29>     DQ<29>  @BASEBOARD_FAB2_LIB.BASEBOARD_FAB2(SCH_1):M_M_DQ<29>
   36  M_M_DQ<28>     DQ<28>  @BASEBOARD_FAB2_LIB.BASEBOARD_FAB2(SCH_1):M_M_DQ<28>
  190  M_M_DQ<27>     DQ<27>  @BASEBOARD_FAB2_LIB.BASEBOARD_FAB2(SCH_1):M_M_DQ<27>
   45  M_M_DQ<26>     DQ<26>  @BASEBOARD_FAB2_LIB.BASEBOARD_FAB2(SCH_1):M_M_DQ<26>
  183  M_M_DQ<25>     DQ<25>  @BASEBOARD_FAB2_LIB.BASEBOARD_FAB2(SCH_1):M_M_DQ<25>
   38  M_M_DQ<24>     DQ<24>  @BASEBOARD_FAB2_LIB.BASEBOARD_FAB2(SCH_1):M_M_DQ<24>
  177  M_M_DQ<23>     DQ<23>  @BASEBOARD_FAB2_LIB.BASEBOARD_FAB2(SCH_1):M_M_DQ<23>
   32  M_M_DQ<22>     DQ<22>  @BASEBOARD_FAB2_LIB.BASEBOARD_FAB2(SCH_1):M_M_DQ<22>
  170  M_M_DQ<21>     DQ<21>  @BASEBOARD_FAB2_LIB.BASEBOARD_FAB2(SCH_1):M_M_DQ<21>
   25  M_M_DQ<20>     DQ<20>  @BASEBOARD_FAB2_LIB.BASEBOARD_FAB2(SCH_1):M_M_DQ<20>
  150  M_M_DQ<1>      DQ<1>  @BASEBOARD_FAB2_LIB.BASEBOARD_FAB2(SCH_1):M_M_DQ<1>
  179  M_M_DQ<19>     DQ<19>  @BASEBOARD_FAB2_LIB.BASEBOARD_FAB2(SCH_1):M_M_DQ<19>
   34  M_M_DQ<18>     DQ<18>  @BASEBOARD_FAB2_LIB.BASEBOARD_FAB2(SCH_1):M_M_DQ<18>
  172  M_M_DQ<17>     DQ<17>  @BASEBOARD_FAB2_LIB.BASEBOARD_FAB2(SCH_1):M_M_DQ<17>
   27  M_M_DQ<16>     DQ<16>  @BASEBOARD_FAB2_LIB.BASEBOARD_FAB2(SCH_1):M_M_DQ<16>
  166  M_M_DQ<15>     DQ<15>  @BASEBOARD_FAB2_LIB.BASEBOARD_FAB2(SCH_1):M_M_DQ<15>
   21  M_M_DQ<14>     DQ<14>  @BASEBOARD_FAB2_LIB.BASEBOARD_FAB2(SCH_1):M_M_DQ<14>
  159  M_M_DQ<13>     DQ<13>  @BASEBOARD_FAB2_LIB.BASEBOARD_FAB2(SCH_1):M_M_DQ<13>
   14  M_M_DQ<12>     DQ<12>  @BASEBOARD_FAB2_LIB.BASEBOARD_FAB2(SCH_1):M_M_DQ<12>
  168  M_M_DQ<11>     DQ<11>  @BASEBOARD_FAB2_LIB.BASEBOARD_FAB2(SCH_1):M_M_DQ<11>
   23  M_M_DQ<10>     DQ<10>  @BASEBOARD_FAB2_LIB.BASEBOARD_FAB2(SCH_1):M_M_DQ<10>
    5  M_M_DQ<0>      DQ<0>  @BASEBOARD_FAB2_LIB.BASEBOARD_FAB2(SCH_1):M_M_DQ<0>
  237  M_M_CS_N<7>    S3_N_C<1>  @BASEBOARD_FAB2_LIB.BASEBOARD_FAB2(SCH_1):M_M_CS_N<7>
   93  M_M_CS_N<6>    S2_N_C<0>  @BASEBOARD_FAB2_LIB.BASEBOARD_FAB2(SCH_1):M_M_CS_N<6>
   89  M_M_CS_N<5>     S1_N  @BASEBOARD_FAB2_LIB.BASEBOARD_FAB2(SCH_1):M_M_CS_N<5>
   84  M_M_CS_N<4>     S0_N  @BASEBOARD_FAB2_LIB.BASEBOARD_FAB2(SCH_1):M_M_CS_N<4>
  218  M_M_CLK_DP<3>   CK1P  @BASEBOARD_FAB2_LIB.BASEBOARD_FAB2(SCH_1):M_M_CLK_DP<3>
   74  M_M_CLK_DP<2>   CK0P  @BASEBOARD_FAB2_LIB.BASEBOARD_FAB2(SCH_1):M_M_CLK_DP<2>
  219  M_M_CLK_DN<3>   CK1N  @BASEBOARD_FAB2_LIB.BASEBOARD_FAB2(SCH_1):M_M_CLK_DN<3>
   75  M_M_CLK_DN<2>   CK0N  @BASEBOARD_FAB2_LIB.BASEBOARD_FAB2(SCH_1):M_M_CLK_DN<2>
  203  M_M_CKE<3>     CKE<1>  @BASEBOARD_FAB2_LIB.BASEBOARD_FAB2(SCH_1):M_M_CKE<3>
   60  M_M_CKE<2>     CKE<0>  @BASEBOARD_FAB2_LIB.BASEBOARD_FAB2(SCH_1):M_M_CKE<2>
  235  M_M_C<2>        C<2>  @BASEBOARD_FAB2_LIB.BASEBOARD_FAB2(SCH_1):M_M_C<2>
  207  M_M_BG<1>      BG<1>  @BASEBOARD_FAB2_LIB.BASEBOARD_FAB2(SCH_1):M_M_BG<1>
   63  M_M_BG<0>      BG<0>  @BASEBOARD_FAB2_LIB.BASEBOARD_FAB2(SCH_1):M_M_BG<0>
  224  M_M_BA<1>      BA<1>  @BASEBOARD_FAB2_LIB.BASEBOARD_FAB2(SCH_1):M_M_BA<1>
   81  M_M_BA<0>      BA<0>  @BASEBOARD_FAB2_LIB.BASEBOARD_FAB2(SCH_1):M_M_BA<0>
  208  M_M_ALERT_N    ALERT_N  @BASEBOARD_FAB2_LIB.BASEBOARD_FAB2(SCH_1):M_M_ALERT_N
   62  M_M_ACT_N      ACT_N  @BASEBOARD_FAB2_LIB.BASEBOARD_FAB2(SCH_1):M_M_ACT_N
   58  M_KLM_RST_N    RESET_N  @BASEBOARD_FAB2_LIB.BASEBOARD_FAB2(SCH_1):M_KLM_RST_N
  140  GND            SA<1>  @BASEBOARD_FAB2_LIB.BASEBOARD_FAB2(SCH_1):GND
   78  FM_DIMM_EVENT_COD_N  EVENT_N  @BASEBOARD_FAB2_LIB.BASEBOARD_FAB2(SCH_1):FM_DIMM_EVENT_COD_N
  230  FM_ADR_COMPLETE_KLM_N  SAVE_N_NC  @BASEBOARD_FAB2_LIB.BASEBOARD_FAB2(SCH_1):FM_ADR_COMPLETE_KLM_N

SCONN288_H44441003_PIP  I55  J9L2   [SCONN288_H44441003_PIP-SCONN,HA]
   77  PVTT_KLM       VTT<1>  @BASEBOARD_FAB2_LIB.BASEBOARD_FAB2(SCH_1):PVTT_KLM
  221  PVTT_KLM       VTT<0>  @BASEBOARD_FAB2_LIB.BASEBOARD_FAB2(SCH_1):PVTT_KLM
  142  PVPP_KLM       VPP<4>  @BASEBOARD_FAB2_LIB.BASEBOARD_FAB2(SCH_1):PVPP_KLM
  143  PVPP_KLM       VPP<3>  @BASEBOARD_FAB2_LIB.BASEBOARD_FAB2(SCH_1):PVPP_KLM
  288  PVPP_KLM       VPP<2>  @BASEBOARD_FAB2_LIB.BASEBOARD_FAB2(SCH_1):PVPP_KLM
  286  PVPP_KLM       VPP<1>  @BASEBOARD_FAB2_LIB.BASEBOARD_FAB2(SCH_1):PVPP_KLM
  287  PVPP_KLM       VPP<0>  @BASEBOARD_FAB2_LIB.BASEBOARD_FAB2(SCH_1):PVPP_KLM
   59  PVDDQ_KLM      VDD<25>  @BASEBOARD_FAB2_LIB.BASEBOARD_FAB2(SCH_1):PVDDQ_KLM
   61  PVDDQ_KLM      VDD<24>  @BASEBOARD_FAB2_LIB.BASEBOARD_FAB2(SCH_1):PVDDQ_KLM
   64  PVDDQ_KLM      VDD<23>  @BASEBOARD_FAB2_LIB.BASEBOARD_FAB2(SCH_1):PVDDQ_KLM
   67  PVDDQ_KLM      VDD<22>  @BASEBOARD_FAB2_LIB.BASEBOARD_FAB2(SCH_1):PVDDQ_KLM
   70  PVDDQ_KLM      VDD<21>  @BASEBOARD_FAB2_LIB.BASEBOARD_FAB2(SCH_1):PVDDQ_KLM
   73  PVDDQ_KLM      VDD<20>  @BASEBOARD_FAB2_LIB.BASEBOARD_FAB2(SCH_1):PVDDQ_KLM
   76  PVDDQ_KLM      VDD<19>  @BASEBOARD_FAB2_LIB.BASEBOARD_FAB2(SCH_1):PVDDQ_KLM
   80  PVDDQ_KLM      VDD<18>  @BASEBOARD_FAB2_LIB.BASEBOARD_FAB2(SCH_1):PVDDQ_KLM
   83  PVDDQ_KLM      VDD<17>  @BASEBOARD_FAB2_LIB.BASEBOARD_FAB2(SCH_1):PVDDQ_KLM
   85  PVDDQ_KLM      VDD<16>  @BASEBOARD_FAB2_LIB.BASEBOARD_FAB2(SCH_1):PVDDQ_KLM
   88  PVDDQ_KLM      VDD<15>  @BASEBOARD_FAB2_LIB.BASEBOARD_FAB2(SCH_1):PVDDQ_KLM
   90  PVDDQ_KLM      VDD<14>  @BASEBOARD_FAB2_LIB.BASEBOARD_FAB2(SCH_1):PVDDQ_KLM
   92  PVDDQ_KLM      VDD<13>  @BASEBOARD_FAB2_LIB.BASEBOARD_FAB2(SCH_1):PVDDQ_KLM
  204  PVDDQ_KLM      VDD<12>  @BASEBOARD_FAB2_LIB.BASEBOARD_FAB2(SCH_1):PVDDQ_KLM
  206  PVDDQ_KLM      VDD<11>  @BASEBOARD_FAB2_LIB.BASEBOARD_FAB2(SCH_1):PVDDQ_KLM
  209  PVDDQ_KLM      VDD<10>  @BASEBOARD_FAB2_LIB.BASEBOARD_FAB2(SCH_1):PVDDQ_KLM
  212  PVDDQ_KLM      VDD<9>  @BASEBOARD_FAB2_LIB.BASEBOARD_FAB2(SCH_1):PVDDQ_KLM
  215  PVDDQ_KLM      VDD<8>  @BASEBOARD_FAB2_LIB.BASEBOARD_FAB2(SCH_1):PVDDQ_KLM
  217  PVDDQ_KLM      VDD<7>  @BASEBOARD_FAB2_LIB.BASEBOARD_FAB2(SCH_1):PVDDQ_KLM
  220  PVDDQ_KLM      VDD<6>  @BASEBOARD_FAB2_LIB.BASEBOARD_FAB2(SCH_1):PVDDQ_KLM
  223  PVDDQ_KLM      VDD<5>  @BASEBOARD_FAB2_LIB.BASEBOARD_FAB2(SCH_1):PVDDQ_KLM
  226  PVDDQ_KLM      VDD<4>  @BASEBOARD_FAB2_LIB.BASEBOARD_FAB2(SCH_1):PVDDQ_KLM
  229  PVDDQ_KLM      VDD<3>  @BASEBOARD_FAB2_LIB.BASEBOARD_FAB2(SCH_1):PVDDQ_KLM
  231  PVDDQ_KLM      VDD<2>  @BASEBOARD_FAB2_LIB.BASEBOARD_FAB2(SCH_1):PVDDQ_KLM
  233  PVDDQ_KLM      VDD<1>  @BASEBOARD_FAB2_LIB.BASEBOARD_FAB2(SCH_1):PVDDQ_KLM
  236  PVDDQ_KLM      VDD<0>  @BASEBOARD_FAB2_LIB.BASEBOARD_FAB2(SCH_1):PVDDQ_KLM
    1  P12V_NVDIMM_KLM  12V<1>  @BASEBOARD_FAB2_LIB.BASEBOARD_FAB2(SCH_1):P12V_NVDIMM_KLM
  145  P12V_NVDIMM_KLM  12V<0>  @BASEBOARD_FAB2_LIB.BASEBOARD_FAB2(SCH_1):P12V_NVDIMM_KLM

SCONN288_H44441003_PIP  I138  J9L2   [SCONN288_H44441003_PIP-SCONN,HA]
    2  GND            VSS<93>  @BASEBOARD_FAB2_LIB.BASEBOARD_FAB2(SCH_1):GND
    4  GND            VSS<92>  @BASEBOARD_FAB2_LIB.BASEBOARD_FAB2(SCH_1):GND
    6  GND            VSS<91>  @BASEBOARD_FAB2_LIB.BASEBOARD_FAB2(SCH_1):GND
    9  GND            VSS<90>  @BASEBOARD_FAB2_LIB.BASEBOARD_FAB2(SCH_1):GND
   11  GND            VSS<89>  @BASEBOARD_FAB2_LIB.BASEBOARD_FAB2(SCH_1):GND
   13  GND            VSS<88>  @BASEBOARD_FAB2_LIB.BASEBOARD_FAB2(SCH_1):GND
   15  GND            VSS<87>  @BASEBOARD_FAB2_LIB.BASEBOARD_FAB2(SCH_1):GND
   17  GND            VSS<86>  @BASEBOARD_FAB2_LIB.BASEBOARD_FAB2(SCH_1):GND
   20  GND            VSS<85>  @BASEBOARD_FAB2_LIB.BASEBOARD_FAB2(SCH_1):GND
   22  GND            VSS<84>  @BASEBOARD_FAB2_LIB.BASEBOARD_FAB2(SCH_1):GND
   24  GND            VSS<83>  @BASEBOARD_FAB2_LIB.BASEBOARD_FAB2(SCH_1):GND
   26  GND            VSS<82>  @BASEBOARD_FAB2_LIB.BASEBOARD_FAB2(SCH_1):GND
   28  GND            VSS<81>  @BASEBOARD_FAB2_LIB.BASEBOARD_FAB2(SCH_1):GND
   31  GND            VSS<80>  @BASEBOARD_FAB2_LIB.BASEBOARD_FAB2(SCH_1):GND
   33  GND            VSS<79>  @BASEBOARD_FAB2_LIB.BASEBOARD_FAB2(SCH_1):GND
   35  GND            VSS<78>  @BASEBOARD_FAB2_LIB.BASEBOARD_FAB2(SCH_1):GND
   37  GND            VSS<77>  @BASEBOARD_FAB2_LIB.BASEBOARD_FAB2(SCH_1):GND
   39  GND            VSS<76>  @BASEBOARD_FAB2_LIB.BASEBOARD_FAB2(SCH_1):GND
   42  GND            VSS<75>  @BASEBOARD_FAB2_LIB.BASEBOARD_FAB2(SCH_1):GND
   44  GND            VSS<74>  @BASEBOARD_FAB2_LIB.BASEBOARD_FAB2(SCH_1):GND
   46  GND            VSS<73>  @BASEBOARD_FAB2_LIB.BASEBOARD_FAB2(SCH_1):GND
   48  GND            VSS<72>  @BASEBOARD_FAB2_LIB.BASEBOARD_FAB2(SCH_1):GND
   50  GND            VSS<71>  @BASEBOARD_FAB2_LIB.BASEBOARD_FAB2(SCH_1):GND
   53  GND            VSS<70>  @BASEBOARD_FAB2_LIB.BASEBOARD_FAB2(SCH_1):GND
   55  GND            VSS<69>  @BASEBOARD_FAB2_LIB.BASEBOARD_FAB2(SCH_1):GND
   57  GND            VSS<68>  @BASEBOARD_FAB2_LIB.BASEBOARD_FAB2(SCH_1):GND
   94  GND            VSS<67>  @BASEBOARD_FAB2_LIB.BASEBOARD_FAB2(SCH_1):GND
   96  GND            VSS<66>  @BASEBOARD_FAB2_LIB.BASEBOARD_FAB2(SCH_1):GND
   98  GND            VSS<65>  @BASEBOARD_FAB2_LIB.BASEBOARD_FAB2(SCH_1):GND
  101  GND            VSS<64>  @BASEBOARD_FAB2_LIB.BASEBOARD_FAB2(SCH_1):GND
  103  GND            VSS<63>  @BASEBOARD_FAB2_LIB.BASEBOARD_FAB2(SCH_1):GND
  105  GND            VSS<62>  @BASEBOARD_FAB2_LIB.BASEBOARD_FAB2(SCH_1):GND
  107  GND            VSS<61>  @BASEBOARD_FAB2_LIB.BASEBOARD_FAB2(SCH_1):GND
  109  GND            VSS<60>  @BASEBOARD_FAB2_LIB.BASEBOARD_FAB2(SCH_1):GND
  112  GND            VSS<59>  @BASEBOARD_FAB2_LIB.BASEBOARD_FAB2(SCH_1):GND
  114  GND            VSS<58>  @BASEBOARD_FAB2_LIB.BASEBOARD_FAB2(SCH_1):GND
  116  GND            VSS<57>  @BASEBOARD_FAB2_LIB.BASEBOARD_FAB2(SCH_1):GND
  118  GND            VSS<56>  @BASEBOARD_FAB2_LIB.BASEBOARD_FAB2(SCH_1):GND
  120  GND            VSS<55>  @BASEBOARD_FAB2_LIB.BASEBOARD_FAB2(SCH_1):GND
  123  GND            VSS<54>  @BASEBOARD_FAB2_LIB.BASEBOARD_FAB2(SCH_1):GND
  125  GND            VSS<53>  @BASEBOARD_FAB2_LIB.BASEBOARD_FAB2(SCH_1):GND
  127  GND            VSS<52>  @BASEBOARD_FAB2_LIB.BASEBOARD_FAB2(SCH_1):GND
  129  GND            VSS<51>  @BASEBOARD_FAB2_LIB.BASEBOARD_FAB2(SCH_1):GND
  131  GND            VSS<50>  @BASEBOARD_FAB2_LIB.BASEBOARD_FAB2(SCH_1):GND
  134  GND            VSS<49>  @BASEBOARD_FAB2_LIB.BASEBOARD_FAB2(SCH_1):GND
  136  GND            VSS<48>  @BASEBOARD_FAB2_LIB.BASEBOARD_FAB2(SCH_1):GND
  138  GND            VSS<47>  @BASEBOARD_FAB2_LIB.BASEBOARD_FAB2(SCH_1):GND
  147  GND            VSS<46>  @BASEBOARD_FAB2_LIB.BASEBOARD_FAB2(SCH_1):GND
  149  GND            VSS<45>  @BASEBOARD_FAB2_LIB.BASEBOARD_FAB2(SCH_1):GND
  151  GND            VSS<44>  @BASEBOARD_FAB2_LIB.BASEBOARD_FAB2(SCH_1):GND
  154  GND            VSS<43>  @BASEBOARD_FAB2_LIB.BASEBOARD_FAB2(SCH_1):GND
  156  GND            VSS<42>  @BASEBOARD_FAB2_LIB.BASEBOARD_FAB2(SCH_1):GND
  158  GND            VSS<41>  @BASEBOARD_FAB2_LIB.BASEBOARD_FAB2(SCH_1):GND
  160  GND            VSS<40>  @BASEBOARD_FAB2_LIB.BASEBOARD_FAB2(SCH_1):GND
  162  GND            VSS<39>  @BASEBOARD_FAB2_LIB.BASEBOARD_FAB2(SCH_1):GND
  165  GND            VSS<38>  @BASEBOARD_FAB2_LIB.BASEBOARD_FAB2(SCH_1):GND
  167  GND            VSS<37>  @BASEBOARD_FAB2_LIB.BASEBOARD_FAB2(SCH_1):GND
  169  GND            VSS<36>  @BASEBOARD_FAB2_LIB.BASEBOARD_FAB2(SCH_1):GND
  171  GND            VSS<35>  @BASEBOARD_FAB2_LIB.BASEBOARD_FAB2(SCH_1):GND
  173  GND            VSS<34>  @BASEBOARD_FAB2_LIB.BASEBOARD_FAB2(SCH_1):GND
  176  GND            VSS<33>  @BASEBOARD_FAB2_LIB.BASEBOARD_FAB2(SCH_1):GND
  178  GND            VSS<32>  @BASEBOARD_FAB2_LIB.BASEBOARD_FAB2(SCH_1):GND
  180  GND            VSS<31>  @BASEBOARD_FAB2_LIB.BASEBOARD_FAB2(SCH_1):GND
  182  GND            VSS<30>  @BASEBOARD_FAB2_LIB.BASEBOARD_FAB2(SCH_1):GND
  184  GND            VSS<29>  @BASEBOARD_FAB2_LIB.BASEBOARD_FAB2(SCH_1):GND
  187  GND            VSS<28>  @BASEBOARD_FAB2_LIB.BASEBOARD_FAB2(SCH_1):GND
  189  GND            VSS<27>  @BASEBOARD_FAB2_LIB.BASEBOARD_FAB2(SCH_1):GND
  191  GND            VSS<26>  @BASEBOARD_FAB2_LIB.BASEBOARD_FAB2(SCH_1):GND
  193  GND            VSS<25>  @BASEBOARD_FAB2_LIB.BASEBOARD_FAB2(SCH_1):GND
  195  GND            VSS<24>  @BASEBOARD_FAB2_LIB.BASEBOARD_FAB2(SCH_1):GND
  198  GND            VSS<23>  @BASEBOARD_FAB2_LIB.BASEBOARD_FAB2(SCH_1):GND
  200  GND            VSS<22>  @BASEBOARD_FAB2_LIB.BASEBOARD_FAB2(SCH_1):GND
  202  GND            VSS<21>  @BASEBOARD_FAB2_LIB.BASEBOARD_FAB2(SCH_1):GND
  239  GND            VSS<20>  @BASEBOARD_FAB2_LIB.BASEBOARD_FAB2(SCH_1):GND
  241  GND            VSS<19>  @BASEBOARD_FAB2_LIB.BASEBOARD_FAB2(SCH_1):GND
  243  GND            VSS<18>  @BASEBOARD_FAB2_LIB.BASEBOARD_FAB2(SCH_1):GND
  246  GND            VSS<17>  @BASEBOARD_FAB2_LIB.BASEBOARD_FAB2(SCH_1):GND
  248  GND            VSS<16>  @BASEBOARD_FAB2_LIB.BASEBOARD_FAB2(SCH_1):GND
  250  GND            VSS<15>  @BASEBOARD_FAB2_LIB.BASEBOARD_FAB2(SCH_1):GND
  252  GND            VSS<14>  @BASEBOARD_FAB2_LIB.BASEBOARD_FAB2(SCH_1):GND
  254  GND            VSS<13>  @BASEBOARD_FAB2_LIB.BASEBOARD_FAB2(SCH_1):GND
  257  GND            VSS<12>  @BASEBOARD_FAB2_LIB.BASEBOARD_FAB2(SCH_1):GND
  259  GND            VSS<11>  @BASEBOARD_FAB2_LIB.BASEBOARD_FAB2(SCH_1):GND
  261  GND            VSS<10>  @BASEBOARD_FAB2_LIB.BASEBOARD_FAB2(SCH_1):GND
  263  GND            VSS<9>  @BASEBOARD_FAB2_LIB.BASEBOARD_FAB2(SCH_1):GND
  265  GND            VSS<8>  @BASEBOARD_FAB2_LIB.BASEBOARD_FAB2(SCH_1):GND
  268  GND            VSS<7>  @BASEBOARD_FAB2_LIB.BASEBOARD_FAB2(SCH_1):GND
  270  GND            VSS<6>  @BASEBOARD_FAB2_LIB.BASEBOARD_FAB2(SCH_1):GND
  272  GND            VSS<5>  @BASEBOARD_FAB2_LIB.BASEBOARD_FAB2(SCH_1):GND
  274  GND            VSS<4>  @BASEBOARD_FAB2_LIB.BASEBOARD_FAB2(SCH_1):GND
  276  GND            VSS<3>  @BASEBOARD_FAB2_LIB.BASEBOARD_FAB2(SCH_1):GND
  279  GND            VSS<2>  @BASEBOARD_FAB2_LIB.BASEBOARD_FAB2(SCH_1):GND
  281  GND            VSS<1>  @BASEBOARD_FAB2_LIB.BASEBOARD_FAB2(SCH_1):GND
  283  GND            VSS<0>  @BASEBOARD_FAB2_LIB.BASEBOARD_FAB2(SCH_1):GND

SCONN288_H44441003_PIP  I100  J9L2   [SCONN288_H44441003_PIP-SCONN,HA]
    7  M_L_DQS_DP<9>  DQS9P  @BASEBOARD_FAB2_LIB.BASEBOARD_FAB2(SCH_1):M_L_DQS_DP<9>
  197  M_L_DQS_DP<8>  DQS8P  @BASEBOARD_FAB2_LIB.BASEBOARD_FAB2(SCH_1):M_L_DQS_DP<8>
  278  M_L_DQS_DP<7>  DQS7P  @BASEBOARD_FAB2_LIB.BASEBOARD_FAB2(SCH_1):M_L_DQS_DP<7>
  267  M_L_DQS_DP<6>  DQS6P  @BASEBOARD_FAB2_LIB.BASEBOARD_FAB2(SCH_1):M_L_DQS_DP<6>
  256  M_L_DQS_DP<5>  DQS5P  @BASEBOARD_FAB2_LIB.BASEBOARD_FAB2(SCH_1):M_L_DQS_DP<5>
  245  M_L_DQS_DP<4>  DQS4P  @BASEBOARD_FAB2_LIB.BASEBOARD_FAB2(SCH_1):M_L_DQS_DP<4>
  186  M_L_DQS_DP<3>  DQS3P  @BASEBOARD_FAB2_LIB.BASEBOARD_FAB2(SCH_1):M_L_DQS_DP<3>
  175  M_L_DQS_DP<2>  DQS2P  @BASEBOARD_FAB2_LIB.BASEBOARD_FAB2(SCH_1):M_L_DQS_DP<2>
  164  M_L_DQS_DP<1>  DQS1P  @BASEBOARD_FAB2_LIB.BASEBOARD_FAB2(SCH_1):M_L_DQS_DP<1>
   51  M_L_DQS_DP<17>  DQS17P  @BASEBOARD_FAB2_LIB.BASEBOARD_FAB2(SCH_1):M_L_DQS_DP<17>
  132  M_L_DQS_DP<16>  DQS16P  @BASEBOARD_FAB2_LIB.BASEBOARD_FAB2(SCH_1):M_L_DQS_DP<16>
  121  M_L_DQS_DP<15>  DQS15P  @BASEBOARD_FAB2_LIB.BASEBOARD_FAB2(SCH_1):M_L_DQS_DP<15>
  110  M_L_DQS_DP<14>  DQS14P  @BASEBOARD_FAB2_LIB.BASEBOARD_FAB2(SCH_1):M_L_DQS_DP<14>
   99  M_L_DQS_DP<13>  DQS13P  @BASEBOARD_FAB2_LIB.BASEBOARD_FAB2(SCH_1):M_L_DQS_DP<13>
   40  M_L_DQS_DP<12>  DQS12P  @BASEBOARD_FAB2_LIB.BASEBOARD_FAB2(SCH_1):M_L_DQS_DP<12>
   29  M_L_DQS_DP<11>  DQS11P  @BASEBOARD_FAB2_LIB.BASEBOARD_FAB2(SCH_1):M_L_DQS_DP<11>
   18  M_L_DQS_DP<10>  DQS10P  @BASEBOARD_FAB2_LIB.BASEBOARD_FAB2(SCH_1):M_L_DQS_DP<10>
  153  M_L_DQS_DP<0>  DQS0P  @BASEBOARD_FAB2_LIB.BASEBOARD_FAB2(SCH_1):M_L_DQS_DP<0>
    8  M_L_DQS_DN<9>  DQS9N  @BASEBOARD_FAB2_LIB.BASEBOARD_FAB2(SCH_1):M_L_DQS_DN<9>
  196  M_L_DQS_DN<8>  DQS8N  @BASEBOARD_FAB2_LIB.BASEBOARD_FAB2(SCH_1):M_L_DQS_DN<8>
  277  M_L_DQS_DN<7>  DQS7N  @BASEBOARD_FAB2_LIB.BASEBOARD_FAB2(SCH_1):M_L_DQS_DN<7>
  266  M_L_DQS_DN<6>  DQS6N  @BASEBOARD_FAB2_LIB.BASEBOARD_FAB2(SCH_1):M_L_DQS_DN<6>
  255  M_L_DQS_DN<5>  DQS5N  @BASEBOARD_FAB2_LIB.BASEBOARD_FAB2(SCH_1):M_L_DQS_DN<5>
  244  M_L_DQS_DN<4>  DQS4N  @BASEBOARD_FAB2_LIB.BASEBOARD_FAB2(SCH_1):M_L_DQS_DN<4>
  185  M_L_DQS_DN<3>  DQS3N  @BASEBOARD_FAB2_LIB.BASEBOARD_FAB2(SCH_1):M_L_DQS_DN<3>
  174  M_L_DQS_DN<2>  DQS2N  @BASEBOARD_FAB2_LIB.BASEBOARD_FAB2(SCH_1):M_L_DQS_DN<2>
  163  M_L_DQS_DN<1>  DQS1N  @BASEBOARD_FAB2_LIB.BASEBOARD_FAB2(SCH_1):M_L_DQS_DN<1>
   52  M_L_DQS_DN<17>  DQS17N  @BASEBOARD_FAB2_LIB.BASEBOARD_FAB2(SCH_1):M_L_DQS_DN<17>
  133  M_L_DQS_DN<16>  DQS16N  @BASEBOARD_FAB2_LIB.BASEBOARD_FAB2(SCH_1):M_L_DQS_DN<16>
  122  M_L_DQS_DN<15>  DQS15N  @BASEBOARD_FAB2_LIB.BASEBOARD_FAB2(SCH_1):M_L_DQS_DN<15>
  111  M_L_DQS_DN<14>  DQS14N  @BASEBOARD_FAB2_LIB.BASEBOARD_FAB2(SCH_1):M_L_DQS_DN<14>
  100  M_L_DQS_DN<13>  DQS13N  @BASEBOARD_FAB2_LIB.BASEBOARD_FAB2(SCH_1):M_L_DQS_DN<13>
   41  M_L_DQS_DN<12>  DQS12N  @BASEBOARD_FAB2_LIB.BASEBOARD_FAB2(SCH_1):M_L_DQS_DN<12>
   30  M_L_DQS_DN<11>  DQS11N  @BASEBOARD_FAB2_LIB.BASEBOARD_FAB2(SCH_1):M_L_DQS_DN<11>
   19  M_L_DQS_DN<10>  DQS10N  @BASEBOARD_FAB2_LIB.BASEBOARD_FAB2(SCH_1):M_L_DQS_DN<10>
  152  M_L_DQS_DN<0>  DQS0N  @BASEBOARD_FAB2_LIB.BASEBOARD_FAB2(SCH_1):M_L_DQS_DN<0>

SCONN288_H44441003_PIP  I12  J9L2   [SCONN288_H44441003_PIP-SCONN,HA]
  144  TP_CH_L_DIMM0_RFU_2  RFU<2>  @BASEBOARD_FAB2_LIB.BASEBOARD_FAB2(SCH_1):TP_CH_L_DIMM0_RFU_2
  227  TP_CH_L_DIMM0_RFU_1  RFU<1>  @BASEBOARD_FAB2_LIB.BASEBOARD_FAB2(SCH_1):TP_CH_L_DIMM0_RFU_1
  205  TP_CH_L_DIMM0_RFU_0  RFU<0>  @BASEBOARD_FAB2_LIB.BASEBOARD_FAB2(SCH_1):TP_CH_L_DIMM0_RFU_0
  285  SMB_DDR_KLM_VPP_SDA    SDA  @BASEBOARD_FAB2_LIB.BASEBOARD_FAB2(SCH_1):SMB_DDR_KLM_VPP_SDA
  141  SMB_DDR_KLM_VPP_SCL    SCL  @BASEBOARD_FAB2_LIB.BASEBOARD_FAB2(SCH_1):SMB_DDR_KLM_VPP_SCL
  284  PVPP_KLM       VDDSPD  @BASEBOARD_FAB2_LIB.BASEBOARD_FAB2(SCH_1):PVPP_KLM
  140  PVPP_KLM       SA<1>  @BASEBOARD_FAB2_LIB.BASEBOARD_FAB2(SCH_1):PVPP_KLM
  139  PVPP_KLM       SA<0>  @BASEBOARD_FAB2_LIB.BASEBOARD_FAB2(SCH_1):PVPP_KLM
  146  M_L_VREF       VREFCA  @BASEBOARD_FAB2_LIB.BASEBOARD_FAB2(SCH_1):M_L_VREF
  222  M_L_PAR          PAR  @BASEBOARD_FAB2_LIB.BASEBOARD_FAB2(SCH_1):M_L_PAR
   91  M_L_ODT<3>     ODT<1>  @BASEBOARD_FAB2_LIB.BASEBOARD_FAB2(SCH_1):M_L_ODT<3>
   87  M_L_ODT<2>     ODT<0>  @BASEBOARD_FAB2_LIB.BASEBOARD_FAB2(SCH_1):M_L_ODT<2>
   66  M_L_MA<9>         A9  @BASEBOARD_FAB2_LIB.BASEBOARD_FAB2(SCH_1):M_L_MA<9>
   68  M_L_MA<8>         A8  @BASEBOARD_FAB2_LIB.BASEBOARD_FAB2(SCH_1):M_L_MA<8>
  211  M_L_MA<7>         A7  @BASEBOARD_FAB2_LIB.BASEBOARD_FAB2(SCH_1):M_L_MA<7>
   69  M_L_MA<6>         A6  @BASEBOARD_FAB2_LIB.BASEBOARD_FAB2(SCH_1):M_L_MA<6>
  213  M_L_MA<5>         A5  @BASEBOARD_FAB2_LIB.BASEBOARD_FAB2(SCH_1):M_L_MA<5>
  214  M_L_MA<4>         A4  @BASEBOARD_FAB2_LIB.BASEBOARD_FAB2(SCH_1):M_L_MA<4>
   71  M_L_MA<3>         A3  @BASEBOARD_FAB2_LIB.BASEBOARD_FAB2(SCH_1):M_L_MA<3>
  216  M_L_MA<2>         A2  @BASEBOARD_FAB2_LIB.BASEBOARD_FAB2(SCH_1):M_L_MA<2>
   72  M_L_MA<1>         A1  @BASEBOARD_FAB2_LIB.BASEBOARD_FAB2(SCH_1):M_L_MA<1>
  234  M_L_MA<17>       A17  @BASEBOARD_FAB2_LIB.BASEBOARD_FAB2(SCH_1):M_L_MA<17>
   82  M_L_MA<16>     A16_RAS_N  @BASEBOARD_FAB2_LIB.BASEBOARD_FAB2(SCH_1):M_L_MA<16>
   86  M_L_MA<15>     A15_CAS_N  @BASEBOARD_FAB2_LIB.BASEBOARD_FAB2(SCH_1):M_L_MA<15>
  228  M_L_MA<14>     A14_WE_N  @BASEBOARD_FAB2_LIB.BASEBOARD_FAB2(SCH_1):M_L_MA<14>
  232  M_L_MA<13>       A13  @BASEBOARD_FAB2_LIB.BASEBOARD_FAB2(SCH_1):M_L_MA<13>
   65  M_L_MA<12>       A12  @BASEBOARD_FAB2_LIB.BASEBOARD_FAB2(SCH_1):M_L_MA<12>
  210  M_L_MA<11>       A11  @BASEBOARD_FAB2_LIB.BASEBOARD_FAB2(SCH_1):M_L_MA<11>
  225  M_L_MA<10>       A10  @BASEBOARD_FAB2_LIB.BASEBOARD_FAB2(SCH_1):M_L_MA<10>
   79  M_L_MA<0>         A0  @BASEBOARD_FAB2_LIB.BASEBOARD_FAB2(SCH_1):M_L_MA<0>
  199  M_L_ECC<7>     CB<7>  @BASEBOARD_FAB2_LIB.BASEBOARD_FAB2(SCH_1):M_L_ECC<7>
   54  M_L_ECC<6>     CB<6>  @BASEBOARD_FAB2_LIB.BASEBOARD_FAB2(SCH_1):M_L_ECC<6>
  192  M_L_ECC<5>     CB<5>  @BASEBOARD_FAB2_LIB.BASEBOARD_FAB2(SCH_1):M_L_ECC<5>
   47  M_L_ECC<4>     CB<4>  @BASEBOARD_FAB2_LIB.BASEBOARD_FAB2(SCH_1):M_L_ECC<4>
  201  M_L_ECC<3>     CB<3>  @BASEBOARD_FAB2_LIB.BASEBOARD_FAB2(SCH_1):M_L_ECC<3>
   56  M_L_ECC<2>     CB<2>  @BASEBOARD_FAB2_LIB.BASEBOARD_FAB2(SCH_1):M_L_ECC<2>
  194  M_L_ECC<1>     CB<1>  @BASEBOARD_FAB2_LIB.BASEBOARD_FAB2(SCH_1):M_L_ECC<1>
   49  M_L_ECC<0>     CB<0>  @BASEBOARD_FAB2_LIB.BASEBOARD_FAB2(SCH_1):M_L_ECC<0>
  161  M_L_DQ<9>      DQ<9>  @BASEBOARD_FAB2_LIB.BASEBOARD_FAB2(SCH_1):M_L_DQ<9>
   16  M_L_DQ<8>      DQ<8>  @BASEBOARD_FAB2_LIB.BASEBOARD_FAB2(SCH_1):M_L_DQ<8>
  155  M_L_DQ<7>      DQ<7>  @BASEBOARD_FAB2_LIB.BASEBOARD_FAB2(SCH_1):M_L_DQ<7>
   10  M_L_DQ<6>      DQ<6>  @BASEBOARD_FAB2_LIB.BASEBOARD_FAB2(SCH_1):M_L_DQ<6>
  280  M_L_DQ<63>     DQ<63>  @BASEBOARD_FAB2_LIB.BASEBOARD_FAB2(SCH_1):M_L_DQ<63>
  135  M_L_DQ<62>     DQ<62>  @BASEBOARD_FAB2_LIB.BASEBOARD_FAB2(SCH_1):M_L_DQ<62>
  273  M_L_DQ<61>     DQ<61>  @BASEBOARD_FAB2_LIB.BASEBOARD_FAB2(SCH_1):M_L_DQ<61>
  128  M_L_DQ<60>     DQ<60>  @BASEBOARD_FAB2_LIB.BASEBOARD_FAB2(SCH_1):M_L_DQ<60>
  148  M_L_DQ<5>      DQ<5>  @BASEBOARD_FAB2_LIB.BASEBOARD_FAB2(SCH_1):M_L_DQ<5>
  282  M_L_DQ<59>     DQ<59>  @BASEBOARD_FAB2_LIB.BASEBOARD_FAB2(SCH_1):M_L_DQ<59>
  137  M_L_DQ<58>     DQ<58>  @BASEBOARD_FAB2_LIB.BASEBOARD_FAB2(SCH_1):M_L_DQ<58>
  275  M_L_DQ<57>     DQ<57>  @BASEBOARD_FAB2_LIB.BASEBOARD_FAB2(SCH_1):M_L_DQ<57>
  130  M_L_DQ<56>     DQ<56>  @BASEBOARD_FAB2_LIB.BASEBOARD_FAB2(SCH_1):M_L_DQ<56>
  269  M_L_DQ<55>     DQ<55>  @BASEBOARD_FAB2_LIB.BASEBOARD_FAB2(SCH_1):M_L_DQ<55>
  124  M_L_DQ<54>     DQ<54>  @BASEBOARD_FAB2_LIB.BASEBOARD_FAB2(SCH_1):M_L_DQ<54>
  262  M_L_DQ<53>     DQ<53>  @BASEBOARD_FAB2_LIB.BASEBOARD_FAB2(SCH_1):M_L_DQ<53>
  117  M_L_DQ<52>     DQ<52>  @BASEBOARD_FAB2_LIB.BASEBOARD_FAB2(SCH_1):M_L_DQ<52>
  271  M_L_DQ<51>     DQ<51>  @BASEBOARD_FAB2_LIB.BASEBOARD_FAB2(SCH_1):M_L_DQ<51>
  126  M_L_DQ<50>     DQ<50>  @BASEBOARD_FAB2_LIB.BASEBOARD_FAB2(SCH_1):M_L_DQ<50>
    3  M_L_DQ<4>      DQ<4>  @BASEBOARD_FAB2_LIB.BASEBOARD_FAB2(SCH_1):M_L_DQ<4>
  264  M_L_DQ<49>     DQ<49>  @BASEBOARD_FAB2_LIB.BASEBOARD_FAB2(SCH_1):M_L_DQ<49>
  119  M_L_DQ<48>     DQ<48>  @BASEBOARD_FAB2_LIB.BASEBOARD_FAB2(SCH_1):M_L_DQ<48>
  258  M_L_DQ<47>     DQ<47>  @BASEBOARD_FAB2_LIB.BASEBOARD_FAB2(SCH_1):M_L_DQ<47>
  113  M_L_DQ<46>     DQ<46>  @BASEBOARD_FAB2_LIB.BASEBOARD_FAB2(SCH_1):M_L_DQ<46>
  251  M_L_DQ<45>     DQ<45>  @BASEBOARD_FAB2_LIB.BASEBOARD_FAB2(SCH_1):M_L_DQ<45>
  106  M_L_DQ<44>     DQ<44>  @BASEBOARD_FAB2_LIB.BASEBOARD_FAB2(SCH_1):M_L_DQ<44>
  260  M_L_DQ<43>     DQ<43>  @BASEBOARD_FAB2_LIB.BASEBOARD_FAB2(SCH_1):M_L_DQ<43>
  115  M_L_DQ<42>     DQ<42>  @BASEBOARD_FAB2_LIB.BASEBOARD_FAB2(SCH_1):M_L_DQ<42>
  253  M_L_DQ<41>     DQ<41>  @BASEBOARD_FAB2_LIB.BASEBOARD_FAB2(SCH_1):M_L_DQ<41>
  108  M_L_DQ<40>     DQ<40>  @BASEBOARD_FAB2_LIB.BASEBOARD_FAB2(SCH_1):M_L_DQ<40>
  157  M_L_DQ<3>      DQ<3>  @BASEBOARD_FAB2_LIB.BASEBOARD_FAB2(SCH_1):M_L_DQ<3>
  247  M_L_DQ<39>     DQ<39>  @BASEBOARD_FAB2_LIB.BASEBOARD_FAB2(SCH_1):M_L_DQ<39>
  102  M_L_DQ<38>     DQ<38>  @BASEBOARD_FAB2_LIB.BASEBOARD_FAB2(SCH_1):M_L_DQ<38>
  240  M_L_DQ<37>     DQ<37>  @BASEBOARD_FAB2_LIB.BASEBOARD_FAB2(SCH_1):M_L_DQ<37>
   95  M_L_DQ<36>     DQ<36>  @BASEBOARD_FAB2_LIB.BASEBOARD_FAB2(SCH_1):M_L_DQ<36>
  249  M_L_DQ<35>     DQ<35>  @BASEBOARD_FAB2_LIB.BASEBOARD_FAB2(SCH_1):M_L_DQ<35>
  104  M_L_DQ<34>     DQ<34>  @BASEBOARD_FAB2_LIB.BASEBOARD_FAB2(SCH_1):M_L_DQ<34>
  242  M_L_DQ<33>     DQ<33>  @BASEBOARD_FAB2_LIB.BASEBOARD_FAB2(SCH_1):M_L_DQ<33>
   97  M_L_DQ<32>     DQ<32>  @BASEBOARD_FAB2_LIB.BASEBOARD_FAB2(SCH_1):M_L_DQ<32>
  188  M_L_DQ<31>     DQ<31>  @BASEBOARD_FAB2_LIB.BASEBOARD_FAB2(SCH_1):M_L_DQ<31>
   43  M_L_DQ<30>     DQ<30>  @BASEBOARD_FAB2_LIB.BASEBOARD_FAB2(SCH_1):M_L_DQ<30>
   12  M_L_DQ<2>      DQ<2>  @BASEBOARD_FAB2_LIB.BASEBOARD_FAB2(SCH_1):M_L_DQ<2>
  181  M_L_DQ<29>     DQ<29>  @BASEBOARD_FAB2_LIB.BASEBOARD_FAB2(SCH_1):M_L_DQ<29>
   36  M_L_DQ<28>     DQ<28>  @BASEBOARD_FAB2_LIB.BASEBOARD_FAB2(SCH_1):M_L_DQ<28>
  190  M_L_DQ<27>     DQ<27>  @BASEBOARD_FAB2_LIB.BASEBOARD_FAB2(SCH_1):M_L_DQ<27>
   45  M_L_DQ<26>     DQ<26>  @BASEBOARD_FAB2_LIB.BASEBOARD_FAB2(SCH_1):M_L_DQ<26>
  183  M_L_DQ<25>     DQ<25>  @BASEBOARD_FAB2_LIB.BASEBOARD_FAB2(SCH_1):M_L_DQ<25>
   38  M_L_DQ<24>     DQ<24>  @BASEBOARD_FAB2_LIB.BASEBOARD_FAB2(SCH_1):M_L_DQ<24>
  177  M_L_DQ<23>     DQ<23>  @BASEBOARD_FAB2_LIB.BASEBOARD_FAB2(SCH_1):M_L_DQ<23>
   32  M_L_DQ<22>     DQ<22>  @BASEBOARD_FAB2_LIB.BASEBOARD_FAB2(SCH_1):M_L_DQ<22>
  170  M_L_DQ<21>     DQ<21>  @BASEBOARD_FAB2_LIB.BASEBOARD_FAB2(SCH_1):M_L_DQ<21>
   25  M_L_DQ<20>     DQ<20>  @BASEBOARD_FAB2_LIB.BASEBOARD_FAB2(SCH_1):M_L_DQ<20>
  150  M_L_DQ<1>      DQ<1>  @BASEBOARD_FAB2_LIB.BASEBOARD_FAB2(SCH_1):M_L_DQ<1>
  179  M_L_DQ<19>     DQ<19>  @BASEBOARD_FAB2_LIB.BASEBOARD_FAB2(SCH_1):M_L_DQ<19>
   34  M_L_DQ<18>     DQ<18>  @BASEBOARD_FAB2_LIB.BASEBOARD_FAB2(SCH_1):M_L_DQ<18>
  172  M_L_DQ<17>     DQ<17>  @BASEBOARD_FAB2_LIB.BASEBOARD_FAB2(SCH_1):M_L_DQ<17>
   27  M_L_DQ<16>     DQ<16>  @BASEBOARD_FAB2_LIB.BASEBOARD_FAB2(SCH_1):M_L_DQ<16>
  166  M_L_DQ<15>     DQ<15>  @BASEBOARD_FAB2_LIB.BASEBOARD_FAB2(SCH_1):M_L_DQ<15>
   21  M_L_DQ<14>     DQ<14>  @BASEBOARD_FAB2_LIB.BASEBOARD_FAB2(SCH_1):M_L_DQ<14>
  159  M_L_DQ<13>     DQ<13>  @BASEBOARD_FAB2_LIB.BASEBOARD_FAB2(SCH_1):M_L_DQ<13>
   14  M_L_DQ<12>     DQ<12>  @BASEBOARD_FAB2_LIB.BASEBOARD_FAB2(SCH_1):M_L_DQ<12>
  168  M_L_DQ<11>     DQ<11>  @BASEBOARD_FAB2_LIB.BASEBOARD_FAB2(SCH_1):M_L_DQ<11>
   23  M_L_DQ<10>     DQ<10>  @BASEBOARD_FAB2_LIB.BASEBOARD_FAB2(SCH_1):M_L_DQ<10>
    5  M_L_DQ<0>      DQ<0>  @BASEBOARD_FAB2_LIB.BASEBOARD_FAB2(SCH_1):M_L_DQ<0>
  237  M_L_CS_N<7>    S3_N_C<1>  @BASEBOARD_FAB2_LIB.BASEBOARD_FAB2(SCH_1):M_L_CS_N<7>
   93  M_L_CS_N<6>    S2_N_C<0>  @BASEBOARD_FAB2_LIB.BASEBOARD_FAB2(SCH_1):M_L_CS_N<6>
   89  M_L_CS_N<5>     S1_N  @BASEBOARD_FAB2_LIB.BASEBOARD_FAB2(SCH_1):M_L_CS_N<5>
   84  M_L_CS_N<4>     S0_N  @BASEBOARD_FAB2_LIB.BASEBOARD_FAB2(SCH_1):M_L_CS_N<4>
  218  M_L_CLK_DP<3>   CK1P  @BASEBOARD_FAB2_LIB.BASEBOARD_FAB2(SCH_1):M_L_CLK_DP<3>
   74  M_L_CLK_DP<2>   CK0P  @BASEBOARD_FAB2_LIB.BASEBOARD_FAB2(SCH_1):M_L_CLK_DP<2>
  219  M_L_CLK_DN<3>   CK1N  @BASEBOARD_FAB2_LIB.BASEBOARD_FAB2(SCH_1):M_L_CLK_DN<3>
   75  M_L_CLK_DN<2>   CK0N  @BASEBOARD_FAB2_LIB.BASEBOARD_FAB2(SCH_1):M_L_CLK_DN<2>
  203  M_L_CKE<3>     CKE<1>  @BASEBOARD_FAB2_LIB.BASEBOARD_FAB2(SCH_1):M_L_CKE<3>
   60  M_L_CKE<2>     CKE<0>  @BASEBOARD_FAB2_LIB.BASEBOARD_FAB2(SCH_1):M_L_CKE<2>
  235  M_L_C<2>        C<2>  @BASEBOARD_FAB2_LIB.BASEBOARD_FAB2(SCH_1):M_L_C<2>
  207  M_L_BG<1>      BG<1>  @BASEBOARD_FAB2_LIB.BASEBOARD_FAB2(SCH_1):M_L_BG<1>
   63  M_L_BG<0>      BG<0>  @BASEBOARD_FAB2_LIB.BASEBOARD_FAB2(SCH_1):M_L_BG<0>
  224  M_L_BA<1>      BA<1>  @BASEBOARD_FAB2_LIB.BASEBOARD_FAB2(SCH_1):M_L_BA<1>
   81  M_L_BA<0>      BA<0>  @BASEBOARD_FAB2_LIB.BASEBOARD_FAB2(SCH_1):M_L_BA<0>
  208  M_L_ALERT_N    ALERT_N  @BASEBOARD_FAB2_LIB.BASEBOARD_FAB2(SCH_1):M_L_ALERT_N
   62  M_L_ACT_N      ACT_N  @BASEBOARD_FAB2_LIB.BASEBOARD_FAB2(SCH_1):M_L_ACT_N
   58  M_KLM_RST_N    RESET_N  @BASEBOARD_FAB2_LIB.BASEBOARD_FAB2(SCH_1):M_KLM_RST_N
  238  GND            SA<2>  @BASEBOARD_FAB2_LIB.BASEBOARD_FAB2(SCH_1):GND
   78  FM_DIMM_EVENT_COD_N  EVENT_N  @BASEBOARD_FAB2_LIB.BASEBOARD_FAB2(SCH_1):FM_DIMM_EVENT_COD_N
  230  FM_ADR_COMPLETE_KLM_N  SAVE_N_NC  @BASEBOARD_FAB2_LIB.BASEBOARD_FAB2(SCH_1):FM_ADR_COMPLETE_KLM_N

SCONN288_H44441003_PIP  I57  J9M1   [SCONN288_H44441003_PIP-SCONN,HA]
   77  PVTT_KLM       VTT<1>  @BASEBOARD_FAB2_LIB.BASEBOARD_FAB2(SCH_1):PVTT_KLM
  221  PVTT_KLM       VTT<0>  @BASEBOARD_FAB2_LIB.BASEBOARD_FAB2(SCH_1):PVTT_KLM
  142  PVPP_KLM       VPP<4>  @BASEBOARD_FAB2_LIB.BASEBOARD_FAB2(SCH_1):PVPP_KLM
  143  PVPP_KLM       VPP<3>  @BASEBOARD_FAB2_LIB.BASEBOARD_FAB2(SCH_1):PVPP_KLM
  288  PVPP_KLM       VPP<2>  @BASEBOARD_FAB2_LIB.BASEBOARD_FAB2(SCH_1):PVPP_KLM
  286  PVPP_KLM       VPP<1>  @BASEBOARD_FAB2_LIB.BASEBOARD_FAB2(SCH_1):PVPP_KLM
  287  PVPP_KLM       VPP<0>  @BASEBOARD_FAB2_LIB.BASEBOARD_FAB2(SCH_1):PVPP_KLM
   59  PVDDQ_KLM      VDD<25>  @BASEBOARD_FAB2_LIB.BASEBOARD_FAB2(SCH_1):PVDDQ_KLM
   61  PVDDQ_KLM      VDD<24>  @BASEBOARD_FAB2_LIB.BASEBOARD_FAB2(SCH_1):PVDDQ_KLM
   64  PVDDQ_KLM      VDD<23>  @BASEBOARD_FAB2_LIB.BASEBOARD_FAB2(SCH_1):PVDDQ_KLM
   67  PVDDQ_KLM      VDD<22>  @BASEBOARD_FAB2_LIB.BASEBOARD_FAB2(SCH_1):PVDDQ_KLM
   70  PVDDQ_KLM      VDD<21>  @BASEBOARD_FAB2_LIB.BASEBOARD_FAB2(SCH_1):PVDDQ_KLM
   73  PVDDQ_KLM      VDD<20>  @BASEBOARD_FAB2_LIB.BASEBOARD_FAB2(SCH_1):PVDDQ_KLM
   76  PVDDQ_KLM      VDD<19>  @BASEBOARD_FAB2_LIB.BASEBOARD_FAB2(SCH_1):PVDDQ_KLM
   80  PVDDQ_KLM      VDD<18>  @BASEBOARD_FAB2_LIB.BASEBOARD_FAB2(SCH_1):PVDDQ_KLM
   83  PVDDQ_KLM      VDD<17>  @BASEBOARD_FAB2_LIB.BASEBOARD_FAB2(SCH_1):PVDDQ_KLM
   85  PVDDQ_KLM      VDD<16>  @BASEBOARD_FAB2_LIB.BASEBOARD_FAB2(SCH_1):PVDDQ_KLM
   88  PVDDQ_KLM      VDD<15>  @BASEBOARD_FAB2_LIB.BASEBOARD_FAB2(SCH_1):PVDDQ_KLM
   90  PVDDQ_KLM      VDD<14>  @BASEBOARD_FAB2_LIB.BASEBOARD_FAB2(SCH_1):PVDDQ_KLM
   92  PVDDQ_KLM      VDD<13>  @BASEBOARD_FAB2_LIB.BASEBOARD_FAB2(SCH_1):PVDDQ_KLM
  204  PVDDQ_KLM      VDD<12>  @BASEBOARD_FAB2_LIB.BASEBOARD_FAB2(SCH_1):PVDDQ_KLM
  206  PVDDQ_KLM      VDD<11>  @BASEBOARD_FAB2_LIB.BASEBOARD_FAB2(SCH_1):PVDDQ_KLM
  209  PVDDQ_KLM      VDD<10>  @BASEBOARD_FAB2_LIB.BASEBOARD_FAB2(SCH_1):PVDDQ_KLM
  212  PVDDQ_KLM      VDD<9>  @BASEBOARD_FAB2_LIB.BASEBOARD_FAB2(SCH_1):PVDDQ_KLM
  215  PVDDQ_KLM      VDD<8>  @BASEBOARD_FAB2_LIB.BASEBOARD_FAB2(SCH_1):PVDDQ_KLM
  217  PVDDQ_KLM      VDD<7>  @BASEBOARD_FAB2_LIB.BASEBOARD_FAB2(SCH_1):PVDDQ_KLM
  220  PVDDQ_KLM      VDD<6>  @BASEBOARD_FAB2_LIB.BASEBOARD_FAB2(SCH_1):PVDDQ_KLM
  223  PVDDQ_KLM      VDD<5>  @BASEBOARD_FAB2_LIB.BASEBOARD_FAB2(SCH_1):PVDDQ_KLM
  226  PVDDQ_KLM      VDD<4>  @BASEBOARD_FAB2_LIB.BASEBOARD_FAB2(SCH_1):PVDDQ_KLM
  229  PVDDQ_KLM      VDD<3>  @BASEBOARD_FAB2_LIB.BASEBOARD_FAB2(SCH_1):PVDDQ_KLM
  231  PVDDQ_KLM      VDD<2>  @BASEBOARD_FAB2_LIB.BASEBOARD_FAB2(SCH_1):PVDDQ_KLM
  233  PVDDQ_KLM      VDD<1>  @BASEBOARD_FAB2_LIB.BASEBOARD_FAB2(SCH_1):PVDDQ_KLM
  236  PVDDQ_KLM      VDD<0>  @BASEBOARD_FAB2_LIB.BASEBOARD_FAB2(SCH_1):PVDDQ_KLM
    1  P12V_NVDIMM_KLM  12V<1>  @BASEBOARD_FAB2_LIB.BASEBOARD_FAB2(SCH_1):P12V_NVDIMM_KLM
  145  P12V_NVDIMM_KLM  12V<0>  @BASEBOARD_FAB2_LIB.BASEBOARD_FAB2(SCH_1):P12V_NVDIMM_KLM

SCONN288_H44441003_PIP  I138  J9M1   [SCONN288_H44441003_PIP-SCONN,HA]
    2  GND            VSS<93>  @BASEBOARD_FAB2_LIB.BASEBOARD_FAB2(SCH_1):GND
    4  GND            VSS<92>  @BASEBOARD_FAB2_LIB.BASEBOARD_FAB2(SCH_1):GND
    6  GND            VSS<91>  @BASEBOARD_FAB2_LIB.BASEBOARD_FAB2(SCH_1):GND
    9  GND            VSS<90>  @BASEBOARD_FAB2_LIB.BASEBOARD_FAB2(SCH_1):GND
   11  GND            VSS<89>  @BASEBOARD_FAB2_LIB.BASEBOARD_FAB2(SCH_1):GND
   13  GND            VSS<88>  @BASEBOARD_FAB2_LIB.BASEBOARD_FAB2(SCH_1):GND
   15  GND            VSS<87>  @BASEBOARD_FAB2_LIB.BASEBOARD_FAB2(SCH_1):GND
   17  GND            VSS<86>  @BASEBOARD_FAB2_LIB.BASEBOARD_FAB2(SCH_1):GND
   20  GND            VSS<85>  @BASEBOARD_FAB2_LIB.BASEBOARD_FAB2(SCH_1):GND
   22  GND            VSS<84>  @BASEBOARD_FAB2_LIB.BASEBOARD_FAB2(SCH_1):GND
   24  GND            VSS<83>  @BASEBOARD_FAB2_LIB.BASEBOARD_FAB2(SCH_1):GND
   26  GND            VSS<82>  @BASEBOARD_FAB2_LIB.BASEBOARD_FAB2(SCH_1):GND
   28  GND            VSS<81>  @BASEBOARD_FAB2_LIB.BASEBOARD_FAB2(SCH_1):GND
   31  GND            VSS<80>  @BASEBOARD_FAB2_LIB.BASEBOARD_FAB2(SCH_1):GND
   33  GND            VSS<79>  @BASEBOARD_FAB2_LIB.BASEBOARD_FAB2(SCH_1):GND
   35  GND            VSS<78>  @BASEBOARD_FAB2_LIB.BASEBOARD_FAB2(SCH_1):GND
   37  GND            VSS<77>  @BASEBOARD_FAB2_LIB.BASEBOARD_FAB2(SCH_1):GND
   39  GND            VSS<76>  @BASEBOARD_FAB2_LIB.BASEBOARD_FAB2(SCH_1):GND
   42  GND            VSS<75>  @BASEBOARD_FAB2_LIB.BASEBOARD_FAB2(SCH_1):GND
   44  GND            VSS<74>  @BASEBOARD_FAB2_LIB.BASEBOARD_FAB2(SCH_1):GND
   46  GND            VSS<73>  @BASEBOARD_FAB2_LIB.BASEBOARD_FAB2(SCH_1):GND
   48  GND            VSS<72>  @BASEBOARD_FAB2_LIB.BASEBOARD_FAB2(SCH_1):GND
   50  GND            VSS<71>  @BASEBOARD_FAB2_LIB.BASEBOARD_FAB2(SCH_1):GND
   53  GND            VSS<70>  @BASEBOARD_FAB2_LIB.BASEBOARD_FAB2(SCH_1):GND
   55  GND            VSS<69>  @BASEBOARD_FAB2_LIB.BASEBOARD_FAB2(SCH_1):GND
   57  GND            VSS<68>  @BASEBOARD_FAB2_LIB.BASEBOARD_FAB2(SCH_1):GND
   94  GND            VSS<67>  @BASEBOARD_FAB2_LIB.BASEBOARD_FAB2(SCH_1):GND
   96  GND            VSS<66>  @BASEBOARD_FAB2_LIB.BASEBOARD_FAB2(SCH_1):GND
   98  GND            VSS<65>  @BASEBOARD_FAB2_LIB.BASEBOARD_FAB2(SCH_1):GND
  101  GND            VSS<64>  @BASEBOARD_FAB2_LIB.BASEBOARD_FAB2(SCH_1):GND
  103  GND            VSS<63>  @BASEBOARD_FAB2_LIB.BASEBOARD_FAB2(SCH_1):GND
  105  GND            VSS<62>  @BASEBOARD_FAB2_LIB.BASEBOARD_FAB2(SCH_1):GND
  107  GND            VSS<61>  @BASEBOARD_FAB2_LIB.BASEBOARD_FAB2(SCH_1):GND
  109  GND            VSS<60>  @BASEBOARD_FAB2_LIB.BASEBOARD_FAB2(SCH_1):GND
  112  GND            VSS<59>  @BASEBOARD_FAB2_LIB.BASEBOARD_FAB2(SCH_1):GND
  114  GND            VSS<58>  @BASEBOARD_FAB2_LIB.BASEBOARD_FAB2(SCH_1):GND
  116  GND            VSS<57>  @BASEBOARD_FAB2_LIB.BASEBOARD_FAB2(SCH_1):GND
  118  GND            VSS<56>  @BASEBOARD_FAB2_LIB.BASEBOARD_FAB2(SCH_1):GND
  120  GND            VSS<55>  @BASEBOARD_FAB2_LIB.BASEBOARD_FAB2(SCH_1):GND
  123  GND            VSS<54>  @BASEBOARD_FAB2_LIB.BASEBOARD_FAB2(SCH_1):GND
  125  GND            VSS<53>  @BASEBOARD_FAB2_LIB.BASEBOARD_FAB2(SCH_1):GND
  127  GND            VSS<52>  @BASEBOARD_FAB2_LIB.BASEBOARD_FAB2(SCH_1):GND
  129  GND            VSS<51>  @BASEBOARD_FAB2_LIB.BASEBOARD_FAB2(SCH_1):GND
  131  GND            VSS<50>  @BASEBOARD_FAB2_LIB.BASEBOARD_FAB2(SCH_1):GND
  134  GND            VSS<49>  @BASEBOARD_FAB2_LIB.BASEBOARD_FAB2(SCH_1):GND
  136  GND            VSS<48>  @BASEBOARD_FAB2_LIB.BASEBOARD_FAB2(SCH_1):GND
  138  GND            VSS<47>  @BASEBOARD_FAB2_LIB.BASEBOARD_FAB2(SCH_1):GND
  147  GND            VSS<46>  @BASEBOARD_FAB2_LIB.BASEBOARD_FAB2(SCH_1):GND
  149  GND            VSS<45>  @BASEBOARD_FAB2_LIB.BASEBOARD_FAB2(SCH_1):GND
  151  GND            VSS<44>  @BASEBOARD_FAB2_LIB.BASEBOARD_FAB2(SCH_1):GND
  154  GND            VSS<43>  @BASEBOARD_FAB2_LIB.BASEBOARD_FAB2(SCH_1):GND
  156  GND            VSS<42>  @BASEBOARD_FAB2_LIB.BASEBOARD_FAB2(SCH_1):GND
  158  GND            VSS<41>  @BASEBOARD_FAB2_LIB.BASEBOARD_FAB2(SCH_1):GND
  160  GND            VSS<40>  @BASEBOARD_FAB2_LIB.BASEBOARD_FAB2(SCH_1):GND
  162  GND            VSS<39>  @BASEBOARD_FAB2_LIB.BASEBOARD_FAB2(SCH_1):GND
  165  GND            VSS<38>  @BASEBOARD_FAB2_LIB.BASEBOARD_FAB2(SCH_1):GND
  167  GND            VSS<37>  @BASEBOARD_FAB2_LIB.BASEBOARD_FAB2(SCH_1):GND
  169  GND            VSS<36>  @BASEBOARD_FAB2_LIB.BASEBOARD_FAB2(SCH_1):GND
  171  GND            VSS<35>  @BASEBOARD_FAB2_LIB.BASEBOARD_FAB2(SCH_1):GND
  173  GND            VSS<34>  @BASEBOARD_FAB2_LIB.BASEBOARD_FAB2(SCH_1):GND
  176  GND            VSS<33>  @BASEBOARD_FAB2_LIB.BASEBOARD_FAB2(SCH_1):GND
  178  GND            VSS<32>  @BASEBOARD_FAB2_LIB.BASEBOARD_FAB2(SCH_1):GND
  180  GND            VSS<31>  @BASEBOARD_FAB2_LIB.BASEBOARD_FAB2(SCH_1):GND
  182  GND            VSS<30>  @BASEBOARD_FAB2_LIB.BASEBOARD_FAB2(SCH_1):GND
  184  GND            VSS<29>  @BASEBOARD_FAB2_LIB.BASEBOARD_FAB2(SCH_1):GND
  187  GND            VSS<28>  @BASEBOARD_FAB2_LIB.BASEBOARD_FAB2(SCH_1):GND
  189  GND            VSS<27>  @BASEBOARD_FAB2_LIB.BASEBOARD_FAB2(SCH_1):GND
  191  GND            VSS<26>  @BASEBOARD_FAB2_LIB.BASEBOARD_FAB2(SCH_1):GND
  193  GND            VSS<25>  @BASEBOARD_FAB2_LIB.BASEBOARD_FAB2(SCH_1):GND
  195  GND            VSS<24>  @BASEBOARD_FAB2_LIB.BASEBOARD_FAB2(SCH_1):GND
  198  GND            VSS<23>  @BASEBOARD_FAB2_LIB.BASEBOARD_FAB2(SCH_1):GND
  200  GND            VSS<22>  @BASEBOARD_FAB2_LIB.BASEBOARD_FAB2(SCH_1):GND
  202  GND            VSS<21>  @BASEBOARD_FAB2_LIB.BASEBOARD_FAB2(SCH_1):GND
  239  GND            VSS<20>  @BASEBOARD_FAB2_LIB.BASEBOARD_FAB2(SCH_1):GND
  241  GND            VSS<19>  @BASEBOARD_FAB2_LIB.BASEBOARD_FAB2(SCH_1):GND
  243  GND            VSS<18>  @BASEBOARD_FAB2_LIB.BASEBOARD_FAB2(SCH_1):GND
  246  GND            VSS<17>  @BASEBOARD_FAB2_LIB.BASEBOARD_FAB2(SCH_1):GND
  248  GND            VSS<16>  @BASEBOARD_FAB2_LIB.BASEBOARD_FAB2(SCH_1):GND
  250  GND            VSS<15>  @BASEBOARD_FAB2_LIB.BASEBOARD_FAB2(SCH_1):GND
  252  GND            VSS<14>  @BASEBOARD_FAB2_LIB.BASEBOARD_FAB2(SCH_1):GND
  254  GND            VSS<13>  @BASEBOARD_FAB2_LIB.BASEBOARD_FAB2(SCH_1):GND
  257  GND            VSS<12>  @BASEBOARD_FAB2_LIB.BASEBOARD_FAB2(SCH_1):GND
  259  GND            VSS<11>  @BASEBOARD_FAB2_LIB.BASEBOARD_FAB2(SCH_1):GND
  261  GND            VSS<10>  @BASEBOARD_FAB2_LIB.BASEBOARD_FAB2(SCH_1):GND
  263  GND            VSS<9>  @BASEBOARD_FAB2_LIB.BASEBOARD_FAB2(SCH_1):GND
  265  GND            VSS<8>  @BASEBOARD_FAB2_LIB.BASEBOARD_FAB2(SCH_1):GND
  268  GND            VSS<7>  @BASEBOARD_FAB2_LIB.BASEBOARD_FAB2(SCH_1):GND
  270  GND            VSS<6>  @BASEBOARD_FAB2_LIB.BASEBOARD_FAB2(SCH_1):GND
  272  GND            VSS<5>  @BASEBOARD_FAB2_LIB.BASEBOARD_FAB2(SCH_1):GND
  274  GND            VSS<4>  @BASEBOARD_FAB2_LIB.BASEBOARD_FAB2(SCH_1):GND
  276  GND            VSS<3>  @BASEBOARD_FAB2_LIB.BASEBOARD_FAB2(SCH_1):GND
  279  GND            VSS<2>  @BASEBOARD_FAB2_LIB.BASEBOARD_FAB2(SCH_1):GND
  281  GND            VSS<1>  @BASEBOARD_FAB2_LIB.BASEBOARD_FAB2(SCH_1):GND
  283  GND            VSS<0>  @BASEBOARD_FAB2_LIB.BASEBOARD_FAB2(SCH_1):GND

SCONN288_H44441003_PIP  I102  J9M1   [SCONN288_H44441003_PIP-SCONN,HA]
    7  M_K_DQS_DP<9>  DQS9P  @BASEBOARD_FAB2_LIB.BASEBOARD_FAB2(SCH_1):M_K_DQS_DP<9>
  197  M_K_DQS_DP<8>  DQS8P  @BASEBOARD_FAB2_LIB.BASEBOARD_FAB2(SCH_1):M_K_DQS_DP<8>
  278  M_K_DQS_DP<7>  DQS7P  @BASEBOARD_FAB2_LIB.BASEBOARD_FAB2(SCH_1):M_K_DQS_DP<7>
  267  M_K_DQS_DP<6>  DQS6P  @BASEBOARD_FAB2_LIB.BASEBOARD_FAB2(SCH_1):M_K_DQS_DP<6>
  256  M_K_DQS_DP<5>  DQS5P  @BASEBOARD_FAB2_LIB.BASEBOARD_FAB2(SCH_1):M_K_DQS_DP<5>
  245  M_K_DQS_DP<4>  DQS4P  @BASEBOARD_FAB2_LIB.BASEBOARD_FAB2(SCH_1):M_K_DQS_DP<4>
  186  M_K_DQS_DP<3>  DQS3P  @BASEBOARD_FAB2_LIB.BASEBOARD_FAB2(SCH_1):M_K_DQS_DP<3>
  175  M_K_DQS_DP<2>  DQS2P  @BASEBOARD_FAB2_LIB.BASEBOARD_FAB2(SCH_1):M_K_DQS_DP<2>
  164  M_K_DQS_DP<1>  DQS1P  @BASEBOARD_FAB2_LIB.BASEBOARD_FAB2(SCH_1):M_K_DQS_DP<1>
   51  M_K_DQS_DP<17>  DQS17P  @BASEBOARD_FAB2_LIB.BASEBOARD_FAB2(SCH_1):M_K_DQS_DP<17>
  132  M_K_DQS_DP<16>  DQS16P  @BASEBOARD_FAB2_LIB.BASEBOARD_FAB2(SCH_1):M_K_DQS_DP<16>
  121  M_K_DQS_DP<15>  DQS15P  @BASEBOARD_FAB2_LIB.BASEBOARD_FAB2(SCH_1):M_K_DQS_DP<15>
  110  M_K_DQS_DP<14>  DQS14P  @BASEBOARD_FAB2_LIB.BASEBOARD_FAB2(SCH_1):M_K_DQS_DP<14>
   99  M_K_DQS_DP<13>  DQS13P  @BASEBOARD_FAB2_LIB.BASEBOARD_FAB2(SCH_1):M_K_DQS_DP<13>
   40  M_K_DQS_DP<12>  DQS12P  @BASEBOARD_FAB2_LIB.BASEBOARD_FAB2(SCH_1):M_K_DQS_DP<12>
   29  M_K_DQS_DP<11>  DQS11P  @BASEBOARD_FAB2_LIB.BASEBOARD_FAB2(SCH_1):M_K_DQS_DP<11>
   18  M_K_DQS_DP<10>  DQS10P  @BASEBOARD_FAB2_LIB.BASEBOARD_FAB2(SCH_1):M_K_DQS_DP<10>
  153  M_K_DQS_DP<0>  DQS0P  @BASEBOARD_FAB2_LIB.BASEBOARD_FAB2(SCH_1):M_K_DQS_DP<0>
    8  M_K_DQS_DN<9>  DQS9N  @BASEBOARD_FAB2_LIB.BASEBOARD_FAB2(SCH_1):M_K_DQS_DN<9>
  196  M_K_DQS_DN<8>  DQS8N  @BASEBOARD_FAB2_LIB.BASEBOARD_FAB2(SCH_1):M_K_DQS_DN<8>
  277  M_K_DQS_DN<7>  DQS7N  @BASEBOARD_FAB2_LIB.BASEBOARD_FAB2(SCH_1):M_K_DQS_DN<7>
  266  M_K_DQS_DN<6>  DQS6N  @BASEBOARD_FAB2_LIB.BASEBOARD_FAB2(SCH_1):M_K_DQS_DN<6>
  255  M_K_DQS_DN<5>  DQS5N  @BASEBOARD_FAB2_LIB.BASEBOARD_FAB2(SCH_1):M_K_DQS_DN<5>
  244  M_K_DQS_DN<4>  DQS4N  @BASEBOARD_FAB2_LIB.BASEBOARD_FAB2(SCH_1):M_K_DQS_DN<4>
  185  M_K_DQS_DN<3>  DQS3N  @BASEBOARD_FAB2_LIB.BASEBOARD_FAB2(SCH_1):M_K_DQS_DN<3>
  174  M_K_DQS_DN<2>  DQS2N  @BASEBOARD_FAB2_LIB.BASEBOARD_FAB2(SCH_1):M_K_DQS_DN<2>
  163  M_K_DQS_DN<1>  DQS1N  @BASEBOARD_FAB2_LIB.BASEBOARD_FAB2(SCH_1):M_K_DQS_DN<1>
   52  M_K_DQS_DN<17>  DQS17N  @BASEBOARD_FAB2_LIB.BASEBOARD_FAB2(SCH_1):M_K_DQS_DN<17>
  133  M_K_DQS_DN<16>  DQS16N  @BASEBOARD_FAB2_LIB.BASEBOARD_FAB2(SCH_1):M_K_DQS_DN<16>
  122  M_K_DQS_DN<15>  DQS15N  @BASEBOARD_FAB2_LIB.BASEBOARD_FAB2(SCH_1):M_K_DQS_DN<15>
  111  M_K_DQS_DN<14>  DQS14N  @BASEBOARD_FAB2_LIB.BASEBOARD_FAB2(SCH_1):M_K_DQS_DN<14>
  100  M_K_DQS_DN<13>  DQS13N  @BASEBOARD_FAB2_LIB.BASEBOARD_FAB2(SCH_1):M_K_DQS_DN<13>
   41  M_K_DQS_DN<12>  DQS12N  @BASEBOARD_FAB2_LIB.BASEBOARD_FAB2(SCH_1):M_K_DQS_DN<12>
   30  M_K_DQS_DN<11>  DQS11N  @BASEBOARD_FAB2_LIB.BASEBOARD_FAB2(SCH_1):M_K_DQS_DN<11>
   19  M_K_DQS_DN<10>  DQS10N  @BASEBOARD_FAB2_LIB.BASEBOARD_FAB2(SCH_1):M_K_DQS_DN<10>
  152  M_K_DQS_DN<0>  DQS0N  @BASEBOARD_FAB2_LIB.BASEBOARD_FAB2(SCH_1):M_K_DQS_DN<0>

SCONN288_H44441003_PIP  I14  J9M1   [SCONN288_H44441003_PIP-SCONN,HA]
  144  TP_CH_K_DIMM0_RFU_2  RFU<2>  @BASEBOARD_FAB2_LIB.BASEBOARD_FAB2(SCH_1):TP_CH_K_DIMM0_RFU_2
  227  TP_CH_K_DIMM0_RFU_1  RFU<1>  @BASEBOARD_FAB2_LIB.BASEBOARD_FAB2(SCH_1):TP_CH_K_DIMM0_RFU_1
  205  TP_CH_K_DIMM0_RFU_0  RFU<0>  @BASEBOARD_FAB2_LIB.BASEBOARD_FAB2(SCH_1):TP_CH_K_DIMM0_RFU_0
  285  SMB_DDR_KLM_VPP_SDA    SDA  @BASEBOARD_FAB2_LIB.BASEBOARD_FAB2(SCH_1):SMB_DDR_KLM_VPP_SDA
  141  SMB_DDR_KLM_VPP_SCL    SCL  @BASEBOARD_FAB2_LIB.BASEBOARD_FAB2(SCH_1):SMB_DDR_KLM_VPP_SCL
  284  PVPP_KLM       VDDSPD  @BASEBOARD_FAB2_LIB.BASEBOARD_FAB2(SCH_1):PVPP_KLM
  139  PVPP_KLM       SA<0>  @BASEBOARD_FAB2_LIB.BASEBOARD_FAB2(SCH_1):PVPP_KLM
  146  M_K_VREF       VREFCA  @BASEBOARD_FAB2_LIB.BASEBOARD_FAB2(SCH_1):M_K_VREF
  222  M_K_PAR          PAR  @BASEBOARD_FAB2_LIB.BASEBOARD_FAB2(SCH_1):M_K_PAR
   91  M_K_ODT<3>     ODT<1>  @BASEBOARD_FAB2_LIB.BASEBOARD_FAB2(SCH_1):M_K_ODT<3>
   87  M_K_ODT<2>     ODT<0>  @BASEBOARD_FAB2_LIB.BASEBOARD_FAB2(SCH_1):M_K_ODT<2>
   66  M_K_MA<9>         A9  @BASEBOARD_FAB2_LIB.BASEBOARD_FAB2(SCH_1):M_K_MA<9>
   68  M_K_MA<8>         A8  @BASEBOARD_FAB2_LIB.BASEBOARD_FAB2(SCH_1):M_K_MA<8>
  211  M_K_MA<7>         A7  @BASEBOARD_FAB2_LIB.BASEBOARD_FAB2(SCH_1):M_K_MA<7>
   69  M_K_MA<6>         A6  @BASEBOARD_FAB2_LIB.BASEBOARD_FAB2(SCH_1):M_K_MA<6>
  213  M_K_MA<5>         A5  @BASEBOARD_FAB2_LIB.BASEBOARD_FAB2(SCH_1):M_K_MA<5>
  214  M_K_MA<4>         A4  @BASEBOARD_FAB2_LIB.BASEBOARD_FAB2(SCH_1):M_K_MA<4>
   71  M_K_MA<3>         A3  @BASEBOARD_FAB2_LIB.BASEBOARD_FAB2(SCH_1):M_K_MA<3>
  216  M_K_MA<2>         A2  @BASEBOARD_FAB2_LIB.BASEBOARD_FAB2(SCH_1):M_K_MA<2>
   72  M_K_MA<1>         A1  @BASEBOARD_FAB2_LIB.BASEBOARD_FAB2(SCH_1):M_K_MA<1>
  234  M_K_MA<17>       A17  @BASEBOARD_FAB2_LIB.BASEBOARD_FAB2(SCH_1):M_K_MA<17>
   82  M_K_MA<16>     A16_RAS_N  @BASEBOARD_FAB2_LIB.BASEBOARD_FAB2(SCH_1):M_K_MA<16>
   86  M_K_MA<15>     A15_CAS_N  @BASEBOARD_FAB2_LIB.BASEBOARD_FAB2(SCH_1):M_K_MA<15>
  228  M_K_MA<14>     A14_WE_N  @BASEBOARD_FAB2_LIB.BASEBOARD_FAB2(SCH_1):M_K_MA<14>
  232  M_K_MA<13>       A13  @BASEBOARD_FAB2_LIB.BASEBOARD_FAB2(SCH_1):M_K_MA<13>
   65  M_K_MA<12>       A12  @BASEBOARD_FAB2_LIB.BASEBOARD_FAB2(SCH_1):M_K_MA<12>
  210  M_K_MA<11>       A11  @BASEBOARD_FAB2_LIB.BASEBOARD_FAB2(SCH_1):M_K_MA<11>
  225  M_K_MA<10>       A10  @BASEBOARD_FAB2_LIB.BASEBOARD_FAB2(SCH_1):M_K_MA<10>
   79  M_K_MA<0>         A0  @BASEBOARD_FAB2_LIB.BASEBOARD_FAB2(SCH_1):M_K_MA<0>
  199  M_K_ECC<7>     CB<7>  @BASEBOARD_FAB2_LIB.BASEBOARD_FAB2(SCH_1):M_K_ECC<7>
   54  M_K_ECC<6>     CB<6>  @BASEBOARD_FAB2_LIB.BASEBOARD_FAB2(SCH_1):M_K_ECC<6>
  192  M_K_ECC<5>     CB<5>  @BASEBOARD_FAB2_LIB.BASEBOARD_FAB2(SCH_1):M_K_ECC<5>
   47  M_K_ECC<4>     CB<4>  @BASEBOARD_FAB2_LIB.BASEBOARD_FAB2(SCH_1):M_K_ECC<4>
  201  M_K_ECC<3>     CB<3>  @BASEBOARD_FAB2_LIB.BASEBOARD_FAB2(SCH_1):M_K_ECC<3>
   56  M_K_ECC<2>     CB<2>  @BASEBOARD_FAB2_LIB.BASEBOARD_FAB2(SCH_1):M_K_ECC<2>
  194  M_K_ECC<1>     CB<1>  @BASEBOARD_FAB2_LIB.BASEBOARD_FAB2(SCH_1):M_K_ECC<1>
   49  M_K_ECC<0>     CB<0>  @BASEBOARD_FAB2_LIB.BASEBOARD_FAB2(SCH_1):M_K_ECC<0>
  161  M_K_DQ<9>      DQ<9>  @BASEBOARD_FAB2_LIB.BASEBOARD_FAB2(SCH_1):M_K_DQ<9>
   16  M_K_DQ<8>      DQ<8>  @BASEBOARD_FAB2_LIB.BASEBOARD_FAB2(SCH_1):M_K_DQ<8>
  155  M_K_DQ<7>      DQ<7>  @BASEBOARD_FAB2_LIB.BASEBOARD_FAB2(SCH_1):M_K_DQ<7>
   10  M_K_DQ<6>      DQ<6>  @BASEBOARD_FAB2_LIB.BASEBOARD_FAB2(SCH_1):M_K_DQ<6>
  280  M_K_DQ<63>     DQ<63>  @BASEBOARD_FAB2_LIB.BASEBOARD_FAB2(SCH_1):M_K_DQ<63>
  135  M_K_DQ<62>     DQ<62>  @BASEBOARD_FAB2_LIB.BASEBOARD_FAB2(SCH_1):M_K_DQ<62>
  273  M_K_DQ<61>     DQ<61>  @BASEBOARD_FAB2_LIB.BASEBOARD_FAB2(SCH_1):M_K_DQ<61>
  128  M_K_DQ<60>     DQ<60>  @BASEBOARD_FAB2_LIB.BASEBOARD_FAB2(SCH_1):M_K_DQ<60>
  148  M_K_DQ<5>      DQ<5>  @BASEBOARD_FAB2_LIB.BASEBOARD_FAB2(SCH_1):M_K_DQ<5>
  282  M_K_DQ<59>     DQ<59>  @BASEBOARD_FAB2_LIB.BASEBOARD_FAB2(SCH_1):M_K_DQ<59>
  137  M_K_DQ<58>     DQ<58>  @BASEBOARD_FAB2_LIB.BASEBOARD_FAB2(SCH_1):M_K_DQ<58>
  275  M_K_DQ<57>     DQ<57>  @BASEBOARD_FAB2_LIB.BASEBOARD_FAB2(SCH_1):M_K_DQ<57>
  130  M_K_DQ<56>     DQ<56>  @BASEBOARD_FAB2_LIB.BASEBOARD_FAB2(SCH_1):M_K_DQ<56>
  269  M_K_DQ<55>     DQ<55>  @BASEBOARD_FAB2_LIB.BASEBOARD_FAB2(SCH_1):M_K_DQ<55>
  124  M_K_DQ<54>     DQ<54>  @BASEBOARD_FAB2_LIB.BASEBOARD_FAB2(SCH_1):M_K_DQ<54>
  262  M_K_DQ<53>     DQ<53>  @BASEBOARD_FAB2_LIB.BASEBOARD_FAB2(SCH_1):M_K_DQ<53>
  117  M_K_DQ<52>     DQ<52>  @BASEBOARD_FAB2_LIB.BASEBOARD_FAB2(SCH_1):M_K_DQ<52>
  271  M_K_DQ<51>     DQ<51>  @BASEBOARD_FAB2_LIB.BASEBOARD_FAB2(SCH_1):M_K_DQ<51>
  126  M_K_DQ<50>     DQ<50>  @BASEBOARD_FAB2_LIB.BASEBOARD_FAB2(SCH_1):M_K_DQ<50>
    3  M_K_DQ<4>      DQ<4>  @BASEBOARD_FAB2_LIB.BASEBOARD_FAB2(SCH_1):M_K_DQ<4>
  264  M_K_DQ<49>     DQ<49>  @BASEBOARD_FAB2_LIB.BASEBOARD_FAB2(SCH_1):M_K_DQ<49>
  119  M_K_DQ<48>     DQ<48>  @BASEBOARD_FAB2_LIB.BASEBOARD_FAB2(SCH_1):M_K_DQ<48>
  258  M_K_DQ<47>     DQ<47>  @BASEBOARD_FAB2_LIB.BASEBOARD_FAB2(SCH_1):M_K_DQ<47>
  113  M_K_DQ<46>     DQ<46>  @BASEBOARD_FAB2_LIB.BASEBOARD_FAB2(SCH_1):M_K_DQ<46>
  251  M_K_DQ<45>     DQ<45>  @BASEBOARD_FAB2_LIB.BASEBOARD_FAB2(SCH_1):M_K_DQ<45>
  106  M_K_DQ<44>     DQ<44>  @BASEBOARD_FAB2_LIB.BASEBOARD_FAB2(SCH_1):M_K_DQ<44>
  260  M_K_DQ<43>     DQ<43>  @BASEBOARD_FAB2_LIB.BASEBOARD_FAB2(SCH_1):M_K_DQ<43>
  115  M_K_DQ<42>     DQ<42>  @BASEBOARD_FAB2_LIB.BASEBOARD_FAB2(SCH_1):M_K_DQ<42>
  253  M_K_DQ<41>     DQ<41>  @BASEBOARD_FAB2_LIB.BASEBOARD_FAB2(SCH_1):M_K_DQ<41>
  108  M_K_DQ<40>     DQ<40>  @BASEBOARD_FAB2_LIB.BASEBOARD_FAB2(SCH_1):M_K_DQ<40>
  157  M_K_DQ<3>      DQ<3>  @BASEBOARD_FAB2_LIB.BASEBOARD_FAB2(SCH_1):M_K_DQ<3>
  247  M_K_DQ<39>     DQ<39>  @BASEBOARD_FAB2_LIB.BASEBOARD_FAB2(SCH_1):M_K_DQ<39>
  102  M_K_DQ<38>     DQ<38>  @BASEBOARD_FAB2_LIB.BASEBOARD_FAB2(SCH_1):M_K_DQ<38>
  240  M_K_DQ<37>     DQ<37>  @BASEBOARD_FAB2_LIB.BASEBOARD_FAB2(SCH_1):M_K_DQ<37>
   95  M_K_DQ<36>     DQ<36>  @BASEBOARD_FAB2_LIB.BASEBOARD_FAB2(SCH_1):M_K_DQ<36>
  249  M_K_DQ<35>     DQ<35>  @BASEBOARD_FAB2_LIB.BASEBOARD_FAB2(SCH_1):M_K_DQ<35>
  104  M_K_DQ<34>     DQ<34>  @BASEBOARD_FAB2_LIB.BASEBOARD_FAB2(SCH_1):M_K_DQ<34>
  242  M_K_DQ<33>     DQ<33>  @BASEBOARD_FAB2_LIB.BASEBOARD_FAB2(SCH_1):M_K_DQ<33>
   97  M_K_DQ<32>     DQ<32>  @BASEBOARD_FAB2_LIB.BASEBOARD_FAB2(SCH_1):M_K_DQ<32>
  188  M_K_DQ<31>     DQ<31>  @BASEBOARD_FAB2_LIB.BASEBOARD_FAB2(SCH_1):M_K_DQ<31>
   43  M_K_DQ<30>     DQ<30>  @BASEBOARD_FAB2_LIB.BASEBOARD_FAB2(SCH_1):M_K_DQ<30>
   12  M_K_DQ<2>      DQ<2>  @BASEBOARD_FAB2_LIB.BASEBOARD_FAB2(SCH_1):M_K_DQ<2>
  181  M_K_DQ<29>     DQ<29>  @BASEBOARD_FAB2_LIB.BASEBOARD_FAB2(SCH_1):M_K_DQ<29>
   36  M_K_DQ<28>     DQ<28>  @BASEBOARD_FAB2_LIB.BASEBOARD_FAB2(SCH_1):M_K_DQ<28>
  190  M_K_DQ<27>     DQ<27>  @BASEBOARD_FAB2_LIB.BASEBOARD_FAB2(SCH_1):M_K_DQ<27>
   45  M_K_DQ<26>     DQ<26>  @BASEBOARD_FAB2_LIB.BASEBOARD_FAB2(SCH_1):M_K_DQ<26>
  183  M_K_DQ<25>     DQ<25>  @BASEBOARD_FAB2_LIB.BASEBOARD_FAB2(SCH_1):M_K_DQ<25>
   38  M_K_DQ<24>     DQ<24>  @BASEBOARD_FAB2_LIB.BASEBOARD_FAB2(SCH_1):M_K_DQ<24>
  177  M_K_DQ<23>     DQ<23>  @BASEBOARD_FAB2_LIB.BASEBOARD_FAB2(SCH_1):M_K_DQ<23>
   32  M_K_DQ<22>     DQ<22>  @BASEBOARD_FAB2_LIB.BASEBOARD_FAB2(SCH_1):M_K_DQ<22>
  170  M_K_DQ<21>     DQ<21>  @BASEBOARD_FAB2_LIB.BASEBOARD_FAB2(SCH_1):M_K_DQ<21>
   25  M_K_DQ<20>     DQ<20>  @BASEBOARD_FAB2_LIB.BASEBOARD_FAB2(SCH_1):M_K_DQ<20>
  150  M_K_DQ<1>      DQ<1>  @BASEBOARD_FAB2_LIB.BASEBOARD_FAB2(SCH_1):M_K_DQ<1>
  179  M_K_DQ<19>     DQ<19>  @BASEBOARD_FAB2_LIB.BASEBOARD_FAB2(SCH_1):M_K_DQ<19>
   34  M_K_DQ<18>     DQ<18>  @BASEBOARD_FAB2_LIB.BASEBOARD_FAB2(SCH_1):M_K_DQ<18>
  172  M_K_DQ<17>     DQ<17>  @BASEBOARD_FAB2_LIB.BASEBOARD_FAB2(SCH_1):M_K_DQ<17>
   27  M_K_DQ<16>     DQ<16>  @BASEBOARD_FAB2_LIB.BASEBOARD_FAB2(SCH_1):M_K_DQ<16>
  166  M_K_DQ<15>     DQ<15>  @BASEBOARD_FAB2_LIB.BASEBOARD_FAB2(SCH_1):M_K_DQ<15>
   21  M_K_DQ<14>     DQ<14>  @BASEBOARD_FAB2_LIB.BASEBOARD_FAB2(SCH_1):M_K_DQ<14>
  159  M_K_DQ<13>     DQ<13>  @BASEBOARD_FAB2_LIB.BASEBOARD_FAB2(SCH_1):M_K_DQ<13>
   14  M_K_DQ<12>     DQ<12>  @BASEBOARD_FAB2_LIB.BASEBOARD_FAB2(SCH_1):M_K_DQ<12>
  168  M_K_DQ<11>     DQ<11>  @BASEBOARD_FAB2_LIB.BASEBOARD_FAB2(SCH_1):M_K_DQ<11>
   23  M_K_DQ<10>     DQ<10>  @BASEBOARD_FAB2_LIB.BASEBOARD_FAB2(SCH_1):M_K_DQ<10>
    5  M_K_DQ<0>      DQ<0>  @BASEBOARD_FAB2_LIB.BASEBOARD_FAB2(SCH_1):M_K_DQ<0>
  237  M_K_CS_N<7>    S3_N_C<1>  @BASEBOARD_FAB2_LIB.BASEBOARD_FAB2(SCH_1):M_K_CS_N<7>
   93  M_K_CS_N<6>    S2_N_C<0>  @BASEBOARD_FAB2_LIB.BASEBOARD_FAB2(SCH_1):M_K_CS_N<6>
   89  M_K_CS_N<5>     S1_N  @BASEBOARD_FAB2_LIB.BASEBOARD_FAB2(SCH_1):M_K_CS_N<5>
   84  M_K_CS_N<4>     S0_N  @BASEBOARD_FAB2_LIB.BASEBOARD_FAB2(SCH_1):M_K_CS_N<4>
  218  M_K_CLK_DP<3>   CK1P  @BASEBOARD_FAB2_LIB.BASEBOARD_FAB2(SCH_1):M_K_CLK_DP<3>
   74  M_K_CLK_DP<2>   CK0P  @BASEBOARD_FAB2_LIB.BASEBOARD_FAB2(SCH_1):M_K_CLK_DP<2>
  219  M_K_CLK_DN<3>   CK1N  @BASEBOARD_FAB2_LIB.BASEBOARD_FAB2(SCH_1):M_K_CLK_DN<3>
   75  M_K_CLK_DN<2>   CK0N  @BASEBOARD_FAB2_LIB.BASEBOARD_FAB2(SCH_1):M_K_CLK_DN<2>
  203  M_K_CKE<3>     CKE<1>  @BASEBOARD_FAB2_LIB.BASEBOARD_FAB2(SCH_1):M_K_CKE<3>
   60  M_K_CKE<2>     CKE<0>  @BASEBOARD_FAB2_LIB.BASEBOARD_FAB2(SCH_1):M_K_CKE<2>
  235  M_K_C<2>        C<2>  @BASEBOARD_FAB2_LIB.BASEBOARD_FAB2(SCH_1):M_K_C<2>
  207  M_K_BG<1>      BG<1>  @BASEBOARD_FAB2_LIB.BASEBOARD_FAB2(SCH_1):M_K_BG<1>
   63  M_K_BG<0>      BG<0>  @BASEBOARD_FAB2_LIB.BASEBOARD_FAB2(SCH_1):M_K_BG<0>
  224  M_K_BA<1>      BA<1>  @BASEBOARD_FAB2_LIB.BASEBOARD_FAB2(SCH_1):M_K_BA<1>
   81  M_K_BA<0>      BA<0>  @BASEBOARD_FAB2_LIB.BASEBOARD_FAB2(SCH_1):M_K_BA<0>
  208  M_K_ALERT_N    ALERT_N  @BASEBOARD_FAB2_LIB.BASEBOARD_FAB2(SCH_1):M_K_ALERT_N
   62  M_K_ACT_N      ACT_N  @BASEBOARD_FAB2_LIB.BASEBOARD_FAB2(SCH_1):M_K_ACT_N
   58  M_KLM_RST_N    RESET_N  @BASEBOARD_FAB2_LIB.BASEBOARD_FAB2(SCH_1):M_KLM_RST_N
  238  GND            SA<2>  @BASEBOARD_FAB2_LIB.BASEBOARD_FAB2(SCH_1):GND
  140  GND            SA<1>  @BASEBOARD_FAB2_LIB.BASEBOARD_FAB2(SCH_1):GND
   78  FM_DIMM_EVENT_COD_N  EVENT_N  @BASEBOARD_FAB2_LIB.BASEBOARD_FAB2(SCH_1):FM_DIMM_EVENT_COD_N
  230  FM_ADR_COMPLETE_KLM_N  SAVE_N_NC  @BASEBOARD_FAB2_LIB.BASEBOARD_FAB2(SCH_1):FM_ADR_COMPLETE_KLM_N

SCONN288_H44441003_PIP  I75  J9T1   [SCONN288_H44441003_PIP-SCONN,HA]
   77  PVTT_GHJ       VTT<1>  @BASEBOARD_FAB2_LIB.BASEBOARD_FAB2(SCH_1):PVTT_GHJ
  221  PVTT_GHJ       VTT<0>  @BASEBOARD_FAB2_LIB.BASEBOARD_FAB2(SCH_1):PVTT_GHJ
  142  PVPP_GHJ       VPP<4>  @BASEBOARD_FAB2_LIB.BASEBOARD_FAB2(SCH_1):PVPP_GHJ
  143  PVPP_GHJ       VPP<3>  @BASEBOARD_FAB2_LIB.BASEBOARD_FAB2(SCH_1):PVPP_GHJ
  288  PVPP_GHJ       VPP<2>  @BASEBOARD_FAB2_LIB.BASEBOARD_FAB2(SCH_1):PVPP_GHJ
  286  PVPP_GHJ       VPP<1>  @BASEBOARD_FAB2_LIB.BASEBOARD_FAB2(SCH_1):PVPP_GHJ
  287  PVPP_GHJ       VPP<0>  @BASEBOARD_FAB2_LIB.BASEBOARD_FAB2(SCH_1):PVPP_GHJ
   59  PVDDQ_GHJ      VDD<25>  @BASEBOARD_FAB2_LIB.BASEBOARD_FAB2(SCH_1):PVDDQ_GHJ
   61  PVDDQ_GHJ      VDD<24>  @BASEBOARD_FAB2_LIB.BASEBOARD_FAB2(SCH_1):PVDDQ_GHJ
   64  PVDDQ_GHJ      VDD<23>  @BASEBOARD_FAB2_LIB.BASEBOARD_FAB2(SCH_1):PVDDQ_GHJ
   67  PVDDQ_GHJ      VDD<22>  @BASEBOARD_FAB2_LIB.BASEBOARD_FAB2(SCH_1):PVDDQ_GHJ
   70  PVDDQ_GHJ      VDD<21>  @BASEBOARD_FAB2_LIB.BASEBOARD_FAB2(SCH_1):PVDDQ_GHJ
   73  PVDDQ_GHJ      VDD<20>  @BASEBOARD_FAB2_LIB.BASEBOARD_FAB2(SCH_1):PVDDQ_GHJ
   76  PVDDQ_GHJ      VDD<19>  @BASEBOARD_FAB2_LIB.BASEBOARD_FAB2(SCH_1):PVDDQ_GHJ
   80  PVDDQ_GHJ      VDD<18>  @BASEBOARD_FAB2_LIB.BASEBOARD_FAB2(SCH_1):PVDDQ_GHJ
   83  PVDDQ_GHJ      VDD<17>  @BASEBOARD_FAB2_LIB.BASEBOARD_FAB2(SCH_1):PVDDQ_GHJ
   85  PVDDQ_GHJ      VDD<16>  @BASEBOARD_FAB2_LIB.BASEBOARD_FAB2(SCH_1):PVDDQ_GHJ
   88  PVDDQ_GHJ      VDD<15>  @BASEBOARD_FAB2_LIB.BASEBOARD_FAB2(SCH_1):PVDDQ_GHJ
   90  PVDDQ_GHJ      VDD<14>  @BASEBOARD_FAB2_LIB.BASEBOARD_FAB2(SCH_1):PVDDQ_GHJ
   92  PVDDQ_GHJ      VDD<13>  @BASEBOARD_FAB2_LIB.BASEBOARD_FAB2(SCH_1):PVDDQ_GHJ
  204  PVDDQ_GHJ      VDD<12>  @BASEBOARD_FAB2_LIB.BASEBOARD_FAB2(SCH_1):PVDDQ_GHJ
  206  PVDDQ_GHJ      VDD<11>  @BASEBOARD_FAB2_LIB.BASEBOARD_FAB2(SCH_1):PVDDQ_GHJ
  209  PVDDQ_GHJ      VDD<10>  @BASEBOARD_FAB2_LIB.BASEBOARD_FAB2(SCH_1):PVDDQ_GHJ
  212  PVDDQ_GHJ      VDD<9>  @BASEBOARD_FAB2_LIB.BASEBOARD_FAB2(SCH_1):PVDDQ_GHJ
  215  PVDDQ_GHJ      VDD<8>  @BASEBOARD_FAB2_LIB.BASEBOARD_FAB2(SCH_1):PVDDQ_GHJ
  217  PVDDQ_GHJ      VDD<7>  @BASEBOARD_FAB2_LIB.BASEBOARD_FAB2(SCH_1):PVDDQ_GHJ
  220  PVDDQ_GHJ      VDD<6>  @BASEBOARD_FAB2_LIB.BASEBOARD_FAB2(SCH_1):PVDDQ_GHJ
  223  PVDDQ_GHJ      VDD<5>  @BASEBOARD_FAB2_LIB.BASEBOARD_FAB2(SCH_1):PVDDQ_GHJ
  226  PVDDQ_GHJ      VDD<4>  @BASEBOARD_FAB2_LIB.BASEBOARD_FAB2(SCH_1):PVDDQ_GHJ
  229  PVDDQ_GHJ      VDD<3>  @BASEBOARD_FAB2_LIB.BASEBOARD_FAB2(SCH_1):PVDDQ_GHJ
  231  PVDDQ_GHJ      VDD<2>  @BASEBOARD_FAB2_LIB.BASEBOARD_FAB2(SCH_1):PVDDQ_GHJ
  233  PVDDQ_GHJ      VDD<1>  @BASEBOARD_FAB2_LIB.BASEBOARD_FAB2(SCH_1):PVDDQ_GHJ
  236  PVDDQ_GHJ      VDD<0>  @BASEBOARD_FAB2_LIB.BASEBOARD_FAB2(SCH_1):PVDDQ_GHJ
    1  P12V_NVDIMM_GHJ  12V<1>  @BASEBOARD_FAB2_LIB.BASEBOARD_FAB2(SCH_1):P12V_NVDIMM_GHJ
  145  P12V_NVDIMM_GHJ  12V<0>  @BASEBOARD_FAB2_LIB.BASEBOARD_FAB2(SCH_1):P12V_NVDIMM_GHJ

SCONN288_H44441003_PIP  I144  J9T1   [SCONN288_H44441003_PIP-SCONN,HA]
    2  GND            VSS<93>  @BASEBOARD_FAB2_LIB.BASEBOARD_FAB2(SCH_1):GND
    4  GND            VSS<92>  @BASEBOARD_FAB2_LIB.BASEBOARD_FAB2(SCH_1):GND
    6  GND            VSS<91>  @BASEBOARD_FAB2_LIB.BASEBOARD_FAB2(SCH_1):GND
    9  GND            VSS<90>  @BASEBOARD_FAB2_LIB.BASEBOARD_FAB2(SCH_1):GND
   11  GND            VSS<89>  @BASEBOARD_FAB2_LIB.BASEBOARD_FAB2(SCH_1):GND
   13  GND            VSS<88>  @BASEBOARD_FAB2_LIB.BASEBOARD_FAB2(SCH_1):GND
   15  GND            VSS<87>  @BASEBOARD_FAB2_LIB.BASEBOARD_FAB2(SCH_1):GND
   17  GND            VSS<86>  @BASEBOARD_FAB2_LIB.BASEBOARD_FAB2(SCH_1):GND
   20  GND            VSS<85>  @BASEBOARD_FAB2_LIB.BASEBOARD_FAB2(SCH_1):GND
   22  GND            VSS<84>  @BASEBOARD_FAB2_LIB.BASEBOARD_FAB2(SCH_1):GND
   24  GND            VSS<83>  @BASEBOARD_FAB2_LIB.BASEBOARD_FAB2(SCH_1):GND
   26  GND            VSS<82>  @BASEBOARD_FAB2_LIB.BASEBOARD_FAB2(SCH_1):GND
   28  GND            VSS<81>  @BASEBOARD_FAB2_LIB.BASEBOARD_FAB2(SCH_1):GND
   31  GND            VSS<80>  @BASEBOARD_FAB2_LIB.BASEBOARD_FAB2(SCH_1):GND
   33  GND            VSS<79>  @BASEBOARD_FAB2_LIB.BASEBOARD_FAB2(SCH_1):GND
   35  GND            VSS<78>  @BASEBOARD_FAB2_LIB.BASEBOARD_FAB2(SCH_1):GND
   37  GND            VSS<77>  @BASEBOARD_FAB2_LIB.BASEBOARD_FAB2(SCH_1):GND
   39  GND            VSS<76>  @BASEBOARD_FAB2_LIB.BASEBOARD_FAB2(SCH_1):GND
   42  GND            VSS<75>  @BASEBOARD_FAB2_LIB.BASEBOARD_FAB2(SCH_1):GND
   44  GND            VSS<74>  @BASEBOARD_FAB2_LIB.BASEBOARD_FAB2(SCH_1):GND
   46  GND            VSS<73>  @BASEBOARD_FAB2_LIB.BASEBOARD_FAB2(SCH_1):GND
   48  GND            VSS<72>  @BASEBOARD_FAB2_LIB.BASEBOARD_FAB2(SCH_1):GND
   50  GND            VSS<71>  @BASEBOARD_FAB2_LIB.BASEBOARD_FAB2(SCH_1):GND
   53  GND            VSS<70>  @BASEBOARD_FAB2_LIB.BASEBOARD_FAB2(SCH_1):GND
   55  GND            VSS<69>  @BASEBOARD_FAB2_LIB.BASEBOARD_FAB2(SCH_1):GND
   57  GND            VSS<68>  @BASEBOARD_FAB2_LIB.BASEBOARD_FAB2(SCH_1):GND
   94  GND            VSS<67>  @BASEBOARD_FAB2_LIB.BASEBOARD_FAB2(SCH_1):GND
   96  GND            VSS<66>  @BASEBOARD_FAB2_LIB.BASEBOARD_FAB2(SCH_1):GND
   98  GND            VSS<65>  @BASEBOARD_FAB2_LIB.BASEBOARD_FAB2(SCH_1):GND
  101  GND            VSS<64>  @BASEBOARD_FAB2_LIB.BASEBOARD_FAB2(SCH_1):GND
  103  GND            VSS<63>  @BASEBOARD_FAB2_LIB.BASEBOARD_FAB2(SCH_1):GND
  105  GND            VSS<62>  @BASEBOARD_FAB2_LIB.BASEBOARD_FAB2(SCH_1):GND
  107  GND            VSS<61>  @BASEBOARD_FAB2_LIB.BASEBOARD_FAB2(SCH_1):GND
  109  GND            VSS<60>  @BASEBOARD_FAB2_LIB.BASEBOARD_FAB2(SCH_1):GND
  112  GND            VSS<59>  @BASEBOARD_FAB2_LIB.BASEBOARD_FAB2(SCH_1):GND
  114  GND            VSS<58>  @BASEBOARD_FAB2_LIB.BASEBOARD_FAB2(SCH_1):GND
  116  GND            VSS<57>  @BASEBOARD_FAB2_LIB.BASEBOARD_FAB2(SCH_1):GND
  118  GND            VSS<56>  @BASEBOARD_FAB2_LIB.BASEBOARD_FAB2(SCH_1):GND
  120  GND            VSS<55>  @BASEBOARD_FAB2_LIB.BASEBOARD_FAB2(SCH_1):GND
  123  GND            VSS<54>  @BASEBOARD_FAB2_LIB.BASEBOARD_FAB2(SCH_1):GND
  125  GND            VSS<53>  @BASEBOARD_FAB2_LIB.BASEBOARD_FAB2(SCH_1):GND
  127  GND            VSS<52>  @BASEBOARD_FAB2_LIB.BASEBOARD_FAB2(SCH_1):GND
  129  GND            VSS<51>  @BASEBOARD_FAB2_LIB.BASEBOARD_FAB2(SCH_1):GND
  131  GND            VSS<50>  @BASEBOARD_FAB2_LIB.BASEBOARD_FAB2(SCH_1):GND
  134  GND            VSS<49>  @BASEBOARD_FAB2_LIB.BASEBOARD_FAB2(SCH_1):GND
  136  GND            VSS<48>  @BASEBOARD_FAB2_LIB.BASEBOARD_FAB2(SCH_1):GND
  138  GND            VSS<47>  @BASEBOARD_FAB2_LIB.BASEBOARD_FAB2(SCH_1):GND
  147  GND            VSS<46>  @BASEBOARD_FAB2_LIB.BASEBOARD_FAB2(SCH_1):GND
  149  GND            VSS<45>  @BASEBOARD_FAB2_LIB.BASEBOARD_FAB2(SCH_1):GND
  151  GND            VSS<44>  @BASEBOARD_FAB2_LIB.BASEBOARD_FAB2(SCH_1):GND
  154  GND            VSS<43>  @BASEBOARD_FAB2_LIB.BASEBOARD_FAB2(SCH_1):GND
  156  GND            VSS<42>  @BASEBOARD_FAB2_LIB.BASEBOARD_FAB2(SCH_1):GND
  158  GND            VSS<41>  @BASEBOARD_FAB2_LIB.BASEBOARD_FAB2(SCH_1):GND
  160  GND            VSS<40>  @BASEBOARD_FAB2_LIB.BASEBOARD_FAB2(SCH_1):GND
  162  GND            VSS<39>  @BASEBOARD_FAB2_LIB.BASEBOARD_FAB2(SCH_1):GND
  165  GND            VSS<38>  @BASEBOARD_FAB2_LIB.BASEBOARD_FAB2(SCH_1):GND
  167  GND            VSS<37>  @BASEBOARD_FAB2_LIB.BASEBOARD_FAB2(SCH_1):GND
  169  GND            VSS<36>  @BASEBOARD_FAB2_LIB.BASEBOARD_FAB2(SCH_1):GND
  171  GND            VSS<35>  @BASEBOARD_FAB2_LIB.BASEBOARD_FAB2(SCH_1):GND
  173  GND            VSS<34>  @BASEBOARD_FAB2_LIB.BASEBOARD_FAB2(SCH_1):GND
  176  GND            VSS<33>  @BASEBOARD_FAB2_LIB.BASEBOARD_FAB2(SCH_1):GND
  178  GND            VSS<32>  @BASEBOARD_FAB2_LIB.BASEBOARD_FAB2(SCH_1):GND
  180  GND            VSS<31>  @BASEBOARD_FAB2_LIB.BASEBOARD_FAB2(SCH_1):GND
  182  GND            VSS<30>  @BASEBOARD_FAB2_LIB.BASEBOARD_FAB2(SCH_1):GND
  184  GND            VSS<29>  @BASEBOARD_FAB2_LIB.BASEBOARD_FAB2(SCH_1):GND
  187  GND            VSS<28>  @BASEBOARD_FAB2_LIB.BASEBOARD_FAB2(SCH_1):GND
  189  GND            VSS<27>  @BASEBOARD_FAB2_LIB.BASEBOARD_FAB2(SCH_1):GND
  191  GND            VSS<26>  @BASEBOARD_FAB2_LIB.BASEBOARD_FAB2(SCH_1):GND
  193  GND            VSS<25>  @BASEBOARD_FAB2_LIB.BASEBOARD_FAB2(SCH_1):GND
  195  GND            VSS<24>  @BASEBOARD_FAB2_LIB.BASEBOARD_FAB2(SCH_1):GND
  198  GND            VSS<23>  @BASEBOARD_FAB2_LIB.BASEBOARD_FAB2(SCH_1):GND
  200  GND            VSS<22>  @BASEBOARD_FAB2_LIB.BASEBOARD_FAB2(SCH_1):GND
  202  GND            VSS<21>  @BASEBOARD_FAB2_LIB.BASEBOARD_FAB2(SCH_1):GND
  239  GND            VSS<20>  @BASEBOARD_FAB2_LIB.BASEBOARD_FAB2(SCH_1):GND
  241  GND            VSS<19>  @BASEBOARD_FAB2_LIB.BASEBOARD_FAB2(SCH_1):GND
  243  GND            VSS<18>  @BASEBOARD_FAB2_LIB.BASEBOARD_FAB2(SCH_1):GND
  246  GND            VSS<17>  @BASEBOARD_FAB2_LIB.BASEBOARD_FAB2(SCH_1):GND
  248  GND            VSS<16>  @BASEBOARD_FAB2_LIB.BASEBOARD_FAB2(SCH_1):GND
  250  GND            VSS<15>  @BASEBOARD_FAB2_LIB.BASEBOARD_FAB2(SCH_1):GND
  252  GND            VSS<14>  @BASEBOARD_FAB2_LIB.BASEBOARD_FAB2(SCH_1):GND
  254  GND            VSS<13>  @BASEBOARD_FAB2_LIB.BASEBOARD_FAB2(SCH_1):GND
  257  GND            VSS<12>  @BASEBOARD_FAB2_LIB.BASEBOARD_FAB2(SCH_1):GND
  259  GND            VSS<11>  @BASEBOARD_FAB2_LIB.BASEBOARD_FAB2(SCH_1):GND
  261  GND            VSS<10>  @BASEBOARD_FAB2_LIB.BASEBOARD_FAB2(SCH_1):GND
  263  GND            VSS<9>  @BASEBOARD_FAB2_LIB.BASEBOARD_FAB2(SCH_1):GND
  265  GND            VSS<8>  @BASEBOARD_FAB2_LIB.BASEBOARD_FAB2(SCH_1):GND
  268  GND            VSS<7>  @BASEBOARD_FAB2_LIB.BASEBOARD_FAB2(SCH_1):GND
  270  GND            VSS<6>  @BASEBOARD_FAB2_LIB.BASEBOARD_FAB2(SCH_1):GND
  272  GND            VSS<5>  @BASEBOARD_FAB2_LIB.BASEBOARD_FAB2(SCH_1):GND
  274  GND            VSS<4>  @BASEBOARD_FAB2_LIB.BASEBOARD_FAB2(SCH_1):GND
  276  GND            VSS<3>  @BASEBOARD_FAB2_LIB.BASEBOARD_FAB2(SCH_1):GND
  279  GND            VSS<2>  @BASEBOARD_FAB2_LIB.BASEBOARD_FAB2(SCH_1):GND
  281  GND            VSS<1>  @BASEBOARD_FAB2_LIB.BASEBOARD_FAB2(SCH_1):GND
  283  GND            VSS<0>  @BASEBOARD_FAB2_LIB.BASEBOARD_FAB2(SCH_1):GND

SCONN288_H44441003_PIP  I120  J9T1   [SCONN288_H44441003_PIP-SCONN,HA]
    7  M_G_DQS_DP<9>  DQS9P  @BASEBOARD_FAB2_LIB.BASEBOARD_FAB2(SCH_1):M_G_DQS_DP<9>
  197  M_G_DQS_DP<8>  DQS8P  @BASEBOARD_FAB2_LIB.BASEBOARD_FAB2(SCH_1):M_G_DQS_DP<8>
  278  M_G_DQS_DP<7>  DQS7P  @BASEBOARD_FAB2_LIB.BASEBOARD_FAB2(SCH_1):M_G_DQS_DP<7>
  267  M_G_DQS_DP<6>  DQS6P  @BASEBOARD_FAB2_LIB.BASEBOARD_FAB2(SCH_1):M_G_DQS_DP<6>
  256  M_G_DQS_DP<5>  DQS5P  @BASEBOARD_FAB2_LIB.BASEBOARD_FAB2(SCH_1):M_G_DQS_DP<5>
  245  M_G_DQS_DP<4>  DQS4P  @BASEBOARD_FAB2_LIB.BASEBOARD_FAB2(SCH_1):M_G_DQS_DP<4>
  186  M_G_DQS_DP<3>  DQS3P  @BASEBOARD_FAB2_LIB.BASEBOARD_FAB2(SCH_1):M_G_DQS_DP<3>
  175  M_G_DQS_DP<2>  DQS2P  @BASEBOARD_FAB2_LIB.BASEBOARD_FAB2(SCH_1):M_G_DQS_DP<2>
  164  M_G_DQS_DP<1>  DQS1P  @BASEBOARD_FAB2_LIB.BASEBOARD_FAB2(SCH_1):M_G_DQS_DP<1>
   51  M_G_DQS_DP<17>  DQS17P  @BASEBOARD_FAB2_LIB.BASEBOARD_FAB2(SCH_1):M_G_DQS_DP<17>
  132  M_G_DQS_DP<16>  DQS16P  @BASEBOARD_FAB2_LIB.BASEBOARD_FAB2(SCH_1):M_G_DQS_DP<16>
  121  M_G_DQS_DP<15>  DQS15P  @BASEBOARD_FAB2_LIB.BASEBOARD_FAB2(SCH_1):M_G_DQS_DP<15>
  110  M_G_DQS_DP<14>  DQS14P  @BASEBOARD_FAB2_LIB.BASEBOARD_FAB2(SCH_1):M_G_DQS_DP<14>
   99  M_G_DQS_DP<13>  DQS13P  @BASEBOARD_FAB2_LIB.BASEBOARD_FAB2(SCH_1):M_G_DQS_DP<13>
   40  M_G_DQS_DP<12>  DQS12P  @BASEBOARD_FAB2_LIB.BASEBOARD_FAB2(SCH_1):M_G_DQS_DP<12>
   29  M_G_DQS_DP<11>  DQS11P  @BASEBOARD_FAB2_LIB.BASEBOARD_FAB2(SCH_1):M_G_DQS_DP<11>
   18  M_G_DQS_DP<10>  DQS10P  @BASEBOARD_FAB2_LIB.BASEBOARD_FAB2(SCH_1):M_G_DQS_DP<10>
  153  M_G_DQS_DP<0>  DQS0P  @BASEBOARD_FAB2_LIB.BASEBOARD_FAB2(SCH_1):M_G_DQS_DP<0>
    8  M_G_DQS_DN<9>  DQS9N  @BASEBOARD_FAB2_LIB.BASEBOARD_FAB2(SCH_1):M_G_DQS_DN<9>
  196  M_G_DQS_DN<8>  DQS8N  @BASEBOARD_FAB2_LIB.BASEBOARD_FAB2(SCH_1):M_G_DQS_DN<8>
  277  M_G_DQS_DN<7>  DQS7N  @BASEBOARD_FAB2_LIB.BASEBOARD_FAB2(SCH_1):M_G_DQS_DN<7>
  266  M_G_DQS_DN<6>  DQS6N  @BASEBOARD_FAB2_LIB.BASEBOARD_FAB2(SCH_1):M_G_DQS_DN<6>
  255  M_G_DQS_DN<5>  DQS5N  @BASEBOARD_FAB2_LIB.BASEBOARD_FAB2(SCH_1):M_G_DQS_DN<5>
  244  M_G_DQS_DN<4>  DQS4N  @BASEBOARD_FAB2_LIB.BASEBOARD_FAB2(SCH_1):M_G_DQS_DN<4>
  185  M_G_DQS_DN<3>  DQS3N  @BASEBOARD_FAB2_LIB.BASEBOARD_FAB2(SCH_1):M_G_DQS_DN<3>
  174  M_G_DQS_DN<2>  DQS2N  @BASEBOARD_FAB2_LIB.BASEBOARD_FAB2(SCH_1):M_G_DQS_DN<2>
  163  M_G_DQS_DN<1>  DQS1N  @BASEBOARD_FAB2_LIB.BASEBOARD_FAB2(SCH_1):M_G_DQS_DN<1>
   52  M_G_DQS_DN<17>  DQS17N  @BASEBOARD_FAB2_LIB.BASEBOARD_FAB2(SCH_1):M_G_DQS_DN<17>
  133  M_G_DQS_DN<16>  DQS16N  @BASEBOARD_FAB2_LIB.BASEBOARD_FAB2(SCH_1):M_G_DQS_DN<16>
  122  M_G_DQS_DN<15>  DQS15N  @BASEBOARD_FAB2_LIB.BASEBOARD_FAB2(SCH_1):M_G_DQS_DN<15>
  111  M_G_DQS_DN<14>  DQS14N  @BASEBOARD_FAB2_LIB.BASEBOARD_FAB2(SCH_1):M_G_DQS_DN<14>
  100  M_G_DQS_DN<13>  DQS13N  @BASEBOARD_FAB2_LIB.BASEBOARD_FAB2(SCH_1):M_G_DQS_DN<13>
   41  M_G_DQS_DN<12>  DQS12N  @BASEBOARD_FAB2_LIB.BASEBOARD_FAB2(SCH_1):M_G_DQS_DN<12>
   30  M_G_DQS_DN<11>  DQS11N  @BASEBOARD_FAB2_LIB.BASEBOARD_FAB2(SCH_1):M_G_DQS_DN<11>
   19  M_G_DQS_DN<10>  DQS10N  @BASEBOARD_FAB2_LIB.BASEBOARD_FAB2(SCH_1):M_G_DQS_DN<10>
  152  M_G_DQS_DN<0>  DQS0N  @BASEBOARD_FAB2_LIB.BASEBOARD_FAB2(SCH_1):M_G_DQS_DN<0>

SCONN288_H44441003_PIP  I13  J9T1   [SCONN288_H44441003_PIP-SCONN,HA]
  144  TP_CH_G_DIMM0_RFU_2  RFU<2>  @BASEBOARD_FAB2_LIB.BASEBOARD_FAB2(SCH_1):TP_CH_G_DIMM0_RFU_2
  227  TP_CH_G_DIMM0_RFU_1  RFU<1>  @BASEBOARD_FAB2_LIB.BASEBOARD_FAB2(SCH_1):TP_CH_G_DIMM0_RFU_1
  205  TP_CH_G_DIMM0_RFU_0  RFU<0>  @BASEBOARD_FAB2_LIB.BASEBOARD_FAB2(SCH_1):TP_CH_G_DIMM0_RFU_0
  285  SMB_DDR_GHJ_VPP_SDA    SDA  @BASEBOARD_FAB2_LIB.BASEBOARD_FAB2(SCH_1):SMB_DDR_GHJ_VPP_SDA
  141  SMB_DDR_GHJ_VPP_SCL    SCL  @BASEBOARD_FAB2_LIB.BASEBOARD_FAB2(SCH_1):SMB_DDR_GHJ_VPP_SCL
  284  PVPP_GHJ       VDDSPD  @BASEBOARD_FAB2_LIB.BASEBOARD_FAB2(SCH_1):PVPP_GHJ
  139  PVPP_GHJ       SA<0>  @BASEBOARD_FAB2_LIB.BASEBOARD_FAB2(SCH_1):PVPP_GHJ
  146  M_G_VREF       VREFCA  @BASEBOARD_FAB2_LIB.BASEBOARD_FAB2(SCH_1):M_G_VREF
  222  M_G_PAR          PAR  @BASEBOARD_FAB2_LIB.BASEBOARD_FAB2(SCH_1):M_G_PAR
   91  M_G_ODT<3>     ODT<1>  @BASEBOARD_FAB2_LIB.BASEBOARD_FAB2(SCH_1):M_G_ODT<3>
   87  M_G_ODT<2>     ODT<0>  @BASEBOARD_FAB2_LIB.BASEBOARD_FAB2(SCH_1):M_G_ODT<2>
   66  M_G_MA<9>         A9  @BASEBOARD_FAB2_LIB.BASEBOARD_FAB2(SCH_1):M_G_MA<9>
   68  M_G_MA<8>         A8  @BASEBOARD_FAB2_LIB.BASEBOARD_FAB2(SCH_1):M_G_MA<8>
  211  M_G_MA<7>         A7  @BASEBOARD_FAB2_LIB.BASEBOARD_FAB2(SCH_1):M_G_MA<7>
   69  M_G_MA<6>         A6  @BASEBOARD_FAB2_LIB.BASEBOARD_FAB2(SCH_1):M_G_MA<6>
  213  M_G_MA<5>         A5  @BASEBOARD_FAB2_LIB.BASEBOARD_FAB2(SCH_1):M_G_MA<5>
  214  M_G_MA<4>         A4  @BASEBOARD_FAB2_LIB.BASEBOARD_FAB2(SCH_1):M_G_MA<4>
   71  M_G_MA<3>         A3  @BASEBOARD_FAB2_LIB.BASEBOARD_FAB2(SCH_1):M_G_MA<3>
  216  M_G_MA<2>         A2  @BASEBOARD_FAB2_LIB.BASEBOARD_FAB2(SCH_1):M_G_MA<2>
   72  M_G_MA<1>         A1  @BASEBOARD_FAB2_LIB.BASEBOARD_FAB2(SCH_1):M_G_MA<1>
  234  M_G_MA<17>       A17  @BASEBOARD_FAB2_LIB.BASEBOARD_FAB2(SCH_1):M_G_MA<17>
   82  M_G_MA<16>     A16_RAS_N  @BASEBOARD_FAB2_LIB.BASEBOARD_FAB2(SCH_1):M_G_MA<16>
   86  M_G_MA<15>     A15_CAS_N  @BASEBOARD_FAB2_LIB.BASEBOARD_FAB2(SCH_1):M_G_MA<15>
  228  M_G_MA<14>     A14_WE_N  @BASEBOARD_FAB2_LIB.BASEBOARD_FAB2(SCH_1):M_G_MA<14>
  232  M_G_MA<13>       A13  @BASEBOARD_FAB2_LIB.BASEBOARD_FAB2(SCH_1):M_G_MA<13>
   65  M_G_MA<12>       A12  @BASEBOARD_FAB2_LIB.BASEBOARD_FAB2(SCH_1):M_G_MA<12>
  210  M_G_MA<11>       A11  @BASEBOARD_FAB2_LIB.BASEBOARD_FAB2(SCH_1):M_G_MA<11>
  225  M_G_MA<10>       A10  @BASEBOARD_FAB2_LIB.BASEBOARD_FAB2(SCH_1):M_G_MA<10>
   79  M_G_MA<0>         A0  @BASEBOARD_FAB2_LIB.BASEBOARD_FAB2(SCH_1):M_G_MA<0>
  199  M_G_ECC<7>     CB<7>  @BASEBOARD_FAB2_LIB.BASEBOARD_FAB2(SCH_1):M_G_ECC<7>
   54  M_G_ECC<6>     CB<6>  @BASEBOARD_FAB2_LIB.BASEBOARD_FAB2(SCH_1):M_G_ECC<6>
  192  M_G_ECC<5>     CB<5>  @BASEBOARD_FAB2_LIB.BASEBOARD_FAB2(SCH_1):M_G_ECC<5>
   47  M_G_ECC<4>     CB<4>  @BASEBOARD_FAB2_LIB.BASEBOARD_FAB2(SCH_1):M_G_ECC<4>
  201  M_G_ECC<3>     CB<3>  @BASEBOARD_FAB2_LIB.BASEBOARD_FAB2(SCH_1):M_G_ECC<3>
   56  M_G_ECC<2>     CB<2>  @BASEBOARD_FAB2_LIB.BASEBOARD_FAB2(SCH_1):M_G_ECC<2>
  194  M_G_ECC<1>     CB<1>  @BASEBOARD_FAB2_LIB.BASEBOARD_FAB2(SCH_1):M_G_ECC<1>
   49  M_G_ECC<0>     CB<0>  @BASEBOARD_FAB2_LIB.BASEBOARD_FAB2(SCH_1):M_G_ECC<0>
  161  M_G_DQ<9>      DQ<9>  @BASEBOARD_FAB2_LIB.BASEBOARD_FAB2(SCH_1):M_G_DQ<9>
   16  M_G_DQ<8>      DQ<8>  @BASEBOARD_FAB2_LIB.BASEBOARD_FAB2(SCH_1):M_G_DQ<8>
  155  M_G_DQ<7>      DQ<7>  @BASEBOARD_FAB2_LIB.BASEBOARD_FAB2(SCH_1):M_G_DQ<7>
   10  M_G_DQ<6>      DQ<6>  @BASEBOARD_FAB2_LIB.BASEBOARD_FAB2(SCH_1):M_G_DQ<6>
  280  M_G_DQ<63>     DQ<63>  @BASEBOARD_FAB2_LIB.BASEBOARD_FAB2(SCH_1):M_G_DQ<63>
  135  M_G_DQ<62>     DQ<62>  @BASEBOARD_FAB2_LIB.BASEBOARD_FAB2(SCH_1):M_G_DQ<62>
  273  M_G_DQ<61>     DQ<61>  @BASEBOARD_FAB2_LIB.BASEBOARD_FAB2(SCH_1):M_G_DQ<61>
  128  M_G_DQ<60>     DQ<60>  @BASEBOARD_FAB2_LIB.BASEBOARD_FAB2(SCH_1):M_G_DQ<60>
  148  M_G_DQ<5>      DQ<5>  @BASEBOARD_FAB2_LIB.BASEBOARD_FAB2(SCH_1):M_G_DQ<5>
  282  M_G_DQ<59>     DQ<59>  @BASEBOARD_FAB2_LIB.BASEBOARD_FAB2(SCH_1):M_G_DQ<59>
  137  M_G_DQ<58>     DQ<58>  @BASEBOARD_FAB2_LIB.BASEBOARD_FAB2(SCH_1):M_G_DQ<58>
  275  M_G_DQ<57>     DQ<57>  @BASEBOARD_FAB2_LIB.BASEBOARD_FAB2(SCH_1):M_G_DQ<57>
  130  M_G_DQ<56>     DQ<56>  @BASEBOARD_FAB2_LIB.BASEBOARD_FAB2(SCH_1):M_G_DQ<56>
  269  M_G_DQ<55>     DQ<55>  @BASEBOARD_FAB2_LIB.BASEBOARD_FAB2(SCH_1):M_G_DQ<55>
  124  M_G_DQ<54>     DQ<54>  @BASEBOARD_FAB2_LIB.BASEBOARD_FAB2(SCH_1):M_G_DQ<54>
  262  M_G_DQ<53>     DQ<53>  @BASEBOARD_FAB2_LIB.BASEBOARD_FAB2(SCH_1):M_G_DQ<53>
  117  M_G_DQ<52>     DQ<52>  @BASEBOARD_FAB2_LIB.BASEBOARD_FAB2(SCH_1):M_G_DQ<52>
  271  M_G_DQ<51>     DQ<51>  @BASEBOARD_FAB2_LIB.BASEBOARD_FAB2(SCH_1):M_G_DQ<51>
  126  M_G_DQ<50>     DQ<50>  @BASEBOARD_FAB2_LIB.BASEBOARD_FAB2(SCH_1):M_G_DQ<50>
    3  M_G_DQ<4>      DQ<4>  @BASEBOARD_FAB2_LIB.BASEBOARD_FAB2(SCH_1):M_G_DQ<4>
  264  M_G_DQ<49>     DQ<49>  @BASEBOARD_FAB2_LIB.BASEBOARD_FAB2(SCH_1):M_G_DQ<49>
  119  M_G_DQ<48>     DQ<48>  @BASEBOARD_FAB2_LIB.BASEBOARD_FAB2(SCH_1):M_G_DQ<48>
  258  M_G_DQ<47>     DQ<47>  @BASEBOARD_FAB2_LIB.BASEBOARD_FAB2(SCH_1):M_G_DQ<47>
  113  M_G_DQ<46>     DQ<46>  @BASEBOARD_FAB2_LIB.BASEBOARD_FAB2(SCH_1):M_G_DQ<46>
  251  M_G_DQ<45>     DQ<45>  @BASEBOARD_FAB2_LIB.BASEBOARD_FAB2(SCH_1):M_G_DQ<45>
  106  M_G_DQ<44>     DQ<44>  @BASEBOARD_FAB2_LIB.BASEBOARD_FAB2(SCH_1):M_G_DQ<44>
  260  M_G_DQ<43>     DQ<43>  @BASEBOARD_FAB2_LIB.BASEBOARD_FAB2(SCH_1):M_G_DQ<43>
  115  M_G_DQ<42>     DQ<42>  @BASEBOARD_FAB2_LIB.BASEBOARD_FAB2(SCH_1):M_G_DQ<42>
  253  M_G_DQ<41>     DQ<41>  @BASEBOARD_FAB2_LIB.BASEBOARD_FAB2(SCH_1):M_G_DQ<41>
  108  M_G_DQ<40>     DQ<40>  @BASEBOARD_FAB2_LIB.BASEBOARD_FAB2(SCH_1):M_G_DQ<40>
  157  M_G_DQ<3>      DQ<3>  @BASEBOARD_FAB2_LIB.BASEBOARD_FAB2(SCH_1):M_G_DQ<3>
  247  M_G_DQ<39>     DQ<39>  @BASEBOARD_FAB2_LIB.BASEBOARD_FAB2(SCH_1):M_G_DQ<39>
  102  M_G_DQ<38>     DQ<38>  @BASEBOARD_FAB2_LIB.BASEBOARD_FAB2(SCH_1):M_G_DQ<38>
  240  M_G_DQ<37>     DQ<37>  @BASEBOARD_FAB2_LIB.BASEBOARD_FAB2(SCH_1):M_G_DQ<37>
   95  M_G_DQ<36>     DQ<36>  @BASEBOARD_FAB2_LIB.BASEBOARD_FAB2(SCH_1):M_G_DQ<36>
  249  M_G_DQ<35>     DQ<35>  @BASEBOARD_FAB2_LIB.BASEBOARD_FAB2(SCH_1):M_G_DQ<35>
  104  M_G_DQ<34>     DQ<34>  @BASEBOARD_FAB2_LIB.BASEBOARD_FAB2(SCH_1):M_G_DQ<34>
  242  M_G_DQ<33>     DQ<33>  @BASEBOARD_FAB2_LIB.BASEBOARD_FAB2(SCH_1):M_G_DQ<33>
   97  M_G_DQ<32>     DQ<32>  @BASEBOARD_FAB2_LIB.BASEBOARD_FAB2(SCH_1):M_G_DQ<32>
  188  M_G_DQ<31>     DQ<31>  @BASEBOARD_FAB2_LIB.BASEBOARD_FAB2(SCH_1):M_G_DQ<31>
   43  M_G_DQ<30>     DQ<30>  @BASEBOARD_FAB2_LIB.BASEBOARD_FAB2(SCH_1):M_G_DQ<30>
   12  M_G_DQ<2>      DQ<2>  @BASEBOARD_FAB2_LIB.BASEBOARD_FAB2(SCH_1):M_G_DQ<2>
  181  M_G_DQ<29>     DQ<29>  @BASEBOARD_FAB2_LIB.BASEBOARD_FAB2(SCH_1):M_G_DQ<29>
   36  M_G_DQ<28>     DQ<28>  @BASEBOARD_FAB2_LIB.BASEBOARD_FAB2(SCH_1):M_G_DQ<28>
  190  M_G_DQ<27>     DQ<27>  @BASEBOARD_FAB2_LIB.BASEBOARD_FAB2(SCH_1):M_G_DQ<27>
   45  M_G_DQ<26>     DQ<26>  @BASEBOARD_FAB2_LIB.BASEBOARD_FAB2(SCH_1):M_G_DQ<26>
  183  M_G_DQ<25>     DQ<25>  @BASEBOARD_FAB2_LIB.BASEBOARD_FAB2(SCH_1):M_G_DQ<25>
   38  M_G_DQ<24>     DQ<24>  @BASEBOARD_FAB2_LIB.BASEBOARD_FAB2(SCH_1):M_G_DQ<24>
  177  M_G_DQ<23>     DQ<23>  @BASEBOARD_FAB2_LIB.BASEBOARD_FAB2(SCH_1):M_G_DQ<23>
   32  M_G_DQ<22>     DQ<22>  @BASEBOARD_FAB2_LIB.BASEBOARD_FAB2(SCH_1):M_G_DQ<22>
  170  M_G_DQ<21>     DQ<21>  @BASEBOARD_FAB2_LIB.BASEBOARD_FAB2(SCH_1):M_G_DQ<21>
   25  M_G_DQ<20>     DQ<20>  @BASEBOARD_FAB2_LIB.BASEBOARD_FAB2(SCH_1):M_G_DQ<20>
  150  M_G_DQ<1>      DQ<1>  @BASEBOARD_FAB2_LIB.BASEBOARD_FAB2(SCH_1):M_G_DQ<1>
  179  M_G_DQ<19>     DQ<19>  @BASEBOARD_FAB2_LIB.BASEBOARD_FAB2(SCH_1):M_G_DQ<19>
   34  M_G_DQ<18>     DQ<18>  @BASEBOARD_FAB2_LIB.BASEBOARD_FAB2(SCH_1):M_G_DQ<18>
  172  M_G_DQ<17>     DQ<17>  @BASEBOARD_FAB2_LIB.BASEBOARD_FAB2(SCH_1):M_G_DQ<17>
   27  M_G_DQ<16>     DQ<16>  @BASEBOARD_FAB2_LIB.BASEBOARD_FAB2(SCH_1):M_G_DQ<16>
  166  M_G_DQ<15>     DQ<15>  @BASEBOARD_FAB2_LIB.BASEBOARD_FAB2(SCH_1):M_G_DQ<15>
   21  M_G_DQ<14>     DQ<14>  @BASEBOARD_FAB2_LIB.BASEBOARD_FAB2(SCH_1):M_G_DQ<14>
  159  M_G_DQ<13>     DQ<13>  @BASEBOARD_FAB2_LIB.BASEBOARD_FAB2(SCH_1):M_G_DQ<13>
   14  M_G_DQ<12>     DQ<12>  @BASEBOARD_FAB2_LIB.BASEBOARD_FAB2(SCH_1):M_G_DQ<12>
  168  M_G_DQ<11>     DQ<11>  @BASEBOARD_FAB2_LIB.BASEBOARD_FAB2(SCH_1):M_G_DQ<11>
   23  M_G_DQ<10>     DQ<10>  @BASEBOARD_FAB2_LIB.BASEBOARD_FAB2(SCH_1):M_G_DQ<10>
    5  M_G_DQ<0>      DQ<0>  @BASEBOARD_FAB2_LIB.BASEBOARD_FAB2(SCH_1):M_G_DQ<0>
  237  M_G_CS_N<7>    S3_N_C<1>  @BASEBOARD_FAB2_LIB.BASEBOARD_FAB2(SCH_1):M_G_CS_N<7>
   93  M_G_CS_N<6>    S2_N_C<0>  @BASEBOARD_FAB2_LIB.BASEBOARD_FAB2(SCH_1):M_G_CS_N<6>
   89  M_G_CS_N<5>     S1_N  @BASEBOARD_FAB2_LIB.BASEBOARD_FAB2(SCH_1):M_G_CS_N<5>
   84  M_G_CS_N<4>     S0_N  @BASEBOARD_FAB2_LIB.BASEBOARD_FAB2(SCH_1):M_G_CS_N<4>
  218  M_G_CLK_DP<3>   CK1P  @BASEBOARD_FAB2_LIB.BASEBOARD_FAB2(SCH_1):M_G_CLK_DP<3>
   74  M_G_CLK_DP<2>   CK0P  @BASEBOARD_FAB2_LIB.BASEBOARD_FAB2(SCH_1):M_G_CLK_DP<2>
  219  M_G_CLK_DN<3>   CK1N  @BASEBOARD_FAB2_LIB.BASEBOARD_FAB2(SCH_1):M_G_CLK_DN<3>
   75  M_G_CLK_DN<2>   CK0N  @BASEBOARD_FAB2_LIB.BASEBOARD_FAB2(SCH_1):M_G_CLK_DN<2>
  203  M_G_CKE<3>     CKE<1>  @BASEBOARD_FAB2_LIB.BASEBOARD_FAB2(SCH_1):M_G_CKE<3>
   60  M_G_CKE<2>     CKE<0>  @BASEBOARD_FAB2_LIB.BASEBOARD_FAB2(SCH_1):M_G_CKE<2>
  235  M_G_C<2>        C<2>  @BASEBOARD_FAB2_LIB.BASEBOARD_FAB2(SCH_1):M_G_C<2>
  207  M_G_BG<1>      BG<1>  @BASEBOARD_FAB2_LIB.BASEBOARD_FAB2(SCH_1):M_G_BG<1>
   63  M_G_BG<0>      BG<0>  @BASEBOARD_FAB2_LIB.BASEBOARD_FAB2(SCH_1):M_G_BG<0>
  224  M_G_BA<1>      BA<1>  @BASEBOARD_FAB2_LIB.BASEBOARD_FAB2(SCH_1):M_G_BA<1>
   81  M_G_BA<0>      BA<0>  @BASEBOARD_FAB2_LIB.BASEBOARD_FAB2(SCH_1):M_G_BA<0>
  208  M_G_ALERT_N    ALERT_N  @BASEBOARD_FAB2_LIB.BASEBOARD_FAB2(SCH_1):M_G_ALERT_N
   62  M_G_ACT_N      ACT_N  @BASEBOARD_FAB2_LIB.BASEBOARD_FAB2(SCH_1):M_G_ACT_N
   58  M_GHJ_RST_N    RESET_N  @BASEBOARD_FAB2_LIB.BASEBOARD_FAB2(SCH_1):M_GHJ_RST_N
  238  GND            SA<2>  @BASEBOARD_FAB2_LIB.BASEBOARD_FAB2(SCH_1):GND
  140  GND            SA<1>  @BASEBOARD_FAB2_LIB.BASEBOARD_FAB2(SCH_1):GND
   78  FM_DIMM_EVENT_COD_N  EVENT_N  @BASEBOARD_FAB2_LIB.BASEBOARD_FAB2(SCH_1):FM_DIMM_EVENT_COD_N
  230  FM_ADR_COMPLETE_GHJ_N  SAVE_N_NC  @BASEBOARD_FAB2_LIB.BASEBOARD_FAB2(SCH_1):FM_ADR_COMPLETE_GHJ_N

SCONN288_H44441003_PIP  I56  J9U1   [SCONN288_H44441003_PIP-SCONN,HA]
   77  PVTT_GHJ       VTT<1>  @BASEBOARD_FAB2_LIB.BASEBOARD_FAB2(SCH_1):PVTT_GHJ
  221  PVTT_GHJ       VTT<0>  @BASEBOARD_FAB2_LIB.BASEBOARD_FAB2(SCH_1):PVTT_GHJ
  142  PVPP_GHJ       VPP<4>  @BASEBOARD_FAB2_LIB.BASEBOARD_FAB2(SCH_1):PVPP_GHJ
  143  PVPP_GHJ       VPP<3>  @BASEBOARD_FAB2_LIB.BASEBOARD_FAB2(SCH_1):PVPP_GHJ
  288  PVPP_GHJ       VPP<2>  @BASEBOARD_FAB2_LIB.BASEBOARD_FAB2(SCH_1):PVPP_GHJ
  286  PVPP_GHJ       VPP<1>  @BASEBOARD_FAB2_LIB.BASEBOARD_FAB2(SCH_1):PVPP_GHJ
  287  PVPP_GHJ       VPP<0>  @BASEBOARD_FAB2_LIB.BASEBOARD_FAB2(SCH_1):PVPP_GHJ
   59  PVDDQ_GHJ      VDD<25>  @BASEBOARD_FAB2_LIB.BASEBOARD_FAB2(SCH_1):PVDDQ_GHJ
   61  PVDDQ_GHJ      VDD<24>  @BASEBOARD_FAB2_LIB.BASEBOARD_FAB2(SCH_1):PVDDQ_GHJ
   64  PVDDQ_GHJ      VDD<23>  @BASEBOARD_FAB2_LIB.BASEBOARD_FAB2(SCH_1):PVDDQ_GHJ
   67  PVDDQ_GHJ      VDD<22>  @BASEBOARD_FAB2_LIB.BASEBOARD_FAB2(SCH_1):PVDDQ_GHJ
   70  PVDDQ_GHJ      VDD<21>  @BASEBOARD_FAB2_LIB.BASEBOARD_FAB2(SCH_1):PVDDQ_GHJ
   73  PVDDQ_GHJ      VDD<20>  @BASEBOARD_FAB2_LIB.BASEBOARD_FAB2(SCH_1):PVDDQ_GHJ
   76  PVDDQ_GHJ      VDD<19>  @BASEBOARD_FAB2_LIB.BASEBOARD_FAB2(SCH_1):PVDDQ_GHJ
   80  PVDDQ_GHJ      VDD<18>  @BASEBOARD_FAB2_LIB.BASEBOARD_FAB2(SCH_1):PVDDQ_GHJ
   83  PVDDQ_GHJ      VDD<17>  @BASEBOARD_FAB2_LIB.BASEBOARD_FAB2(SCH_1):PVDDQ_GHJ
   85  PVDDQ_GHJ      VDD<16>  @BASEBOARD_FAB2_LIB.BASEBOARD_FAB2(SCH_1):PVDDQ_GHJ
   88  PVDDQ_GHJ      VDD<15>  @BASEBOARD_FAB2_LIB.BASEBOARD_FAB2(SCH_1):PVDDQ_GHJ
   90  PVDDQ_GHJ      VDD<14>  @BASEBOARD_FAB2_LIB.BASEBOARD_FAB2(SCH_1):PVDDQ_GHJ
   92  PVDDQ_GHJ      VDD<13>  @BASEBOARD_FAB2_LIB.BASEBOARD_FAB2(SCH_1):PVDDQ_GHJ
  204  PVDDQ_GHJ      VDD<12>  @BASEBOARD_FAB2_LIB.BASEBOARD_FAB2(SCH_1):PVDDQ_GHJ
  206  PVDDQ_GHJ      VDD<11>  @BASEBOARD_FAB2_LIB.BASEBOARD_FAB2(SCH_1):PVDDQ_GHJ
  209  PVDDQ_GHJ      VDD<10>  @BASEBOARD_FAB2_LIB.BASEBOARD_FAB2(SCH_1):PVDDQ_GHJ
  212  PVDDQ_GHJ      VDD<9>  @BASEBOARD_FAB2_LIB.BASEBOARD_FAB2(SCH_1):PVDDQ_GHJ
  215  PVDDQ_GHJ      VDD<8>  @BASEBOARD_FAB2_LIB.BASEBOARD_FAB2(SCH_1):PVDDQ_GHJ
  217  PVDDQ_GHJ      VDD<7>  @BASEBOARD_FAB2_LIB.BASEBOARD_FAB2(SCH_1):PVDDQ_GHJ
  220  PVDDQ_GHJ      VDD<6>  @BASEBOARD_FAB2_LIB.BASEBOARD_FAB2(SCH_1):PVDDQ_GHJ
  223  PVDDQ_GHJ      VDD<5>  @BASEBOARD_FAB2_LIB.BASEBOARD_FAB2(SCH_1):PVDDQ_GHJ
  226  PVDDQ_GHJ      VDD<4>  @BASEBOARD_FAB2_LIB.BASEBOARD_FAB2(SCH_1):PVDDQ_GHJ
  229  PVDDQ_GHJ      VDD<3>  @BASEBOARD_FAB2_LIB.BASEBOARD_FAB2(SCH_1):PVDDQ_GHJ
  231  PVDDQ_GHJ      VDD<2>  @BASEBOARD_FAB2_LIB.BASEBOARD_FAB2(SCH_1):PVDDQ_GHJ
  233  PVDDQ_GHJ      VDD<1>  @BASEBOARD_FAB2_LIB.BASEBOARD_FAB2(SCH_1):PVDDQ_GHJ
  236  PVDDQ_GHJ      VDD<0>  @BASEBOARD_FAB2_LIB.BASEBOARD_FAB2(SCH_1):PVDDQ_GHJ
    1  P12V_NVDIMM_GHJ  12V<1>  @BASEBOARD_FAB2_LIB.BASEBOARD_FAB2(SCH_1):P12V_NVDIMM_GHJ
  145  P12V_NVDIMM_GHJ  12V<0>  @BASEBOARD_FAB2_LIB.BASEBOARD_FAB2(SCH_1):P12V_NVDIMM_GHJ

SCONN288_H44441003_PIP  I138  J9U1   [SCONN288_H44441003_PIP-SCONN,HA]
    2  GND            VSS<93>  @BASEBOARD_FAB2_LIB.BASEBOARD_FAB2(SCH_1):GND
    4  GND            VSS<92>  @BASEBOARD_FAB2_LIB.BASEBOARD_FAB2(SCH_1):GND
    6  GND            VSS<91>  @BASEBOARD_FAB2_LIB.BASEBOARD_FAB2(SCH_1):GND
    9  GND            VSS<90>  @BASEBOARD_FAB2_LIB.BASEBOARD_FAB2(SCH_1):GND
   11  GND            VSS<89>  @BASEBOARD_FAB2_LIB.BASEBOARD_FAB2(SCH_1):GND
   13  GND            VSS<88>  @BASEBOARD_FAB2_LIB.BASEBOARD_FAB2(SCH_1):GND
   15  GND            VSS<87>  @BASEBOARD_FAB2_LIB.BASEBOARD_FAB2(SCH_1):GND
   17  GND            VSS<86>  @BASEBOARD_FAB2_LIB.BASEBOARD_FAB2(SCH_1):GND
   20  GND            VSS<85>  @BASEBOARD_FAB2_LIB.BASEBOARD_FAB2(SCH_1):GND
   22  GND            VSS<84>  @BASEBOARD_FAB2_LIB.BASEBOARD_FAB2(SCH_1):GND
   24  GND            VSS<83>  @BASEBOARD_FAB2_LIB.BASEBOARD_FAB2(SCH_1):GND
   26  GND            VSS<82>  @BASEBOARD_FAB2_LIB.BASEBOARD_FAB2(SCH_1):GND
   28  GND            VSS<81>  @BASEBOARD_FAB2_LIB.BASEBOARD_FAB2(SCH_1):GND
   31  GND            VSS<80>  @BASEBOARD_FAB2_LIB.BASEBOARD_FAB2(SCH_1):GND
   33  GND            VSS<79>  @BASEBOARD_FAB2_LIB.BASEBOARD_FAB2(SCH_1):GND
   35  GND            VSS<78>  @BASEBOARD_FAB2_LIB.BASEBOARD_FAB2(SCH_1):GND
   37  GND            VSS<77>  @BASEBOARD_FAB2_LIB.BASEBOARD_FAB2(SCH_1):GND
   39  GND            VSS<76>  @BASEBOARD_FAB2_LIB.BASEBOARD_FAB2(SCH_1):GND
   42  GND            VSS<75>  @BASEBOARD_FAB2_LIB.BASEBOARD_FAB2(SCH_1):GND
   44  GND            VSS<74>  @BASEBOARD_FAB2_LIB.BASEBOARD_FAB2(SCH_1):GND
   46  GND            VSS<73>  @BASEBOARD_FAB2_LIB.BASEBOARD_FAB2(SCH_1):GND
   48  GND            VSS<72>  @BASEBOARD_FAB2_LIB.BASEBOARD_FAB2(SCH_1):GND
   50  GND            VSS<71>  @BASEBOARD_FAB2_LIB.BASEBOARD_FAB2(SCH_1):GND
   53  GND            VSS<70>  @BASEBOARD_FAB2_LIB.BASEBOARD_FAB2(SCH_1):GND
   55  GND            VSS<69>  @BASEBOARD_FAB2_LIB.BASEBOARD_FAB2(SCH_1):GND
   57  GND            VSS<68>  @BASEBOARD_FAB2_LIB.BASEBOARD_FAB2(SCH_1):GND
   94  GND            VSS<67>  @BASEBOARD_FAB2_LIB.BASEBOARD_FAB2(SCH_1):GND
   96  GND            VSS<66>  @BASEBOARD_FAB2_LIB.BASEBOARD_FAB2(SCH_1):GND
   98  GND            VSS<65>  @BASEBOARD_FAB2_LIB.BASEBOARD_FAB2(SCH_1):GND
  101  GND            VSS<64>  @BASEBOARD_FAB2_LIB.BASEBOARD_FAB2(SCH_1):GND
  103  GND            VSS<63>  @BASEBOARD_FAB2_LIB.BASEBOARD_FAB2(SCH_1):GND
  105  GND            VSS<62>  @BASEBOARD_FAB2_LIB.BASEBOARD_FAB2(SCH_1):GND
  107  GND            VSS<61>  @BASEBOARD_FAB2_LIB.BASEBOARD_FAB2(SCH_1):GND
  109  GND            VSS<60>  @BASEBOARD_FAB2_LIB.BASEBOARD_FAB2(SCH_1):GND
  112  GND            VSS<59>  @BASEBOARD_FAB2_LIB.BASEBOARD_FAB2(SCH_1):GND
  114  GND            VSS<58>  @BASEBOARD_FAB2_LIB.BASEBOARD_FAB2(SCH_1):GND
  116  GND            VSS<57>  @BASEBOARD_FAB2_LIB.BASEBOARD_FAB2(SCH_1):GND
  118  GND            VSS<56>  @BASEBOARD_FAB2_LIB.BASEBOARD_FAB2(SCH_1):GND
  120  GND            VSS<55>  @BASEBOARD_FAB2_LIB.BASEBOARD_FAB2(SCH_1):GND
  123  GND            VSS<54>  @BASEBOARD_FAB2_LIB.BASEBOARD_FAB2(SCH_1):GND
  125  GND            VSS<53>  @BASEBOARD_FAB2_LIB.BASEBOARD_FAB2(SCH_1):GND
  127  GND            VSS<52>  @BASEBOARD_FAB2_LIB.BASEBOARD_FAB2(SCH_1):GND
  129  GND            VSS<51>  @BASEBOARD_FAB2_LIB.BASEBOARD_FAB2(SCH_1):GND
  131  GND            VSS<50>  @BASEBOARD_FAB2_LIB.BASEBOARD_FAB2(SCH_1):GND
  134  GND            VSS<49>  @BASEBOARD_FAB2_LIB.BASEBOARD_FAB2(SCH_1):GND
  136  GND            VSS<48>  @BASEBOARD_FAB2_LIB.BASEBOARD_FAB2(SCH_1):GND
  138  GND            VSS<47>  @BASEBOARD_FAB2_LIB.BASEBOARD_FAB2(SCH_1):GND
  147  GND            VSS<46>  @BASEBOARD_FAB2_LIB.BASEBOARD_FAB2(SCH_1):GND
  149  GND            VSS<45>  @BASEBOARD_FAB2_LIB.BASEBOARD_FAB2(SCH_1):GND
  151  GND            VSS<44>  @BASEBOARD_FAB2_LIB.BASEBOARD_FAB2(SCH_1):GND
  154  GND            VSS<43>  @BASEBOARD_FAB2_LIB.BASEBOARD_FAB2(SCH_1):GND
  156  GND            VSS<42>  @BASEBOARD_FAB2_LIB.BASEBOARD_FAB2(SCH_1):GND
  158  GND            VSS<41>  @BASEBOARD_FAB2_LIB.BASEBOARD_FAB2(SCH_1):GND
  160  GND            VSS<40>  @BASEBOARD_FAB2_LIB.BASEBOARD_FAB2(SCH_1):GND
  162  GND            VSS<39>  @BASEBOARD_FAB2_LIB.BASEBOARD_FAB2(SCH_1):GND
  165  GND            VSS<38>  @BASEBOARD_FAB2_LIB.BASEBOARD_FAB2(SCH_1):GND
  167  GND            VSS<37>  @BASEBOARD_FAB2_LIB.BASEBOARD_FAB2(SCH_1):GND
  169  GND            VSS<36>  @BASEBOARD_FAB2_LIB.BASEBOARD_FAB2(SCH_1):GND
  171  GND            VSS<35>  @BASEBOARD_FAB2_LIB.BASEBOARD_FAB2(SCH_1):GND
  173  GND            VSS<34>  @BASEBOARD_FAB2_LIB.BASEBOARD_FAB2(SCH_1):GND
  176  GND            VSS<33>  @BASEBOARD_FAB2_LIB.BASEBOARD_FAB2(SCH_1):GND
  178  GND            VSS<32>  @BASEBOARD_FAB2_LIB.BASEBOARD_FAB2(SCH_1):GND
  180  GND            VSS<31>  @BASEBOARD_FAB2_LIB.BASEBOARD_FAB2(SCH_1):GND
  182  GND            VSS<30>  @BASEBOARD_FAB2_LIB.BASEBOARD_FAB2(SCH_1):GND
  184  GND            VSS<29>  @BASEBOARD_FAB2_LIB.BASEBOARD_FAB2(SCH_1):GND
  187  GND            VSS<28>  @BASEBOARD_FAB2_LIB.BASEBOARD_FAB2(SCH_1):GND
  189  GND            VSS<27>  @BASEBOARD_FAB2_LIB.BASEBOARD_FAB2(SCH_1):GND
  191  GND            VSS<26>  @BASEBOARD_FAB2_LIB.BASEBOARD_FAB2(SCH_1):GND
  193  GND            VSS<25>  @BASEBOARD_FAB2_LIB.BASEBOARD_FAB2(SCH_1):GND
  195  GND            VSS<24>  @BASEBOARD_FAB2_LIB.BASEBOARD_FAB2(SCH_1):GND
  198  GND            VSS<23>  @BASEBOARD_FAB2_LIB.BASEBOARD_FAB2(SCH_1):GND
  200  GND            VSS<22>  @BASEBOARD_FAB2_LIB.BASEBOARD_FAB2(SCH_1):GND
  202  GND            VSS<21>  @BASEBOARD_FAB2_LIB.BASEBOARD_FAB2(SCH_1):GND
  239  GND            VSS<20>  @BASEBOARD_FAB2_LIB.BASEBOARD_FAB2(SCH_1):GND
  241  GND            VSS<19>  @BASEBOARD_FAB2_LIB.BASEBOARD_FAB2(SCH_1):GND
  243  GND            VSS<18>  @BASEBOARD_FAB2_LIB.BASEBOARD_FAB2(SCH_1):GND
  246  GND            VSS<17>  @BASEBOARD_FAB2_LIB.BASEBOARD_FAB2(SCH_1):GND
  248  GND            VSS<16>  @BASEBOARD_FAB2_LIB.BASEBOARD_FAB2(SCH_1):GND
  250  GND            VSS<15>  @BASEBOARD_FAB2_LIB.BASEBOARD_FAB2(SCH_1):GND
  252  GND            VSS<14>  @BASEBOARD_FAB2_LIB.BASEBOARD_FAB2(SCH_1):GND
  254  GND            VSS<13>  @BASEBOARD_FAB2_LIB.BASEBOARD_FAB2(SCH_1):GND
  257  GND            VSS<12>  @BASEBOARD_FAB2_LIB.BASEBOARD_FAB2(SCH_1):GND
  259  GND            VSS<11>  @BASEBOARD_FAB2_LIB.BASEBOARD_FAB2(SCH_1):GND
  261  GND            VSS<10>  @BASEBOARD_FAB2_LIB.BASEBOARD_FAB2(SCH_1):GND
  263  GND            VSS<9>  @BASEBOARD_FAB2_LIB.BASEBOARD_FAB2(SCH_1):GND
  265  GND            VSS<8>  @BASEBOARD_FAB2_LIB.BASEBOARD_FAB2(SCH_1):GND
  268  GND            VSS<7>  @BASEBOARD_FAB2_LIB.BASEBOARD_FAB2(SCH_1):GND
  270  GND            VSS<6>  @BASEBOARD_FAB2_LIB.BASEBOARD_FAB2(SCH_1):GND
  272  GND            VSS<5>  @BASEBOARD_FAB2_LIB.BASEBOARD_FAB2(SCH_1):GND
  274  GND            VSS<4>  @BASEBOARD_FAB2_LIB.BASEBOARD_FAB2(SCH_1):GND
  276  GND            VSS<3>  @BASEBOARD_FAB2_LIB.BASEBOARD_FAB2(SCH_1):GND
  279  GND            VSS<2>  @BASEBOARD_FAB2_LIB.BASEBOARD_FAB2(SCH_1):GND
  281  GND            VSS<1>  @BASEBOARD_FAB2_LIB.BASEBOARD_FAB2(SCH_1):GND
  283  GND            VSS<0>  @BASEBOARD_FAB2_LIB.BASEBOARD_FAB2(SCH_1):GND

SCONN288_H44441003_PIP  I101  J9U1   [SCONN288_H44441003_PIP-SCONN,HA]
    7  M_H_DQS_DP<9>  DQS9P  @BASEBOARD_FAB2_LIB.BASEBOARD_FAB2(SCH_1):M_H_DQS_DP<9>
  197  M_H_DQS_DP<8>  DQS8P  @BASEBOARD_FAB2_LIB.BASEBOARD_FAB2(SCH_1):M_H_DQS_DP<8>
  278  M_H_DQS_DP<7>  DQS7P  @BASEBOARD_FAB2_LIB.BASEBOARD_FAB2(SCH_1):M_H_DQS_DP<7>
  267  M_H_DQS_DP<6>  DQS6P  @BASEBOARD_FAB2_LIB.BASEBOARD_FAB2(SCH_1):M_H_DQS_DP<6>
  256  M_H_DQS_DP<5>  DQS5P  @BASEBOARD_FAB2_LIB.BASEBOARD_FAB2(SCH_1):M_H_DQS_DP<5>
  245  M_H_DQS_DP<4>  DQS4P  @BASEBOARD_FAB2_LIB.BASEBOARD_FAB2(SCH_1):M_H_DQS_DP<4>
  186  M_H_DQS_DP<3>  DQS3P  @BASEBOARD_FAB2_LIB.BASEBOARD_FAB2(SCH_1):M_H_DQS_DP<3>
  175  M_H_DQS_DP<2>  DQS2P  @BASEBOARD_FAB2_LIB.BASEBOARD_FAB2(SCH_1):M_H_DQS_DP<2>
  164  M_H_DQS_DP<1>  DQS1P  @BASEBOARD_FAB2_LIB.BASEBOARD_FAB2(SCH_1):M_H_DQS_DP<1>
   51  M_H_DQS_DP<17>  DQS17P  @BASEBOARD_FAB2_LIB.BASEBOARD_FAB2(SCH_1):M_H_DQS_DP<17>
  132  M_H_DQS_DP<16>  DQS16P  @BASEBOARD_FAB2_LIB.BASEBOARD_FAB2(SCH_1):M_H_DQS_DP<16>
  121  M_H_DQS_DP<15>  DQS15P  @BASEBOARD_FAB2_LIB.BASEBOARD_FAB2(SCH_1):M_H_DQS_DP<15>
  110  M_H_DQS_DP<14>  DQS14P  @BASEBOARD_FAB2_LIB.BASEBOARD_FAB2(SCH_1):M_H_DQS_DP<14>
   99  M_H_DQS_DP<13>  DQS13P  @BASEBOARD_FAB2_LIB.BASEBOARD_FAB2(SCH_1):M_H_DQS_DP<13>
   40  M_H_DQS_DP<12>  DQS12P  @BASEBOARD_FAB2_LIB.BASEBOARD_FAB2(SCH_1):M_H_DQS_DP<12>
   29  M_H_DQS_DP<11>  DQS11P  @BASEBOARD_FAB2_LIB.BASEBOARD_FAB2(SCH_1):M_H_DQS_DP<11>
   18  M_H_DQS_DP<10>  DQS10P  @BASEBOARD_FAB2_LIB.BASEBOARD_FAB2(SCH_1):M_H_DQS_DP<10>
  153  M_H_DQS_DP<0>  DQS0P  @BASEBOARD_FAB2_LIB.BASEBOARD_FAB2(SCH_1):M_H_DQS_DP<0>
    8  M_H_DQS_DN<9>  DQS9N  @BASEBOARD_FAB2_LIB.BASEBOARD_FAB2(SCH_1):M_H_DQS_DN<9>
  196  M_H_DQS_DN<8>  DQS8N  @BASEBOARD_FAB2_LIB.BASEBOARD_FAB2(SCH_1):M_H_DQS_DN<8>
  277  M_H_DQS_DN<7>  DQS7N  @BASEBOARD_FAB2_LIB.BASEBOARD_FAB2(SCH_1):M_H_DQS_DN<7>
  266  M_H_DQS_DN<6>  DQS6N  @BASEBOARD_FAB2_LIB.BASEBOARD_FAB2(SCH_1):M_H_DQS_DN<6>
  255  M_H_DQS_DN<5>  DQS5N  @BASEBOARD_FAB2_LIB.BASEBOARD_FAB2(SCH_1):M_H_DQS_DN<5>
  244  M_H_DQS_DN<4>  DQS4N  @BASEBOARD_FAB2_LIB.BASEBOARD_FAB2(SCH_1):M_H_DQS_DN<4>
  185  M_H_DQS_DN<3>  DQS3N  @BASEBOARD_FAB2_LIB.BASEBOARD_FAB2(SCH_1):M_H_DQS_DN<3>
  174  M_H_DQS_DN<2>  DQS2N  @BASEBOARD_FAB2_LIB.BASEBOARD_FAB2(SCH_1):M_H_DQS_DN<2>
  163  M_H_DQS_DN<1>  DQS1N  @BASEBOARD_FAB2_LIB.BASEBOARD_FAB2(SCH_1):M_H_DQS_DN<1>
   52  M_H_DQS_DN<17>  DQS17N  @BASEBOARD_FAB2_LIB.BASEBOARD_FAB2(SCH_1):M_H_DQS_DN<17>
  133  M_H_DQS_DN<16>  DQS16N  @BASEBOARD_FAB2_LIB.BASEBOARD_FAB2(SCH_1):M_H_DQS_DN<16>
  122  M_H_DQS_DN<15>  DQS15N  @BASEBOARD_FAB2_LIB.BASEBOARD_FAB2(SCH_1):M_H_DQS_DN<15>
  111  M_H_DQS_DN<14>  DQS14N  @BASEBOARD_FAB2_LIB.BASEBOARD_FAB2(SCH_1):M_H_DQS_DN<14>
  100  M_H_DQS_DN<13>  DQS13N  @BASEBOARD_FAB2_LIB.BASEBOARD_FAB2(SCH_1):M_H_DQS_DN<13>
   41  M_H_DQS_DN<12>  DQS12N  @BASEBOARD_FAB2_LIB.BASEBOARD_FAB2(SCH_1):M_H_DQS_DN<12>
   30  M_H_DQS_DN<11>  DQS11N  @BASEBOARD_FAB2_LIB.BASEBOARD_FAB2(SCH_1):M_H_DQS_DN<11>
   19  M_H_DQS_DN<10>  DQS10N  @BASEBOARD_FAB2_LIB.BASEBOARD_FAB2(SCH_1):M_H_DQS_DN<10>
  152  M_H_DQS_DN<0>  DQS0N  @BASEBOARD_FAB2_LIB.BASEBOARD_FAB2(SCH_1):M_H_DQS_DN<0>

SCONN288_H44441003_PIP  I24  J9U1   [SCONN288_H44441003_PIP-SCONN,HA]
  144  TP_CH_H_DIMM0_RFU_2  RFU<2>  @BASEBOARD_FAB2_LIB.BASEBOARD_FAB2(SCH_1):TP_CH_H_DIMM0_RFU_2
  227  TP_CH_H_DIMM0_RFU_1  RFU<1>  @BASEBOARD_FAB2_LIB.BASEBOARD_FAB2(SCH_1):TP_CH_H_DIMM0_RFU_1
  205  TP_CH_H_DIMM0_RFU_0  RFU<0>  @BASEBOARD_FAB2_LIB.BASEBOARD_FAB2(SCH_1):TP_CH_H_DIMM0_RFU_0
  285  SMB_DDR_GHJ_VPP_SDA    SDA  @BASEBOARD_FAB2_LIB.BASEBOARD_FAB2(SCH_1):SMB_DDR_GHJ_VPP_SDA
  141  SMB_DDR_GHJ_VPP_SCL    SCL  @BASEBOARD_FAB2_LIB.BASEBOARD_FAB2(SCH_1):SMB_DDR_GHJ_VPP_SCL
  284  PVPP_GHJ       VDDSPD  @BASEBOARD_FAB2_LIB.BASEBOARD_FAB2(SCH_1):PVPP_GHJ
  140  PVPP_GHJ       SA<1>  @BASEBOARD_FAB2_LIB.BASEBOARD_FAB2(SCH_1):PVPP_GHJ
  139  PVPP_GHJ       SA<0>  @BASEBOARD_FAB2_LIB.BASEBOARD_FAB2(SCH_1):PVPP_GHJ
  146  M_H_VREF       VREFCA  @BASEBOARD_FAB2_LIB.BASEBOARD_FAB2(SCH_1):M_H_VREF
  222  M_H_PAR          PAR  @BASEBOARD_FAB2_LIB.BASEBOARD_FAB2(SCH_1):M_H_PAR
   91  M_H_ODT<3>     ODT<1>  @BASEBOARD_FAB2_LIB.BASEBOARD_FAB2(SCH_1):M_H_ODT<3>
   87  M_H_ODT<2>     ODT<0>  @BASEBOARD_FAB2_LIB.BASEBOARD_FAB2(SCH_1):M_H_ODT<2>
   66  M_H_MA<9>         A9  @BASEBOARD_FAB2_LIB.BASEBOARD_FAB2(SCH_1):M_H_MA<9>
   68  M_H_MA<8>         A8  @BASEBOARD_FAB2_LIB.BASEBOARD_FAB2(SCH_1):M_H_MA<8>
  211  M_H_MA<7>         A7  @BASEBOARD_FAB2_LIB.BASEBOARD_FAB2(SCH_1):M_H_MA<7>
   69  M_H_MA<6>         A6  @BASEBOARD_FAB2_LIB.BASEBOARD_FAB2(SCH_1):M_H_MA<6>
  213  M_H_MA<5>         A5  @BASEBOARD_FAB2_LIB.BASEBOARD_FAB2(SCH_1):M_H_MA<5>
  214  M_H_MA<4>         A4  @BASEBOARD_FAB2_LIB.BASEBOARD_FAB2(SCH_1):M_H_MA<4>
   71  M_H_MA<3>         A3  @BASEBOARD_FAB2_LIB.BASEBOARD_FAB2(SCH_1):M_H_MA<3>
  216  M_H_MA<2>         A2  @BASEBOARD_FAB2_LIB.BASEBOARD_FAB2(SCH_1):M_H_MA<2>
   72  M_H_MA<1>         A1  @BASEBOARD_FAB2_LIB.BASEBOARD_FAB2(SCH_1):M_H_MA<1>
  234  M_H_MA<17>       A17  @BASEBOARD_FAB2_LIB.BASEBOARD_FAB2(SCH_1):M_H_MA<17>
   82  M_H_MA<16>     A16_RAS_N  @BASEBOARD_FAB2_LIB.BASEBOARD_FAB2(SCH_1):M_H_MA<16>
   86  M_H_MA<15>     A15_CAS_N  @BASEBOARD_FAB2_LIB.BASEBOARD_FAB2(SCH_1):M_H_MA<15>
  228  M_H_MA<14>     A14_WE_N  @BASEBOARD_FAB2_LIB.BASEBOARD_FAB2(SCH_1):M_H_MA<14>
  232  M_H_MA<13>       A13  @BASEBOARD_FAB2_LIB.BASEBOARD_FAB2(SCH_1):M_H_MA<13>
   65  M_H_MA<12>       A12  @BASEBOARD_FAB2_LIB.BASEBOARD_FAB2(SCH_1):M_H_MA<12>
  210  M_H_MA<11>       A11  @BASEBOARD_FAB2_LIB.BASEBOARD_FAB2(SCH_1):M_H_MA<11>
  225  M_H_MA<10>       A10  @BASEBOARD_FAB2_LIB.BASEBOARD_FAB2(SCH_1):M_H_MA<10>
   79  M_H_MA<0>         A0  @BASEBOARD_FAB2_LIB.BASEBOARD_FAB2(SCH_1):M_H_MA<0>
  199  M_H_ECC<7>     CB<7>  @BASEBOARD_FAB2_LIB.BASEBOARD_FAB2(SCH_1):M_H_ECC<7>
   54  M_H_ECC<6>     CB<6>  @BASEBOARD_FAB2_LIB.BASEBOARD_FAB2(SCH_1):M_H_ECC<6>
  192  M_H_ECC<5>     CB<5>  @BASEBOARD_FAB2_LIB.BASEBOARD_FAB2(SCH_1):M_H_ECC<5>
   47  M_H_ECC<4>     CB<4>  @BASEBOARD_FAB2_LIB.BASEBOARD_FAB2(SCH_1):M_H_ECC<4>
  201  M_H_ECC<3>     CB<3>  @BASEBOARD_FAB2_LIB.BASEBOARD_FAB2(SCH_1):M_H_ECC<3>
   56  M_H_ECC<2>     CB<2>  @BASEBOARD_FAB2_LIB.BASEBOARD_FAB2(SCH_1):M_H_ECC<2>
  194  M_H_ECC<1>     CB<1>  @BASEBOARD_FAB2_LIB.BASEBOARD_FAB2(SCH_1):M_H_ECC<1>
   49  M_H_ECC<0>     CB<0>  @BASEBOARD_FAB2_LIB.BASEBOARD_FAB2(SCH_1):M_H_ECC<0>
  161  M_H_DQ<9>      DQ<9>  @BASEBOARD_FAB2_LIB.BASEBOARD_FAB2(SCH_1):M_H_DQ<9>
   16  M_H_DQ<8>      DQ<8>  @BASEBOARD_FAB2_LIB.BASEBOARD_FAB2(SCH_1):M_H_DQ<8>
  155  M_H_DQ<7>      DQ<7>  @BASEBOARD_FAB2_LIB.BASEBOARD_FAB2(SCH_1):M_H_DQ<7>
   10  M_H_DQ<6>      DQ<6>  @BASEBOARD_FAB2_LIB.BASEBOARD_FAB2(SCH_1):M_H_DQ<6>
  280  M_H_DQ<63>     DQ<63>  @BASEBOARD_FAB2_LIB.BASEBOARD_FAB2(SCH_1):M_H_DQ<63>
  135  M_H_DQ<62>     DQ<62>  @BASEBOARD_FAB2_LIB.BASEBOARD_FAB2(SCH_1):M_H_DQ<62>
  273  M_H_DQ<61>     DQ<61>  @BASEBOARD_FAB2_LIB.BASEBOARD_FAB2(SCH_1):M_H_DQ<61>
  128  M_H_DQ<60>     DQ<60>  @BASEBOARD_FAB2_LIB.BASEBOARD_FAB2(SCH_1):M_H_DQ<60>
  148  M_H_DQ<5>      DQ<5>  @BASEBOARD_FAB2_LIB.BASEBOARD_FAB2(SCH_1):M_H_DQ<5>
  282  M_H_DQ<59>     DQ<59>  @BASEBOARD_FAB2_LIB.BASEBOARD_FAB2(SCH_1):M_H_DQ<59>
  137  M_H_DQ<58>     DQ<58>  @BASEBOARD_FAB2_LIB.BASEBOARD_FAB2(SCH_1):M_H_DQ<58>
  275  M_H_DQ<57>     DQ<57>  @BASEBOARD_FAB2_LIB.BASEBOARD_FAB2(SCH_1):M_H_DQ<57>
  130  M_H_DQ<56>     DQ<56>  @BASEBOARD_FAB2_LIB.BASEBOARD_FAB2(SCH_1):M_H_DQ<56>
  269  M_H_DQ<55>     DQ<55>  @BASEBOARD_FAB2_LIB.BASEBOARD_FAB2(SCH_1):M_H_DQ<55>
  124  M_H_DQ<54>     DQ<54>  @BASEBOARD_FAB2_LIB.BASEBOARD_FAB2(SCH_1):M_H_DQ<54>
  262  M_H_DQ<53>     DQ<53>  @BASEBOARD_FAB2_LIB.BASEBOARD_FAB2(SCH_1):M_H_DQ<53>
  117  M_H_DQ<52>     DQ<52>  @BASEBOARD_FAB2_LIB.BASEBOARD_FAB2(SCH_1):M_H_DQ<52>
  271  M_H_DQ<51>     DQ<51>  @BASEBOARD_FAB2_LIB.BASEBOARD_FAB2(SCH_1):M_H_DQ<51>
  126  M_H_DQ<50>     DQ<50>  @BASEBOARD_FAB2_LIB.BASEBOARD_FAB2(SCH_1):M_H_DQ<50>
    3  M_H_DQ<4>      DQ<4>  @BASEBOARD_FAB2_LIB.BASEBOARD_FAB2(SCH_1):M_H_DQ<4>
  264  M_H_DQ<49>     DQ<49>  @BASEBOARD_FAB2_LIB.BASEBOARD_FAB2(SCH_1):M_H_DQ<49>
  119  M_H_DQ<48>     DQ<48>  @BASEBOARD_FAB2_LIB.BASEBOARD_FAB2(SCH_1):M_H_DQ<48>
  258  M_H_DQ<47>     DQ<47>  @BASEBOARD_FAB2_LIB.BASEBOARD_FAB2(SCH_1):M_H_DQ<47>
  113  M_H_DQ<46>     DQ<46>  @BASEBOARD_FAB2_LIB.BASEBOARD_FAB2(SCH_1):M_H_DQ<46>
  251  M_H_DQ<45>     DQ<45>  @BASEBOARD_FAB2_LIB.BASEBOARD_FAB2(SCH_1):M_H_DQ<45>
  106  M_H_DQ<44>     DQ<44>  @BASEBOARD_FAB2_LIB.BASEBOARD_FAB2(SCH_1):M_H_DQ<44>
  260  M_H_DQ<43>     DQ<43>  @BASEBOARD_FAB2_LIB.BASEBOARD_FAB2(SCH_1):M_H_DQ<43>
  115  M_H_DQ<42>     DQ<42>  @BASEBOARD_FAB2_LIB.BASEBOARD_FAB2(SCH_1):M_H_DQ<42>
  253  M_H_DQ<41>     DQ<41>  @BASEBOARD_FAB2_LIB.BASEBOARD_FAB2(SCH_1):M_H_DQ<41>
  108  M_H_DQ<40>     DQ<40>  @BASEBOARD_FAB2_LIB.BASEBOARD_FAB2(SCH_1):M_H_DQ<40>
  157  M_H_DQ<3>      DQ<3>  @BASEBOARD_FAB2_LIB.BASEBOARD_FAB2(SCH_1):M_H_DQ<3>
  247  M_H_DQ<39>     DQ<39>  @BASEBOARD_FAB2_LIB.BASEBOARD_FAB2(SCH_1):M_H_DQ<39>
  102  M_H_DQ<38>     DQ<38>  @BASEBOARD_FAB2_LIB.BASEBOARD_FAB2(SCH_1):M_H_DQ<38>
  240  M_H_DQ<37>     DQ<37>  @BASEBOARD_FAB2_LIB.BASEBOARD_FAB2(SCH_1):M_H_DQ<37>
   95  M_H_DQ<36>     DQ<36>  @BASEBOARD_FAB2_LIB.BASEBOARD_FAB2(SCH_1):M_H_DQ<36>
  249  M_H_DQ<35>     DQ<35>  @BASEBOARD_FAB2_LIB.BASEBOARD_FAB2(SCH_1):M_H_DQ<35>
  104  M_H_DQ<34>     DQ<34>  @BASEBOARD_FAB2_LIB.BASEBOARD_FAB2(SCH_1):M_H_DQ<34>
  242  M_H_DQ<33>     DQ<33>  @BASEBOARD_FAB2_LIB.BASEBOARD_FAB2(SCH_1):M_H_DQ<33>
   97  M_H_DQ<32>     DQ<32>  @BASEBOARD_FAB2_LIB.BASEBOARD_FAB2(SCH_1):M_H_DQ<32>
  188  M_H_DQ<31>     DQ<31>  @BASEBOARD_FAB2_LIB.BASEBOARD_FAB2(SCH_1):M_H_DQ<31>
   43  M_H_DQ<30>     DQ<30>  @BASEBOARD_FAB2_LIB.BASEBOARD_FAB2(SCH_1):M_H_DQ<30>
   12  M_H_DQ<2>      DQ<2>  @BASEBOARD_FAB2_LIB.BASEBOARD_FAB2(SCH_1):M_H_DQ<2>
  181  M_H_DQ<29>     DQ<29>  @BASEBOARD_FAB2_LIB.BASEBOARD_FAB2(SCH_1):M_H_DQ<29>
   36  M_H_DQ<28>     DQ<28>  @BASEBOARD_FAB2_LIB.BASEBOARD_FAB2(SCH_1):M_H_DQ<28>
  190  M_H_DQ<27>     DQ<27>  @BASEBOARD_FAB2_LIB.BASEBOARD_FAB2(SCH_1):M_H_DQ<27>
   45  M_H_DQ<26>     DQ<26>  @BASEBOARD_FAB2_LIB.BASEBOARD_FAB2(SCH_1):M_H_DQ<26>
  183  M_H_DQ<25>     DQ<25>  @BASEBOARD_FAB2_LIB.BASEBOARD_FAB2(SCH_1):M_H_DQ<25>
   38  M_H_DQ<24>     DQ<24>  @BASEBOARD_FAB2_LIB.BASEBOARD_FAB2(SCH_1):M_H_DQ<24>
  177  M_H_DQ<23>     DQ<23>  @BASEBOARD_FAB2_LIB.BASEBOARD_FAB2(SCH_1):M_H_DQ<23>
   32  M_H_DQ<22>     DQ<22>  @BASEBOARD_FAB2_LIB.BASEBOARD_FAB2(SCH_1):M_H_DQ<22>
  170  M_H_DQ<21>     DQ<21>  @BASEBOARD_FAB2_LIB.BASEBOARD_FAB2(SCH_1):M_H_DQ<21>
   25  M_H_DQ<20>     DQ<20>  @BASEBOARD_FAB2_LIB.BASEBOARD_FAB2(SCH_1):M_H_DQ<20>
  150  M_H_DQ<1>      DQ<1>  @BASEBOARD_FAB2_LIB.BASEBOARD_FAB2(SCH_1):M_H_DQ<1>
  179  M_H_DQ<19>     DQ<19>  @BASEBOARD_FAB2_LIB.BASEBOARD_FAB2(SCH_1):M_H_DQ<19>
   34  M_H_DQ<18>     DQ<18>  @BASEBOARD_FAB2_LIB.BASEBOARD_FAB2(SCH_1):M_H_DQ<18>
  172  M_H_DQ<17>     DQ<17>  @BASEBOARD_FAB2_LIB.BASEBOARD_FAB2(SCH_1):M_H_DQ<17>
   27  M_H_DQ<16>     DQ<16>  @BASEBOARD_FAB2_LIB.BASEBOARD_FAB2(SCH_1):M_H_DQ<16>
  166  M_H_DQ<15>     DQ<15>  @BASEBOARD_FAB2_LIB.BASEBOARD_FAB2(SCH_1):M_H_DQ<15>
   21  M_H_DQ<14>     DQ<14>  @BASEBOARD_FAB2_LIB.BASEBOARD_FAB2(SCH_1):M_H_DQ<14>
  159  M_H_DQ<13>     DQ<13>  @BASEBOARD_FAB2_LIB.BASEBOARD_FAB2(SCH_1):M_H_DQ<13>
   14  M_H_DQ<12>     DQ<12>  @BASEBOARD_FAB2_LIB.BASEBOARD_FAB2(SCH_1):M_H_DQ<12>
  168  M_H_DQ<11>     DQ<11>  @BASEBOARD_FAB2_LIB.BASEBOARD_FAB2(SCH_1):M_H_DQ<11>
   23  M_H_DQ<10>     DQ<10>  @BASEBOARD_FAB2_LIB.BASEBOARD_FAB2(SCH_1):M_H_DQ<10>
    5  M_H_DQ<0>      DQ<0>  @BASEBOARD_FAB2_LIB.BASEBOARD_FAB2(SCH_1):M_H_DQ<0>
  237  M_H_CS_N<7>    S3_N_C<1>  @BASEBOARD_FAB2_LIB.BASEBOARD_FAB2(SCH_1):M_H_CS_N<7>
   93  M_H_CS_N<6>    S2_N_C<0>  @BASEBOARD_FAB2_LIB.BASEBOARD_FAB2(SCH_1):M_H_CS_N<6>
   89  M_H_CS_N<5>     S1_N  @BASEBOARD_FAB2_LIB.BASEBOARD_FAB2(SCH_1):M_H_CS_N<5>
   84  M_H_CS_N<4>     S0_N  @BASEBOARD_FAB2_LIB.BASEBOARD_FAB2(SCH_1):M_H_CS_N<4>
  218  M_H_CLK_DP<3>   CK1P  @BASEBOARD_FAB2_LIB.BASEBOARD_FAB2(SCH_1):M_H_CLK_DP<3>
   74  M_H_CLK_DP<2>   CK0P  @BASEBOARD_FAB2_LIB.BASEBOARD_FAB2(SCH_1):M_H_CLK_DP<2>
  219  M_H_CLK_DN<3>   CK1N  @BASEBOARD_FAB2_LIB.BASEBOARD_FAB2(SCH_1):M_H_CLK_DN<3>
   75  M_H_CLK_DN<2>   CK0N  @BASEBOARD_FAB2_LIB.BASEBOARD_FAB2(SCH_1):M_H_CLK_DN<2>
  203  M_H_CKE<3>     CKE<1>  @BASEBOARD_FAB2_LIB.BASEBOARD_FAB2(SCH_1):M_H_CKE<3>
   60  M_H_CKE<2>     CKE<0>  @BASEBOARD_FAB2_LIB.BASEBOARD_FAB2(SCH_1):M_H_CKE<2>
  235  M_H_C<2>        C<2>  @BASEBOARD_FAB2_LIB.BASEBOARD_FAB2(SCH_1):M_H_C<2>
  207  M_H_BG<1>      BG<1>  @BASEBOARD_FAB2_LIB.BASEBOARD_FAB2(SCH_1):M_H_BG<1>
   63  M_H_BG<0>      BG<0>  @BASEBOARD_FAB2_LIB.BASEBOARD_FAB2(SCH_1):M_H_BG<0>
  224  M_H_BA<1>      BA<1>  @BASEBOARD_FAB2_LIB.BASEBOARD_FAB2(SCH_1):M_H_BA<1>
   81  M_H_BA<0>      BA<0>  @BASEBOARD_FAB2_LIB.BASEBOARD_FAB2(SCH_1):M_H_BA<0>
  208  M_H_ALERT_N    ALERT_N  @BASEBOARD_FAB2_LIB.BASEBOARD_FAB2(SCH_1):M_H_ALERT_N
   62  M_H_ACT_N      ACT_N  @BASEBOARD_FAB2_LIB.BASEBOARD_FAB2(SCH_1):M_H_ACT_N
   58  M_GHJ_RST_N    RESET_N  @BASEBOARD_FAB2_LIB.BASEBOARD_FAB2(SCH_1):M_GHJ_RST_N
  238  GND            SA<2>  @BASEBOARD_FAB2_LIB.BASEBOARD_FAB2(SCH_1):GND
   78  FM_DIMM_EVENT_COD_N  EVENT_N  @BASEBOARD_FAB2_LIB.BASEBOARD_FAB2(SCH_1):FM_DIMM_EVENT_COD_N
  230  FM_ADR_COMPLETE_GHJ_N  SAVE_N_NC  @BASEBOARD_FAB2_LIB.BASEBOARD_FAB2(SCH_1):FM_ADR_COMPLETE_GHJ_N

SCONN288_H44441003_PIP  I171  J9U2   [SCONN288_H44441003_PIP-SCONN,HA]
   77  PVTT_GHJ       VTT<1>  @BASEBOARD_FAB2_LIB.BASEBOARD_FAB2(SCH_1):PVTT_GHJ
  221  PVTT_GHJ       VTT<0>  @BASEBOARD_FAB2_LIB.BASEBOARD_FAB2(SCH_1):PVTT_GHJ
  142  PVPP_GHJ       VPP<4>  @BASEBOARD_FAB2_LIB.BASEBOARD_FAB2(SCH_1):PVPP_GHJ
  143  PVPP_GHJ       VPP<3>  @BASEBOARD_FAB2_LIB.BASEBOARD_FAB2(SCH_1):PVPP_GHJ
  288  PVPP_GHJ       VPP<2>  @BASEBOARD_FAB2_LIB.BASEBOARD_FAB2(SCH_1):PVPP_GHJ
  286  PVPP_GHJ       VPP<1>  @BASEBOARD_FAB2_LIB.BASEBOARD_FAB2(SCH_1):PVPP_GHJ
  287  PVPP_GHJ       VPP<0>  @BASEBOARD_FAB2_LIB.BASEBOARD_FAB2(SCH_1):PVPP_GHJ
   59  PVDDQ_GHJ      VDD<25>  @BASEBOARD_FAB2_LIB.BASEBOARD_FAB2(SCH_1):PVDDQ_GHJ
   61  PVDDQ_GHJ      VDD<24>  @BASEBOARD_FAB2_LIB.BASEBOARD_FAB2(SCH_1):PVDDQ_GHJ
   64  PVDDQ_GHJ      VDD<23>  @BASEBOARD_FAB2_LIB.BASEBOARD_FAB2(SCH_1):PVDDQ_GHJ
   67  PVDDQ_GHJ      VDD<22>  @BASEBOARD_FAB2_LIB.BASEBOARD_FAB2(SCH_1):PVDDQ_GHJ
   70  PVDDQ_GHJ      VDD<21>  @BASEBOARD_FAB2_LIB.BASEBOARD_FAB2(SCH_1):PVDDQ_GHJ
   73  PVDDQ_GHJ      VDD<20>  @BASEBOARD_FAB2_LIB.BASEBOARD_FAB2(SCH_1):PVDDQ_GHJ
   76  PVDDQ_GHJ      VDD<19>  @BASEBOARD_FAB2_LIB.BASEBOARD_FAB2(SCH_1):PVDDQ_GHJ
   80  PVDDQ_GHJ      VDD<18>  @BASEBOARD_FAB2_LIB.BASEBOARD_FAB2(SCH_1):PVDDQ_GHJ
   83  PVDDQ_GHJ      VDD<17>  @BASEBOARD_FAB2_LIB.BASEBOARD_FAB2(SCH_1):PVDDQ_GHJ
   85  PVDDQ_GHJ      VDD<16>  @BASEBOARD_FAB2_LIB.BASEBOARD_FAB2(SCH_1):PVDDQ_GHJ
   88  PVDDQ_GHJ      VDD<15>  @BASEBOARD_FAB2_LIB.BASEBOARD_FAB2(SCH_1):PVDDQ_GHJ
   90  PVDDQ_GHJ      VDD<14>  @BASEBOARD_FAB2_LIB.BASEBOARD_FAB2(SCH_1):PVDDQ_GHJ
   92  PVDDQ_GHJ      VDD<13>  @BASEBOARD_FAB2_LIB.BASEBOARD_FAB2(SCH_1):PVDDQ_GHJ
  204  PVDDQ_GHJ      VDD<12>  @BASEBOARD_FAB2_LIB.BASEBOARD_FAB2(SCH_1):PVDDQ_GHJ
  206  PVDDQ_GHJ      VDD<11>  @BASEBOARD_FAB2_LIB.BASEBOARD_FAB2(SCH_1):PVDDQ_GHJ
  209  PVDDQ_GHJ      VDD<10>  @BASEBOARD_FAB2_LIB.BASEBOARD_FAB2(SCH_1):PVDDQ_GHJ
  212  PVDDQ_GHJ      VDD<9>  @BASEBOARD_FAB2_LIB.BASEBOARD_FAB2(SCH_1):PVDDQ_GHJ
  215  PVDDQ_GHJ      VDD<8>  @BASEBOARD_FAB2_LIB.BASEBOARD_FAB2(SCH_1):PVDDQ_GHJ
  217  PVDDQ_GHJ      VDD<7>  @BASEBOARD_FAB2_LIB.BASEBOARD_FAB2(SCH_1):PVDDQ_GHJ
  220  PVDDQ_GHJ      VDD<6>  @BASEBOARD_FAB2_LIB.BASEBOARD_FAB2(SCH_1):PVDDQ_GHJ
  223  PVDDQ_GHJ      VDD<5>  @BASEBOARD_FAB2_LIB.BASEBOARD_FAB2(SCH_1):PVDDQ_GHJ
  226  PVDDQ_GHJ      VDD<4>  @BASEBOARD_FAB2_LIB.BASEBOARD_FAB2(SCH_1):PVDDQ_GHJ
  229  PVDDQ_GHJ      VDD<3>  @BASEBOARD_FAB2_LIB.BASEBOARD_FAB2(SCH_1):PVDDQ_GHJ
  231  PVDDQ_GHJ      VDD<2>  @BASEBOARD_FAB2_LIB.BASEBOARD_FAB2(SCH_1):PVDDQ_GHJ
  233  PVDDQ_GHJ      VDD<1>  @BASEBOARD_FAB2_LIB.BASEBOARD_FAB2(SCH_1):PVDDQ_GHJ
  236  PVDDQ_GHJ      VDD<0>  @BASEBOARD_FAB2_LIB.BASEBOARD_FAB2(SCH_1):PVDDQ_GHJ
    1  P12V_NVDIMM_GHJ  12V<1>  @BASEBOARD_FAB2_LIB.BASEBOARD_FAB2(SCH_1):P12V_NVDIMM_GHJ
  145  P12V_NVDIMM_GHJ  12V<0>  @BASEBOARD_FAB2_LIB.BASEBOARD_FAB2(SCH_1):P12V_NVDIMM_GHJ

SCONN288_H44441003_PIP  I188  J9U2   [SCONN288_H44441003_PIP-SCONN,HA]
    2  GND            VSS<93>  @BASEBOARD_FAB2_LIB.BASEBOARD_FAB2(SCH_1):GND
    4  GND            VSS<92>  @BASEBOARD_FAB2_LIB.BASEBOARD_FAB2(SCH_1):GND
    6  GND            VSS<91>  @BASEBOARD_FAB2_LIB.BASEBOARD_FAB2(SCH_1):GND
    9  GND            VSS<90>  @BASEBOARD_FAB2_LIB.BASEBOARD_FAB2(SCH_1):GND
   11  GND            VSS<89>  @BASEBOARD_FAB2_LIB.BASEBOARD_FAB2(SCH_1):GND
   13  GND            VSS<88>  @BASEBOARD_FAB2_LIB.BASEBOARD_FAB2(SCH_1):GND
   15  GND            VSS<87>  @BASEBOARD_FAB2_LIB.BASEBOARD_FAB2(SCH_1):GND
   17  GND            VSS<86>  @BASEBOARD_FAB2_LIB.BASEBOARD_FAB2(SCH_1):GND
   20  GND            VSS<85>  @BASEBOARD_FAB2_LIB.BASEBOARD_FAB2(SCH_1):GND
   22  GND            VSS<84>  @BASEBOARD_FAB2_LIB.BASEBOARD_FAB2(SCH_1):GND
   24  GND            VSS<83>  @BASEBOARD_FAB2_LIB.BASEBOARD_FAB2(SCH_1):GND
   26  GND            VSS<82>  @BASEBOARD_FAB2_LIB.BASEBOARD_FAB2(SCH_1):GND
   28  GND            VSS<81>  @BASEBOARD_FAB2_LIB.BASEBOARD_FAB2(SCH_1):GND
   31  GND            VSS<80>  @BASEBOARD_FAB2_LIB.BASEBOARD_FAB2(SCH_1):GND
   33  GND            VSS<79>  @BASEBOARD_FAB2_LIB.BASEBOARD_FAB2(SCH_1):GND
   35  GND            VSS<78>  @BASEBOARD_FAB2_LIB.BASEBOARD_FAB2(SCH_1):GND
   37  GND            VSS<77>  @BASEBOARD_FAB2_LIB.BASEBOARD_FAB2(SCH_1):GND
   39  GND            VSS<76>  @BASEBOARD_FAB2_LIB.BASEBOARD_FAB2(SCH_1):GND
   42  GND            VSS<75>  @BASEBOARD_FAB2_LIB.BASEBOARD_FAB2(SCH_1):GND
   44  GND            VSS<74>  @BASEBOARD_FAB2_LIB.BASEBOARD_FAB2(SCH_1):GND
   46  GND            VSS<73>  @BASEBOARD_FAB2_LIB.BASEBOARD_FAB2(SCH_1):GND
   48  GND            VSS<72>  @BASEBOARD_FAB2_LIB.BASEBOARD_FAB2(SCH_1):GND
   50  GND            VSS<71>  @BASEBOARD_FAB2_LIB.BASEBOARD_FAB2(SCH_1):GND
   53  GND            VSS<70>  @BASEBOARD_FAB2_LIB.BASEBOARD_FAB2(SCH_1):GND
   55  GND            VSS<69>  @BASEBOARD_FAB2_LIB.BASEBOARD_FAB2(SCH_1):GND
   57  GND            VSS<68>  @BASEBOARD_FAB2_LIB.BASEBOARD_FAB2(SCH_1):GND
   94  GND            VSS<67>  @BASEBOARD_FAB2_LIB.BASEBOARD_FAB2(SCH_1):GND
   96  GND            VSS<66>  @BASEBOARD_FAB2_LIB.BASEBOARD_FAB2(SCH_1):GND
   98  GND            VSS<65>  @BASEBOARD_FAB2_LIB.BASEBOARD_FAB2(SCH_1):GND
  101  GND            VSS<64>  @BASEBOARD_FAB2_LIB.BASEBOARD_FAB2(SCH_1):GND
  103  GND            VSS<63>  @BASEBOARD_FAB2_LIB.BASEBOARD_FAB2(SCH_1):GND
  105  GND            VSS<62>  @BASEBOARD_FAB2_LIB.BASEBOARD_FAB2(SCH_1):GND
  107  GND            VSS<61>  @BASEBOARD_FAB2_LIB.BASEBOARD_FAB2(SCH_1):GND
  109  GND            VSS<60>  @BASEBOARD_FAB2_LIB.BASEBOARD_FAB2(SCH_1):GND
  112  GND            VSS<59>  @BASEBOARD_FAB2_LIB.BASEBOARD_FAB2(SCH_1):GND
  114  GND            VSS<58>  @BASEBOARD_FAB2_LIB.BASEBOARD_FAB2(SCH_1):GND
  116  GND            VSS<57>  @BASEBOARD_FAB2_LIB.BASEBOARD_FAB2(SCH_1):GND
  118  GND            VSS<56>  @BASEBOARD_FAB2_LIB.BASEBOARD_FAB2(SCH_1):GND
  120  GND            VSS<55>  @BASEBOARD_FAB2_LIB.BASEBOARD_FAB2(SCH_1):GND
  123  GND            VSS<54>  @BASEBOARD_FAB2_LIB.BASEBOARD_FAB2(SCH_1):GND
  125  GND            VSS<53>  @BASEBOARD_FAB2_LIB.BASEBOARD_FAB2(SCH_1):GND
  127  GND            VSS<52>  @BASEBOARD_FAB2_LIB.BASEBOARD_FAB2(SCH_1):GND
  129  GND            VSS<51>  @BASEBOARD_FAB2_LIB.BASEBOARD_FAB2(SCH_1):GND
  131  GND            VSS<50>  @BASEBOARD_FAB2_LIB.BASEBOARD_FAB2(SCH_1):GND
  134  GND            VSS<49>  @BASEBOARD_FAB2_LIB.BASEBOARD_FAB2(SCH_1):GND
  136  GND            VSS<48>  @BASEBOARD_FAB2_LIB.BASEBOARD_FAB2(SCH_1):GND
  138  GND            VSS<47>  @BASEBOARD_FAB2_LIB.BASEBOARD_FAB2(SCH_1):GND
  147  GND            VSS<46>  @BASEBOARD_FAB2_LIB.BASEBOARD_FAB2(SCH_1):GND
  149  GND            VSS<45>  @BASEBOARD_FAB2_LIB.BASEBOARD_FAB2(SCH_1):GND
  151  GND            VSS<44>  @BASEBOARD_FAB2_LIB.BASEBOARD_FAB2(SCH_1):GND
  154  GND            VSS<43>  @BASEBOARD_FAB2_LIB.BASEBOARD_FAB2(SCH_1):GND
  156  GND            VSS<42>  @BASEBOARD_FAB2_LIB.BASEBOARD_FAB2(SCH_1):GND
  158  GND            VSS<41>  @BASEBOARD_FAB2_LIB.BASEBOARD_FAB2(SCH_1):GND
  160  GND            VSS<40>  @BASEBOARD_FAB2_LIB.BASEBOARD_FAB2(SCH_1):GND
  162  GND            VSS<39>  @BASEBOARD_FAB2_LIB.BASEBOARD_FAB2(SCH_1):GND
  165  GND            VSS<38>  @BASEBOARD_FAB2_LIB.BASEBOARD_FAB2(SCH_1):GND
  167  GND            VSS<37>  @BASEBOARD_FAB2_LIB.BASEBOARD_FAB2(SCH_1):GND
  169  GND            VSS<36>  @BASEBOARD_FAB2_LIB.BASEBOARD_FAB2(SCH_1):GND
  171  GND            VSS<35>  @BASEBOARD_FAB2_LIB.BASEBOARD_FAB2(SCH_1):GND
  173  GND            VSS<34>  @BASEBOARD_FAB2_LIB.BASEBOARD_FAB2(SCH_1):GND
  176  GND            VSS<33>  @BASEBOARD_FAB2_LIB.BASEBOARD_FAB2(SCH_1):GND
  178  GND            VSS<32>  @BASEBOARD_FAB2_LIB.BASEBOARD_FAB2(SCH_1):GND
  180  GND            VSS<31>  @BASEBOARD_FAB2_LIB.BASEBOARD_FAB2(SCH_1):GND
  182  GND            VSS<30>  @BASEBOARD_FAB2_LIB.BASEBOARD_FAB2(SCH_1):GND
  184  GND            VSS<29>  @BASEBOARD_FAB2_LIB.BASEBOARD_FAB2(SCH_1):GND
  187  GND            VSS<28>  @BASEBOARD_FAB2_LIB.BASEBOARD_FAB2(SCH_1):GND
  189  GND            VSS<27>  @BASEBOARD_FAB2_LIB.BASEBOARD_FAB2(SCH_1):GND
  191  GND            VSS<26>  @BASEBOARD_FAB2_LIB.BASEBOARD_FAB2(SCH_1):GND
  193  GND            VSS<25>  @BASEBOARD_FAB2_LIB.BASEBOARD_FAB2(SCH_1):GND
  195  GND            VSS<24>  @BASEBOARD_FAB2_LIB.BASEBOARD_FAB2(SCH_1):GND
  198  GND            VSS<23>  @BASEBOARD_FAB2_LIB.BASEBOARD_FAB2(SCH_1):GND
  200  GND            VSS<22>  @BASEBOARD_FAB2_LIB.BASEBOARD_FAB2(SCH_1):GND
  202  GND            VSS<21>  @BASEBOARD_FAB2_LIB.BASEBOARD_FAB2(SCH_1):GND
  239  GND            VSS<20>  @BASEBOARD_FAB2_LIB.BASEBOARD_FAB2(SCH_1):GND
  241  GND            VSS<19>  @BASEBOARD_FAB2_LIB.BASEBOARD_FAB2(SCH_1):GND
  243  GND            VSS<18>  @BASEBOARD_FAB2_LIB.BASEBOARD_FAB2(SCH_1):GND
  246  GND            VSS<17>  @BASEBOARD_FAB2_LIB.BASEBOARD_FAB2(SCH_1):GND
  248  GND            VSS<16>  @BASEBOARD_FAB2_LIB.BASEBOARD_FAB2(SCH_1):GND
  250  GND            VSS<15>  @BASEBOARD_FAB2_LIB.BASEBOARD_FAB2(SCH_1):GND
  252  GND            VSS<14>  @BASEBOARD_FAB2_LIB.BASEBOARD_FAB2(SCH_1):GND
  254  GND            VSS<13>  @BASEBOARD_FAB2_LIB.BASEBOARD_FAB2(SCH_1):GND
  257  GND            VSS<12>  @BASEBOARD_FAB2_LIB.BASEBOARD_FAB2(SCH_1):GND
  259  GND            VSS<11>  @BASEBOARD_FAB2_LIB.BASEBOARD_FAB2(SCH_1):GND
  261  GND            VSS<10>  @BASEBOARD_FAB2_LIB.BASEBOARD_FAB2(SCH_1):GND
  263  GND            VSS<9>  @BASEBOARD_FAB2_LIB.BASEBOARD_FAB2(SCH_1):GND
  265  GND            VSS<8>  @BASEBOARD_FAB2_LIB.BASEBOARD_FAB2(SCH_1):GND
  268  GND            VSS<7>  @BASEBOARD_FAB2_LIB.BASEBOARD_FAB2(SCH_1):GND
  270  GND            VSS<6>  @BASEBOARD_FAB2_LIB.BASEBOARD_FAB2(SCH_1):GND
  272  GND            VSS<5>  @BASEBOARD_FAB2_LIB.BASEBOARD_FAB2(SCH_1):GND
  274  GND            VSS<4>  @BASEBOARD_FAB2_LIB.BASEBOARD_FAB2(SCH_1):GND
  276  GND            VSS<3>  @BASEBOARD_FAB2_LIB.BASEBOARD_FAB2(SCH_1):GND
  279  GND            VSS<2>  @BASEBOARD_FAB2_LIB.BASEBOARD_FAB2(SCH_1):GND
  281  GND            VSS<1>  @BASEBOARD_FAB2_LIB.BASEBOARD_FAB2(SCH_1):GND
  283  GND            VSS<0>  @BASEBOARD_FAB2_LIB.BASEBOARD_FAB2(SCH_1):GND

SCONN288_H44441003_PIP  I64  J9U2   [SCONN288_H44441003_PIP-SCONN,HA]
    7  M_J_DQS_DP<9>  DQS9P  @BASEBOARD_FAB2_LIB.BASEBOARD_FAB2(SCH_1):M_J_DQS_DP<9>
  197  M_J_DQS_DP<8>  DQS8P  @BASEBOARD_FAB2_LIB.BASEBOARD_FAB2(SCH_1):M_J_DQS_DP<8>
  278  M_J_DQS_DP<7>  DQS7P  @BASEBOARD_FAB2_LIB.BASEBOARD_FAB2(SCH_1):M_J_DQS_DP<7>
  267  M_J_DQS_DP<6>  DQS6P  @BASEBOARD_FAB2_LIB.BASEBOARD_FAB2(SCH_1):M_J_DQS_DP<6>
  256  M_J_DQS_DP<5>  DQS5P  @BASEBOARD_FAB2_LIB.BASEBOARD_FAB2(SCH_1):M_J_DQS_DP<5>
  245  M_J_DQS_DP<4>  DQS4P  @BASEBOARD_FAB2_LIB.BASEBOARD_FAB2(SCH_1):M_J_DQS_DP<4>
  186  M_J_DQS_DP<3>  DQS3P  @BASEBOARD_FAB2_LIB.BASEBOARD_FAB2(SCH_1):M_J_DQS_DP<3>
  175  M_J_DQS_DP<2>  DQS2P  @BASEBOARD_FAB2_LIB.BASEBOARD_FAB2(SCH_1):M_J_DQS_DP<2>
  164  M_J_DQS_DP<1>  DQS1P  @BASEBOARD_FAB2_LIB.BASEBOARD_FAB2(SCH_1):M_J_DQS_DP<1>
   51  M_J_DQS_DP<17>  DQS17P  @BASEBOARD_FAB2_LIB.BASEBOARD_FAB2(SCH_1):M_J_DQS_DP<17>
  132  M_J_DQS_DP<16>  DQS16P  @BASEBOARD_FAB2_LIB.BASEBOARD_FAB2(SCH_1):M_J_DQS_DP<16>
  121  M_J_DQS_DP<15>  DQS15P  @BASEBOARD_FAB2_LIB.BASEBOARD_FAB2(SCH_1):M_J_DQS_DP<15>
  110  M_J_DQS_DP<14>  DQS14P  @BASEBOARD_FAB2_LIB.BASEBOARD_FAB2(SCH_1):M_J_DQS_DP<14>
   99  M_J_DQS_DP<13>  DQS13P  @BASEBOARD_FAB2_LIB.BASEBOARD_FAB2(SCH_1):M_J_DQS_DP<13>
   40  M_J_DQS_DP<12>  DQS12P  @BASEBOARD_FAB2_LIB.BASEBOARD_FAB2(SCH_1):M_J_DQS_DP<12>
   29  M_J_DQS_DP<11>  DQS11P  @BASEBOARD_FAB2_LIB.BASEBOARD_FAB2(SCH_1):M_J_DQS_DP<11>
   18  M_J_DQS_DP<10>  DQS10P  @BASEBOARD_FAB2_LIB.BASEBOARD_FAB2(SCH_1):M_J_DQS_DP<10>
  153  M_J_DQS_DP<0>  DQS0P  @BASEBOARD_FAB2_LIB.BASEBOARD_FAB2(SCH_1):M_J_DQS_DP<0>
    8  M_J_DQS_DN<9>  DQS9N  @BASEBOARD_FAB2_LIB.BASEBOARD_FAB2(SCH_1):M_J_DQS_DN<9>
  196  M_J_DQS_DN<8>  DQS8N  @BASEBOARD_FAB2_LIB.BASEBOARD_FAB2(SCH_1):M_J_DQS_DN<8>
  277  M_J_DQS_DN<7>  DQS7N  @BASEBOARD_FAB2_LIB.BASEBOARD_FAB2(SCH_1):M_J_DQS_DN<7>
  266  M_J_DQS_DN<6>  DQS6N  @BASEBOARD_FAB2_LIB.BASEBOARD_FAB2(SCH_1):M_J_DQS_DN<6>
  255  M_J_DQS_DN<5>  DQS5N  @BASEBOARD_FAB2_LIB.BASEBOARD_FAB2(SCH_1):M_J_DQS_DN<5>
  244  M_J_DQS_DN<4>  DQS4N  @BASEBOARD_FAB2_LIB.BASEBOARD_FAB2(SCH_1):M_J_DQS_DN<4>
  185  M_J_DQS_DN<3>  DQS3N  @BASEBOARD_FAB2_LIB.BASEBOARD_FAB2(SCH_1):M_J_DQS_DN<3>
  174  M_J_DQS_DN<2>  DQS2N  @BASEBOARD_FAB2_LIB.BASEBOARD_FAB2(SCH_1):M_J_DQS_DN<2>
  163  M_J_DQS_DN<1>  DQS1N  @BASEBOARD_FAB2_LIB.BASEBOARD_FAB2(SCH_1):M_J_DQS_DN<1>
   52  M_J_DQS_DN<17>  DQS17N  @BASEBOARD_FAB2_LIB.BASEBOARD_FAB2(SCH_1):M_J_DQS_DN<17>
  133  M_J_DQS_DN<16>  DQS16N  @BASEBOARD_FAB2_LIB.BASEBOARD_FAB2(SCH_1):M_J_DQS_DN<16>
  122  M_J_DQS_DN<15>  DQS15N  @BASEBOARD_FAB2_LIB.BASEBOARD_FAB2(SCH_1):M_J_DQS_DN<15>
  111  M_J_DQS_DN<14>  DQS14N  @BASEBOARD_FAB2_LIB.BASEBOARD_FAB2(SCH_1):M_J_DQS_DN<14>
  100  M_J_DQS_DN<13>  DQS13N  @BASEBOARD_FAB2_LIB.BASEBOARD_FAB2(SCH_1):M_J_DQS_DN<13>
   41  M_J_DQS_DN<12>  DQS12N  @BASEBOARD_FAB2_LIB.BASEBOARD_FAB2(SCH_1):M_J_DQS_DN<12>
   30  M_J_DQS_DN<11>  DQS11N  @BASEBOARD_FAB2_LIB.BASEBOARD_FAB2(SCH_1):M_J_DQS_DN<11>
   19  M_J_DQS_DN<10>  DQS10N  @BASEBOARD_FAB2_LIB.BASEBOARD_FAB2(SCH_1):M_J_DQS_DN<10>
  152  M_J_DQS_DN<0>  DQS0N  @BASEBOARD_FAB2_LIB.BASEBOARD_FAB2(SCH_1):M_J_DQS_DN<0>

SCONN288_H44441003_PIP  I187  J9U2   [SCONN288_H44441003_PIP-SCONN,HA]
  144  TP_CH_J_DIMM_J1_RFU_2  RFU<2>  @BASEBOARD_FAB2_LIB.BASEBOARD_FAB2(SCH_1):TP_CH_J_DIMM_J1_RFU_2
  227  TP_CH_J_DIMM_J1_RFU_1  RFU<1>  @BASEBOARD_FAB2_LIB.BASEBOARD_FAB2(SCH_1):TP_CH_J_DIMM_J1_RFU_1
  205  TP_CH_J_DIMM_J1_RFU_0  RFU<0>  @BASEBOARD_FAB2_LIB.BASEBOARD_FAB2(SCH_1):TP_CH_J_DIMM_J1_RFU_0
  285  SMB_DDR_GHJ_VPP_SDA    SDA  @BASEBOARD_FAB2_LIB.BASEBOARD_FAB2(SCH_1):SMB_DDR_GHJ_VPP_SDA
  141  SMB_DDR_GHJ_VPP_SCL    SCL  @BASEBOARD_FAB2_LIB.BASEBOARD_FAB2(SCH_1):SMB_DDR_GHJ_VPP_SCL
  284  PVPP_GHJ       VDDSPD  @BASEBOARD_FAB2_LIB.BASEBOARD_FAB2(SCH_1):PVPP_GHJ
  238  PVPP_GHJ       SA<2>  @BASEBOARD_FAB2_LIB.BASEBOARD_FAB2(SCH_1):PVPP_GHJ
  139  PVPP_GHJ       SA<0>  @BASEBOARD_FAB2_LIB.BASEBOARD_FAB2(SCH_1):PVPP_GHJ
  146  M_J_VREF       VREFCA  @BASEBOARD_FAB2_LIB.BASEBOARD_FAB2(SCH_1):M_J_VREF
  222  M_J_PAR          PAR  @BASEBOARD_FAB2_LIB.BASEBOARD_FAB2(SCH_1):M_J_PAR
   91  M_J_ODT<3>     ODT<1>  @BASEBOARD_FAB2_LIB.BASEBOARD_FAB2(SCH_1):M_J_ODT<3>
   87  M_J_ODT<2>     ODT<0>  @BASEBOARD_FAB2_LIB.BASEBOARD_FAB2(SCH_1):M_J_ODT<2>
   66  M_J_MA<9>         A9  @BASEBOARD_FAB2_LIB.BASEBOARD_FAB2(SCH_1):M_J_MA<9>
   68  M_J_MA<8>         A8  @BASEBOARD_FAB2_LIB.BASEBOARD_FAB2(SCH_1):M_J_MA<8>
  211  M_J_MA<7>         A7  @BASEBOARD_FAB2_LIB.BASEBOARD_FAB2(SCH_1):M_J_MA<7>
   69  M_J_MA<6>         A6  @BASEBOARD_FAB2_LIB.BASEBOARD_FAB2(SCH_1):M_J_MA<6>
  213  M_J_MA<5>         A5  @BASEBOARD_FAB2_LIB.BASEBOARD_FAB2(SCH_1):M_J_MA<5>
  214  M_J_MA<4>         A4  @BASEBOARD_FAB2_LIB.BASEBOARD_FAB2(SCH_1):M_J_MA<4>
   71  M_J_MA<3>         A3  @BASEBOARD_FAB2_LIB.BASEBOARD_FAB2(SCH_1):M_J_MA<3>
  216  M_J_MA<2>         A2  @BASEBOARD_FAB2_LIB.BASEBOARD_FAB2(SCH_1):M_J_MA<2>
   72  M_J_MA<1>         A1  @BASEBOARD_FAB2_LIB.BASEBOARD_FAB2(SCH_1):M_J_MA<1>
  234  M_J_MA<17>       A17  @BASEBOARD_FAB2_LIB.BASEBOARD_FAB2(SCH_1):M_J_MA<17>
   82  M_J_MA<16>     A16_RAS_N  @BASEBOARD_FAB2_LIB.BASEBOARD_FAB2(SCH_1):M_J_MA<16>
   86  M_J_MA<15>     A15_CAS_N  @BASEBOARD_FAB2_LIB.BASEBOARD_FAB2(SCH_1):M_J_MA<15>
  228  M_J_MA<14>     A14_WE_N  @BASEBOARD_FAB2_LIB.BASEBOARD_FAB2(SCH_1):M_J_MA<14>
  232  M_J_MA<13>       A13  @BASEBOARD_FAB2_LIB.BASEBOARD_FAB2(SCH_1):M_J_MA<13>
   65  M_J_MA<12>       A12  @BASEBOARD_FAB2_LIB.BASEBOARD_FAB2(SCH_1):M_J_MA<12>
  210  M_J_MA<11>       A11  @BASEBOARD_FAB2_LIB.BASEBOARD_FAB2(SCH_1):M_J_MA<11>
  225  M_J_MA<10>       A10  @BASEBOARD_FAB2_LIB.BASEBOARD_FAB2(SCH_1):M_J_MA<10>
   79  M_J_MA<0>         A0  @BASEBOARD_FAB2_LIB.BASEBOARD_FAB2(SCH_1):M_J_MA<0>
  199  M_J_ECC<7>     CB<7>  @BASEBOARD_FAB2_LIB.BASEBOARD_FAB2(SCH_1):M_J_ECC<7>
   54  M_J_ECC<6>     CB<6>  @BASEBOARD_FAB2_LIB.BASEBOARD_FAB2(SCH_1):M_J_ECC<6>
  192  M_J_ECC<5>     CB<5>  @BASEBOARD_FAB2_LIB.BASEBOARD_FAB2(SCH_1):M_J_ECC<5>
   47  M_J_ECC<4>     CB<4>  @BASEBOARD_FAB2_LIB.BASEBOARD_FAB2(SCH_1):M_J_ECC<4>
  201  M_J_ECC<3>     CB<3>  @BASEBOARD_FAB2_LIB.BASEBOARD_FAB2(SCH_1):M_J_ECC<3>
   56  M_J_ECC<2>     CB<2>  @BASEBOARD_FAB2_LIB.BASEBOARD_FAB2(SCH_1):M_J_ECC<2>
  194  M_J_ECC<1>     CB<1>  @BASEBOARD_FAB2_LIB.BASEBOARD_FAB2(SCH_1):M_J_ECC<1>
   49  M_J_ECC<0>     CB<0>  @BASEBOARD_FAB2_LIB.BASEBOARD_FAB2(SCH_1):M_J_ECC<0>
  161  M_J_DQ<9>      DQ<9>  @BASEBOARD_FAB2_LIB.BASEBOARD_FAB2(SCH_1):M_J_DQ<9>
   16  M_J_DQ<8>      DQ<8>  @BASEBOARD_FAB2_LIB.BASEBOARD_FAB2(SCH_1):M_J_DQ<8>
  155  M_J_DQ<7>      DQ<7>  @BASEBOARD_FAB2_LIB.BASEBOARD_FAB2(SCH_1):M_J_DQ<7>
   10  M_J_DQ<6>      DQ<6>  @BASEBOARD_FAB2_LIB.BASEBOARD_FAB2(SCH_1):M_J_DQ<6>
  280  M_J_DQ<63>     DQ<63>  @BASEBOARD_FAB2_LIB.BASEBOARD_FAB2(SCH_1):M_J_DQ<63>
  135  M_J_DQ<62>     DQ<62>  @BASEBOARD_FAB2_LIB.BASEBOARD_FAB2(SCH_1):M_J_DQ<62>
  273  M_J_DQ<61>     DQ<61>  @BASEBOARD_FAB2_LIB.BASEBOARD_FAB2(SCH_1):M_J_DQ<61>
  128  M_J_DQ<60>     DQ<60>  @BASEBOARD_FAB2_LIB.BASEBOARD_FAB2(SCH_1):M_J_DQ<60>
  148  M_J_DQ<5>      DQ<5>  @BASEBOARD_FAB2_LIB.BASEBOARD_FAB2(SCH_1):M_J_DQ<5>
  282  M_J_DQ<59>     DQ<59>  @BASEBOARD_FAB2_LIB.BASEBOARD_FAB2(SCH_1):M_J_DQ<59>
  137  M_J_DQ<58>     DQ<58>  @BASEBOARD_FAB2_LIB.BASEBOARD_FAB2(SCH_1):M_J_DQ<58>
  275  M_J_DQ<57>     DQ<57>  @BASEBOARD_FAB2_LIB.BASEBOARD_FAB2(SCH_1):M_J_DQ<57>
  130  M_J_DQ<56>     DQ<56>  @BASEBOARD_FAB2_LIB.BASEBOARD_FAB2(SCH_1):M_J_DQ<56>
  269  M_J_DQ<55>     DQ<55>  @BASEBOARD_FAB2_LIB.BASEBOARD_FAB2(SCH_1):M_J_DQ<55>
  124  M_J_DQ<54>     DQ<54>  @BASEBOARD_FAB2_LIB.BASEBOARD_FAB2(SCH_1):M_J_DQ<54>
  262  M_J_DQ<53>     DQ<53>  @BASEBOARD_FAB2_LIB.BASEBOARD_FAB2(SCH_1):M_J_DQ<53>
  117  M_J_DQ<52>     DQ<52>  @BASEBOARD_FAB2_LIB.BASEBOARD_FAB2(SCH_1):M_J_DQ<52>
  271  M_J_DQ<51>     DQ<51>  @BASEBOARD_FAB2_LIB.BASEBOARD_FAB2(SCH_1):M_J_DQ<51>
  126  M_J_DQ<50>     DQ<50>  @BASEBOARD_FAB2_LIB.BASEBOARD_FAB2(SCH_1):M_J_DQ<50>
    3  M_J_DQ<4>      DQ<4>  @BASEBOARD_FAB2_LIB.BASEBOARD_FAB2(SCH_1):M_J_DQ<4>
  264  M_J_DQ<49>     DQ<49>  @BASEBOARD_FAB2_LIB.BASEBOARD_FAB2(SCH_1):M_J_DQ<49>
  119  M_J_DQ<48>     DQ<48>  @BASEBOARD_FAB2_LIB.BASEBOARD_FAB2(SCH_1):M_J_DQ<48>
  258  M_J_DQ<47>     DQ<47>  @BASEBOARD_FAB2_LIB.BASEBOARD_FAB2(SCH_1):M_J_DQ<47>
  113  M_J_DQ<46>     DQ<46>  @BASEBOARD_FAB2_LIB.BASEBOARD_FAB2(SCH_1):M_J_DQ<46>
  251  M_J_DQ<45>     DQ<45>  @BASEBOARD_FAB2_LIB.BASEBOARD_FAB2(SCH_1):M_J_DQ<45>
  106  M_J_DQ<44>     DQ<44>  @BASEBOARD_FAB2_LIB.BASEBOARD_FAB2(SCH_1):M_J_DQ<44>
  260  M_J_DQ<43>     DQ<43>  @BASEBOARD_FAB2_LIB.BASEBOARD_FAB2(SCH_1):M_J_DQ<43>
  115  M_J_DQ<42>     DQ<42>  @BASEBOARD_FAB2_LIB.BASEBOARD_FAB2(SCH_1):M_J_DQ<42>
  253  M_J_DQ<41>     DQ<41>  @BASEBOARD_FAB2_LIB.BASEBOARD_FAB2(SCH_1):M_J_DQ<41>
  108  M_J_DQ<40>     DQ<40>  @BASEBOARD_FAB2_LIB.BASEBOARD_FAB2(SCH_1):M_J_DQ<40>
  157  M_J_DQ<3>      DQ<3>  @BASEBOARD_FAB2_LIB.BASEBOARD_FAB2(SCH_1):M_J_DQ<3>
  247  M_J_DQ<39>     DQ<39>  @BASEBOARD_FAB2_LIB.BASEBOARD_FAB2(SCH_1):M_J_DQ<39>
  102  M_J_DQ<38>     DQ<38>  @BASEBOARD_FAB2_LIB.BASEBOARD_FAB2(SCH_1):M_J_DQ<38>
  240  M_J_DQ<37>     DQ<37>  @BASEBOARD_FAB2_LIB.BASEBOARD_FAB2(SCH_1):M_J_DQ<37>
   95  M_J_DQ<36>     DQ<36>  @BASEBOARD_FAB2_LIB.BASEBOARD_FAB2(SCH_1):M_J_DQ<36>
  249  M_J_DQ<35>     DQ<35>  @BASEBOARD_FAB2_LIB.BASEBOARD_FAB2(SCH_1):M_J_DQ<35>
  104  M_J_DQ<34>     DQ<34>  @BASEBOARD_FAB2_LIB.BASEBOARD_FAB2(SCH_1):M_J_DQ<34>
  242  M_J_DQ<33>     DQ<33>  @BASEBOARD_FAB2_LIB.BASEBOARD_FAB2(SCH_1):M_J_DQ<33>
   97  M_J_DQ<32>     DQ<32>  @BASEBOARD_FAB2_LIB.BASEBOARD_FAB2(SCH_1):M_J_DQ<32>
  188  M_J_DQ<31>     DQ<31>  @BASEBOARD_FAB2_LIB.BASEBOARD_FAB2(SCH_1):M_J_DQ<31>
   43  M_J_DQ<30>     DQ<30>  @BASEBOARD_FAB2_LIB.BASEBOARD_FAB2(SCH_1):M_J_DQ<30>
   12  M_J_DQ<2>      DQ<2>  @BASEBOARD_FAB2_LIB.BASEBOARD_FAB2(SCH_1):M_J_DQ<2>
  181  M_J_DQ<29>     DQ<29>  @BASEBOARD_FAB2_LIB.BASEBOARD_FAB2(SCH_1):M_J_DQ<29>
   36  M_J_DQ<28>     DQ<28>  @BASEBOARD_FAB2_LIB.BASEBOARD_FAB2(SCH_1):M_J_DQ<28>
  190  M_J_DQ<27>     DQ<27>  @BASEBOARD_FAB2_LIB.BASEBOARD_FAB2(SCH_1):M_J_DQ<27>
   45  M_J_DQ<26>     DQ<26>  @BASEBOARD_FAB2_LIB.BASEBOARD_FAB2(SCH_1):M_J_DQ<26>
  183  M_J_DQ<25>     DQ<25>  @BASEBOARD_FAB2_LIB.BASEBOARD_FAB2(SCH_1):M_J_DQ<25>
   38  M_J_DQ<24>     DQ<24>  @BASEBOARD_FAB2_LIB.BASEBOARD_FAB2(SCH_1):M_J_DQ<24>
  177  M_J_DQ<23>     DQ<23>  @BASEBOARD_FAB2_LIB.BASEBOARD_FAB2(SCH_1):M_J_DQ<23>
   32  M_J_DQ<22>     DQ<22>  @BASEBOARD_FAB2_LIB.BASEBOARD_FAB2(SCH_1):M_J_DQ<22>
  170  M_J_DQ<21>     DQ<21>  @BASEBOARD_FAB2_LIB.BASEBOARD_FAB2(SCH_1):M_J_DQ<21>
   25  M_J_DQ<20>     DQ<20>  @BASEBOARD_FAB2_LIB.BASEBOARD_FAB2(SCH_1):M_J_DQ<20>
  150  M_J_DQ<1>      DQ<1>  @BASEBOARD_FAB2_LIB.BASEBOARD_FAB2(SCH_1):M_J_DQ<1>
  179  M_J_DQ<19>     DQ<19>  @BASEBOARD_FAB2_LIB.BASEBOARD_FAB2(SCH_1):M_J_DQ<19>
   34  M_J_DQ<18>     DQ<18>  @BASEBOARD_FAB2_LIB.BASEBOARD_FAB2(SCH_1):M_J_DQ<18>
  172  M_J_DQ<17>     DQ<17>  @BASEBOARD_FAB2_LIB.BASEBOARD_FAB2(SCH_1):M_J_DQ<17>
   27  M_J_DQ<16>     DQ<16>  @BASEBOARD_FAB2_LIB.BASEBOARD_FAB2(SCH_1):M_J_DQ<16>
  166  M_J_DQ<15>     DQ<15>  @BASEBOARD_FAB2_LIB.BASEBOARD_FAB2(SCH_1):M_J_DQ<15>
   21  M_J_DQ<14>     DQ<14>  @BASEBOARD_FAB2_LIB.BASEBOARD_FAB2(SCH_1):M_J_DQ<14>
  159  M_J_DQ<13>     DQ<13>  @BASEBOARD_FAB2_LIB.BASEBOARD_FAB2(SCH_1):M_J_DQ<13>
   14  M_J_DQ<12>     DQ<12>  @BASEBOARD_FAB2_LIB.BASEBOARD_FAB2(SCH_1):M_J_DQ<12>
  168  M_J_DQ<11>     DQ<11>  @BASEBOARD_FAB2_LIB.BASEBOARD_FAB2(SCH_1):M_J_DQ<11>
   23  M_J_DQ<10>     DQ<10>  @BASEBOARD_FAB2_LIB.BASEBOARD_FAB2(SCH_1):M_J_DQ<10>
    5  M_J_DQ<0>      DQ<0>  @BASEBOARD_FAB2_LIB.BASEBOARD_FAB2(SCH_1):M_J_DQ<0>
  237  M_J_CS_N<7>    S3_N_C<1>  @BASEBOARD_FAB2_LIB.BASEBOARD_FAB2(SCH_1):M_J_CS_N<7>
   93  M_J_CS_N<6>    S2_N_C<0>  @BASEBOARD_FAB2_LIB.BASEBOARD_FAB2(SCH_1):M_J_CS_N<6>
   89  M_J_CS_N<5>     S1_N  @BASEBOARD_FAB2_LIB.BASEBOARD_FAB2(SCH_1):M_J_CS_N<5>
   84  M_J_CS_N<4>     S0_N  @BASEBOARD_FAB2_LIB.BASEBOARD_FAB2(SCH_1):M_J_CS_N<4>
  218  M_J_CLK_DP<3>   CK1P  @BASEBOARD_FAB2_LIB.BASEBOARD_FAB2(SCH_1):M_J_CLK_DP<3>
   74  M_J_CLK_DP<2>   CK0P  @BASEBOARD_FAB2_LIB.BASEBOARD_FAB2(SCH_1):M_J_CLK_DP<2>
  219  M_J_CLK_DN<3>   CK1N  @BASEBOARD_FAB2_LIB.BASEBOARD_FAB2(SCH_1):M_J_CLK_DN<3>
   75  M_J_CLK_DN<2>   CK0N  @BASEBOARD_FAB2_LIB.BASEBOARD_FAB2(SCH_1):M_J_CLK_DN<2>
  203  M_J_CKE<3>     CKE<1>  @BASEBOARD_FAB2_LIB.BASEBOARD_FAB2(SCH_1):M_J_CKE<3>
   60  M_J_CKE<2>     CKE<0>  @BASEBOARD_FAB2_LIB.BASEBOARD_FAB2(SCH_1):M_J_CKE<2>
  235  M_J_C<2>        C<2>  @BASEBOARD_FAB2_LIB.BASEBOARD_FAB2(SCH_1):M_J_C<2>
  207  M_J_BG<1>      BG<1>  @BASEBOARD_FAB2_LIB.BASEBOARD_FAB2(SCH_1):M_J_BG<1>
   63  M_J_BG<0>      BG<0>  @BASEBOARD_FAB2_LIB.BASEBOARD_FAB2(SCH_1):M_J_BG<0>
  224  M_J_BA<1>      BA<1>  @BASEBOARD_FAB2_LIB.BASEBOARD_FAB2(SCH_1):M_J_BA<1>
   81  M_J_BA<0>      BA<0>  @BASEBOARD_FAB2_LIB.BASEBOARD_FAB2(SCH_1):M_J_BA<0>
  208  M_J_ALERT_N    ALERT_N  @BASEBOARD_FAB2_LIB.BASEBOARD_FAB2(SCH_1):M_J_ALERT_N
   62  M_J_ACT_N      ACT_N  @BASEBOARD_FAB2_LIB.BASEBOARD_FAB2(SCH_1):M_J_ACT_N
   58  M_GHJ_RST_N    RESET_N  @BASEBOARD_FAB2_LIB.BASEBOARD_FAB2(SCH_1):M_GHJ_RST_N
  140  GND            SA<1>  @BASEBOARD_FAB2_LIB.BASEBOARD_FAB2(SCH_1):GND
   78  FM_DIMM_EVENT_COD_N  EVENT_N  @BASEBOARD_FAB2_LIB.BASEBOARD_FAB2(SCH_1):FM_DIMM_EVENT_COD_N
  230  FM_ADR_COMPLETE_GHJ_N  SAVE_N_NC  @BASEBOARD_FAB2_LIB.BASEBOARD_FAB2(SCH_1):FM_ADR_COMPLETE_GHJ_N

CONN17_H71061002_PIP1  I109  JA9G1  [CONN17_H71061002_PIP1-CONN,H71A]
   L2  P3V3_STBY         L2  @BASEBOARD_FAB2_LIB.BASEBOARD_FAB2(SCH_1):P3V3_STBY
   R8  NIC_MDI_SPRV_RJ45_3_R_DP  TRD4P  @BASEBOARD_FAB2_LIB.BASEBOARD_FAB2(SCH_1):NIC_MDI_SPRV_RJ45_3_R_DP
   R9  NIC_MDI_SPRV_RJ45_3_R_DN  TRD4N  @BASEBOARD_FAB2_LIB.BASEBOARD_FAB2(SCH_1):NIC_MDI_SPRV_RJ45_3_R_DN
   R3  NIC_MDI_SPRV_RJ45_2_R_DP  TRD3P  @BASEBOARD_FAB2_LIB.BASEBOARD_FAB2(SCH_1):NIC_MDI_SPRV_RJ45_2_R_DP
   R2  NIC_MDI_SPRV_RJ45_2_R_DN  TRD3N  @BASEBOARD_FAB2_LIB.BASEBOARD_FAB2(SCH_1):NIC_MDI_SPRV_RJ45_2_R_DN
   R4  NIC_MDI_SPRV_RJ45_1_R_DP  TRD2P  @BASEBOARD_FAB2_LIB.BASEBOARD_FAB2(SCH_1):NIC_MDI_SPRV_RJ45_1_R_DP
   R5  NIC_MDI_SPRV_RJ45_1_R_DN  TRD2N  @BASEBOARD_FAB2_LIB.BASEBOARD_FAB2(SCH_1):NIC_MDI_SPRV_RJ45_1_R_DN
  R11  NIC_MDI_SPRV_RJ45_0_R_DP  TRD1P  @BASEBOARD_FAB2_LIB.BASEBOARD_FAB2(SCH_1):NIC_MDI_SPRV_RJ45_0_R_DP
  R10  NIC_MDI_SPRV_RJ45_0_R_DN  TRD1N  @BASEBOARD_FAB2_LIB.BASEBOARD_FAB2(SCH_1):NIC_MDI_SPRV_RJ45_0_R_DN
   L4  NIC_LED_ACT_ANODE_R     L4  @BASEBOARD_FAB2_LIB.BASEBOARD_FAB2(SCH_1):NIC_LED_ACT_ANODE_R
   L3  LED_LAN_2_R_N     L3  @BASEBOARD_FAB2_LIB.BASEBOARD_FAB2(SCH_1):LED_LAN_2_R_N
   L5  LED_LAN_1_R_N     L5  @BASEBOARD_FAB2_LIB.BASEBOARD_FAB2(SCH_1):LED_LAN_1_R_N
   L1  LED_LAN_0_R_N     L1  @BASEBOARD_FAB2_LIB.BASEBOARD_FAB2(SCH_1):LED_LAN_0_R_N
  MH2  GND_NIC          MH2  @BASEBOARD_FAB2_LIB.BASEBOARD_FAB2(SCH_1):GND_NIC
  MH1  GND_NIC          MH1  @BASEBOARD_FAB2_LIB.BASEBOARD_FAB2(SCH_1):GND_NIC
   R7  GND_LAN_TRCT1234_C  TRCT4  @BASEBOARD_FAB2_LIB.BASEBOARD_FAB2(SCH_1):GND_LAN_TRCT1234_C
   R1  GND_LAN_TRCT1234_C  TRCT3  @BASEBOARD_FAB2_LIB.BASEBOARD_FAB2(SCH_1):GND_LAN_TRCT1234_C
   R6  GND_LAN_TRCT1234_C  TRCT2  @BASEBOARD_FAB2_LIB.BASEBOARD_FAB2(SCH_1):GND_LAN_TRCT1234_C
  R12  GND_LAN_TRCT1234_C  TRCT1  @BASEBOARD_FAB2_LIB.BASEBOARD_FAB2(SCH_1):GND_LAN_TRCT1234_C

INDUCTOR  I65  L1A1   [INDUCTOR_SM-0.12UH,IND,D92183-A]
    1  VR_PVDDQ_KLM_PH2_SW    INA  @BASEBOARD_FAB2_LIB.BASEBOARD_FAB2(SCH_1):VR_PVDDQ_KLM_PH2_SW
    2  PVDDQ_KLM        INB  @BASEBOARD_FAB2_LIB.BASEBOARD_FAB2(SCH_1):PVDDQ_KLM

INDUCTOR  I55  L1A2   [INDUCTOR_SM-0.12UH,IND,D92183-A]
    1  VR_PVDDQ_KLM_PH1_SW    INA  @BASEBOARD_FAB2_LIB.BASEBOARD_FAB2(SCH_1):VR_PVDDQ_KLM_PH1_SW
    2  PVDDQ_KLM        INB  @BASEBOARD_FAB2_LIB.BASEBOARD_FAB2(SCH_1):PVDDQ_KLM

INDUCTOR  I124  L1B1   [INDUCTOR_SM-100NH,IND,D92183-0B]
    2  VR_FET_SW_P12V_STBY_PVDDQ_KLM    INB  @BASEBOARD_FAB2_LIB.BASEBOARD_FAB2(SCH_1):VR_FET_SW_P12V_STBY_PVDDQ_KLM
    1  P12V_STBY        INA  @BASEBOARD_FAB2_LIB.BASEBOARD_FAB2(SCH_1):P12V_STBY

INDUCTOR  I32  L1B2   [INDUCTOR_SM-100NH,IND,D92183-0A]
    2  VR_FET_SW_P12V_PVCCIN_CPU1_R    INB  @BASEBOARD_FAB2_LIB.BASEBOARD_FAB2(SCH_1):VR_FET_SW_P12V_PVCCIN_CPU1_R
    1  P12V_STBY        INA  @BASEBOARD_FAB2_LIB.BASEBOARD_FAB2(SCH_1):P12V_STBY

INDUCTOR  I10  L1C1   [INDUCTOR_SM-0.3UH,IND,D92183-0A]
    1  VR_PVSA_CPU1_PHASE_SW    INA  @BASEBOARD_FAB2_LIB.BASEBOARD_FAB2(SCH_1):VR_PVSA_CPU1_PHASE_SW
    2  PVSA_CPU1        INB  @BASEBOARD_FAB2_LIB.BASEBOARD_FAB2(SCH_1):PVSA_CPU1

INDUCTOR  I40  L1C2   [INDUCTOR_SM-0.12UH,IND,D92183-A]
    1  VR_PVCCIN_CPU1_PHASE5    INA  @BASEBOARD_FAB2_LIB.BASEBOARD_FAB2(SCH_1):VR_PVCCIN_CPU1_PHASE5
    2  PVCCIN_CPU1      INB  @BASEBOARD_FAB2_LIB.BASEBOARD_FAB2(SCH_1):PVCCIN_CPU1

INDUCTOR  I20  L1D1   [INDUCTOR_SM-0.12UH,IND,D92183-A]
    1  VR_PVCCIN_CPU1_PHASE4    INA  @BASEBOARD_FAB2_LIB.BASEBOARD_FAB2(SCH_1):VR_PVCCIN_CPU1_PHASE4
    2  PVCCIN_CPU1      INB  @BASEBOARD_FAB2_LIB.BASEBOARD_FAB2(SCH_1):PVCCIN_CPU1

INDUCTOR  I11  L1D2   [INDUCTOR_SM-0.12UH,IND,D92183-A]
    1  VR_PVCCIN_CPU1_PHASE3    INA  @BASEBOARD_FAB2_LIB.BASEBOARD_FAB2(SCH_1):VR_PVCCIN_CPU1_PHASE3
    2  PVCCIN_CPU1      INB  @BASEBOARD_FAB2_LIB.BASEBOARD_FAB2(SCH_1):PVCCIN_CPU1

INDUCTOR  I16  L1D3   [INDUCTOR_SM-0.12UH,IND,D92183-A]
    1  VR_PVCCIN_CPU1_PHASE2    INA  @BASEBOARD_FAB2_LIB.BASEBOARD_FAB2(SCH_1):VR_PVCCIN_CPU1_PHASE2
    2  PVCCIN_CPU1      INB  @BASEBOARD_FAB2_LIB.BASEBOARD_FAB2(SCH_1):PVCCIN_CPU1

INDUCTOR  I10  L1E1   [INDUCTOR_SM-0.12UH,IND,D92183-A]
    1  VR_PVCCIN_CPU1_PHASE1    INA  @BASEBOARD_FAB2_LIB.BASEBOARD_FAB2(SCH_1):VR_PVCCIN_CPU1_PHASE1
    2  PVCCIN_CPU1      INB  @BASEBOARD_FAB2_LIB.BASEBOARD_FAB2(SCH_1):PVCCIN_CPU1

INDUCTOR  I124  L1F1   [INDUCTOR_SM-100NH,IND,D92183-0B]
    2  VR_FET_SW_P12V_STBY_PVDDQ_GHJ    INB  @BASEBOARD_FAB2_LIB.BASEBOARD_FAB2(SCH_1):VR_FET_SW_P12V_STBY_PVDDQ_GHJ
    1  P12V_STBY        INA  @BASEBOARD_FAB2_LIB.BASEBOARD_FAB2(SCH_1):P12V_STBY

INDUCTOR  I65  L1F2   [INDUCTOR_SM-0.12UH,IND,D92183-A]
    1  VR_PVDDQ_GHJ_PH2_SW    INA  @BASEBOARD_FAB2_LIB.BASEBOARD_FAB2(SCH_1):VR_PVDDQ_GHJ_PH2_SW
    2  PVDDQ_GHJ        INB  @BASEBOARD_FAB2_LIB.BASEBOARD_FAB2(SCH_1):PVDDQ_GHJ

INDUCTOR  I55  L1G1   [INDUCTOR_SM-0.12UH,IND,D92183-A]
    1  VR_PVDDQ_GHJ_PH1_SW    INA  @BASEBOARD_FAB2_LIB.BASEBOARD_FAB2(SCH_1):VR_PVDDQ_GHJ_PH1_SW
    2  PVDDQ_GHJ        INB  @BASEBOARD_FAB2_LIB.BASEBOARD_FAB2(SCH_1):PVDDQ_GHJ

CHOKE_4PIN_SM_B  I51  L1L1   [CHOKE_4PIN_SM_B-67 OHM,EMPTY,7A]
    4  USB3_P01_RXP       4  @BASEBOARD_FAB2_LIB.BASEBOARD_FAB2(SCH_1):USB3_P01_RXP
    1  USB3_P01_RXN       1  @BASEBOARD_FAB2_LIB.BASEBOARD_FAB2(SCH_1):USB3_P01_RXN
    3  USB3_P01_FB_RXP      3  @BASEBOARD_FAB2_LIB.BASEBOARD_FAB2(SCH_1):USB3_P01_FB_RXP
    2  USB3_P01_FB_RXN      2  @BASEBOARD_FAB2_LIB.BASEBOARD_FAB2(SCH_1):USB3_P01_FB_RXN

CHOKE_4PIN_SM_B  I62  L1M1   [CHOKE_4PIN_SM_B-67 OHM,EMPTY,7A]
    3  USB3_P01_FB_TXP      3  @BASEBOARD_FAB2_LIB.BASEBOARD_FAB2(SCH_1):USB3_P01_FB_TXP
    2  USB3_P01_FB_TXN      2  @BASEBOARD_FAB2_LIB.BASEBOARD_FAB2(SCH_1):USB3_P01_FB_TXN
    4  USB3_P01_C_TXP      4  @BASEBOARD_FAB2_LIB.BASEBOARD_FAB2(SCH_1):USB3_P01_C_TXP
    1  USB3_P01_C_TXN      1  @BASEBOARD_FAB2_LIB.BASEBOARD_FAB2(SCH_1):USB3_P01_C_TXN

CHOKE_4PIN  I30  L1M2   [CHOKE_4PIN_SMLF-90 OHM,EMPTY,7A]
    3  USB2_P01_ESD_DP     B1  @BASEBOARD_FAB2_LIB.BASEBOARD_FAB2(SCH_1):USB2_P01_ESD_DP
    4  USB2_P01_ESD_DN     B2  @BASEBOARD_FAB2_LIB.BASEBOARD_FAB2(SCH_1):USB2_P01_ESD_DN
    2  USB2_P01_DP       A2  @BASEBOARD_FAB2_LIB.BASEBOARD_FAB2(SCH_1):USB2_P01_DP
    1  USB2_P01_DN       A1  @BASEBOARD_FAB2_LIB.BASEBOARD_FAB2(SCH_1):USB2_P01_DN

INDUCTOR  I71  L2M1   [INDUCTOR_SMT-0.022UH,IND,72189A]
    2  P1V05_PCH_STBY_KR_PLL    INB  @BASEBOARD_FAB2_LIB.BASEBOARD_FAB2(SCH_1):P1V05_PCH_STBY_KR_PLL
    1  P1V05_PCH_STBY    INA  @BASEBOARD_FAB2_LIB.BASEBOARD_FAB2(SCH_1):P1V05_PCH_STBY

INDUCTOR  I164  L4A1   [INDUCTOR_SM-0.47UH,IND,E13358-A]
    1  VR_PVPP_KLM_PHASE    INA  @BASEBOARD_FAB2_LIB.BASEBOARD_FAB2(SCH_1):VR_PVPP_KLM_PHASE
    2  PVPP_KLM         INB  @BASEBOARD_FAB2_LIB.BASEBOARD_FAB2(SCH_1):PVPP_KLM

INDUCTOR  I46  L4C1   [INDUCTOR_SM-100NH,IND,D92183-0A]
    2  VR_FET_SW_P12V_PVCCIN_CPU0_R    INB  @BASEBOARD_FAB2_LIB.BASEBOARD_FAB2(SCH_1):VR_FET_SW_P12V_PVCCIN_CPU0_R
    1  P12V_STBY        INA  @BASEBOARD_FAB2_LIB.BASEBOARD_FAB2(SCH_1):P12V_STBY

INDUCTOR  I7   L4C2   [INDUCTOR_SM-0.3UH,IND,D92183-0A]
    1  VR_PVSA_CPU0_PHASE_SW    INA  @BASEBOARD_FAB2_LIB.BASEBOARD_FAB2(SCH_1):VR_PVSA_CPU0_PHASE_SW
    2  PVSA_CPU0        INB  @BASEBOARD_FAB2_LIB.BASEBOARD_FAB2(SCH_1):PVSA_CPU0

INDUCTOR  I5   L4C3   [INDUCTOR_SM-0.12UH,IND,D92183-A]
    1  VR_PVCCIN_CPU0_PHASE5    INA  @BASEBOARD_FAB2_LIB.BASEBOARD_FAB2(SCH_1):VR_PVCCIN_CPU0_PHASE5
    2  PVCCIN_CPU0      INB  @BASEBOARD_FAB2_LIB.BASEBOARD_FAB2(SCH_1):PVCCIN_CPU0

INDUCTOR  I24  L4D1   [INDUCTOR_SM-0.12UH,IND,D92183-A]
    1  VR_PVCCIN_CPU0_PHASE4    INA  @BASEBOARD_FAB2_LIB.BASEBOARD_FAB2(SCH_1):VR_PVCCIN_CPU0_PHASE4
    2  PVCCIN_CPU0      INB  @BASEBOARD_FAB2_LIB.BASEBOARD_FAB2(SCH_1):PVCCIN_CPU0

INDUCTOR  I15  L4D2   [INDUCTOR_SM-0.12UH,IND,D92183-A]
    1  VR_PVCCIN_CPU0_PHASE3    INA  @BASEBOARD_FAB2_LIB.BASEBOARD_FAB2(SCH_1):VR_PVCCIN_CPU0_PHASE3
    2  PVCCIN_CPU0      INB  @BASEBOARD_FAB2_LIB.BASEBOARD_FAB2(SCH_1):PVCCIN_CPU0

INDUCTOR  I29  L4D3   [INDUCTOR_SM-0.12UH,IND,D92183-A]
    1  VR_PVCCIN_CPU0_PHASE2    INA  @BASEBOARD_FAB2_LIB.BASEBOARD_FAB2(SCH_1):VR_PVCCIN_CPU0_PHASE2
    2  PVCCIN_CPU0      INB  @BASEBOARD_FAB2_LIB.BASEBOARD_FAB2(SCH_1):PVCCIN_CPU0

INDUCTOR  I5   L4E1   [INDUCTOR_SM-0.12UH,IND,D92183-A]
    1  VR_PVCCIN_CPU0_PHASE1    INA  @BASEBOARD_FAB2_LIB.BASEBOARD_FAB2(SCH_1):VR_PVCCIN_CPU0_PHASE1
    2  PVCCIN_CPU0      INB  @BASEBOARD_FAB2_LIB.BASEBOARD_FAB2(SCH_1):PVCCIN_CPU0

INDUCTOR  I67  L4E2   [INDUCTOR_SM-150NH,IND,D92183-0A]
    1  VR_PVCCIO_CPU1_PH1_SW    INA  @BASEBOARD_FAB2_LIB.BASEBOARD_FAB2(SCH_1):VR_PVCCIO_CPU1_PH1_SW
    2  PVCCIO_CPU1      INB  @BASEBOARD_FAB2_LIB.BASEBOARD_FAB2(SCH_1):PVCCIO_CPU1

INDUCTOR  I277  L4G1   [INDUCTOR_SM-0.47UH,IND,E13358-A]
    1  VR_PVPP_GHJ_PHASE    INA  @BASEBOARD_FAB2_LIB.BASEBOARD_FAB2(SCH_1):VR_PVPP_GHJ_PHASE
    2  PVPP_GHJ         INB  @BASEBOARD_FAB2_LIB.BASEBOARD_FAB2(SCH_1):PVPP_GHJ

INDUCTOR  I55  L7A1   [INDUCTOR_SM-0.12UH,IND,D92183-A]
    1  VR_PVDDQ_DEF_PH1_SW    INA  @BASEBOARD_FAB2_LIB.BASEBOARD_FAB2(SCH_1):VR_PVDDQ_DEF_PH1_SW
    2  PVDDQ_DEF        INB  @BASEBOARD_FAB2_LIB.BASEBOARD_FAB2(SCH_1):PVDDQ_DEF

INDUCTOR  I10  L7A2   [INDUCTOR_SM-0.3UH,IND,D92183-0A]
    1  VR_PVNN_PCH_PH1_PHASE_SW    INA  @BASEBOARD_FAB2_LIB.BASEBOARD_FAB2(SCH_1):VR_PVNN_PCH_PH1_PHASE_SW
    2  PVNN_PCH_STBY    INB  @BASEBOARD_FAB2_LIB.BASEBOARD_FAB2(SCH_1):PVNN_PCH_STBY

INDUCTOR  I65  L7A3   [INDUCTOR_SM-0.12UH,IND,D92183-A]
    1  VR_PVDDQ_DEF_PH2_SW    INA  @BASEBOARD_FAB2_LIB.BASEBOARD_FAB2(SCH_1):VR_PVDDQ_DEF_PH2_SW
    2  PVDDQ_DEF        INB  @BASEBOARD_FAB2_LIB.BASEBOARD_FAB2(SCH_1):PVDDQ_DEF

INDUCTOR  I45  L7A4   [INDUCTOR_SM-0.3UH,IND,D92183-0A]
    1  VR_P1V05_PCH_STBY_PH1_PHASE_SW    INA  @BASEBOARD_FAB2_LIB.BASEBOARD_FAB2(SCH_1):VR_P1V05_PCH_STBY_PH1_PHASE_SW
    2  P1V05_PCH_STBY    INB  @BASEBOARD_FAB2_LIB.BASEBOARD_FAB2(SCH_1):P1V05_PCH_STBY

INDUCTOR  I124  L7A5   [INDUCTOR_SM-100NH,IND,D92183-0B]
    2  VR_FET_SW_P12V_STBY_PVDDQ_DEF    INB  @BASEBOARD_FAB2_LIB.BASEBOARD_FAB2(SCH_1):VR_FET_SW_P12V_STBY_PVDDQ_DEF
    1  P12V_STBY        INA  @BASEBOARD_FAB2_LIB.BASEBOARD_FAB2(SCH_1):P12V_STBY

INDUCTOR  I239  L7B1   [INDUCTOR_SM-0.47UH,IND,E13358-A]
    1  VR_PVPP_DEF_PHASE    INA  @BASEBOARD_FAB2_LIB.BASEBOARD_FAB2(SCH_1):VR_PVPP_DEF_PHASE
    2  PVPP_DEF         INB  @BASEBOARD_FAB2_LIB.BASEBOARD_FAB2(SCH_1):PVPP_DEF

INDUCTOR  I56  L7C1   [INDUCTOR_SM-100NH,IND,D92183-0B]
    2  VR_FET_SW_P12V_STBY_PVCCIO_CPU0    INB  @BASEBOARD_FAB2_LIB.BASEBOARD_FAB2(SCH_1):VR_FET_SW_P12V_STBY_PVCCIO_CPU0
    1  P12V_STBY        INA  @BASEBOARD_FAB2_LIB.BASEBOARD_FAB2(SCH_1):P12V_STBY

INDUCTOR  I25  L7C2   [INDUCTOR_SM-150NH,IND,D92183-0A]
    1  VR_PVCCIO_CPU0_PH1_SW    INA  @BASEBOARD_FAB2_LIB.BASEBOARD_FAB2(SCH_1):VR_PVCCIO_CPU0_PH1_SW
    2  PVCCIO_CPU0      INB  @BASEBOARD_FAB2_LIB.BASEBOARD_FAB2(SCH_1):PVCCIO_CPU0

INDUCTOR  I178  L7F1   [INDUCTOR_SM-0.47UH,IND,E13358-A]
    1  VR_PVPP_ABC_PHASE    INA  @BASEBOARD_FAB2_LIB.BASEBOARD_FAB2(SCH_1):VR_PVPP_ABC_PHASE
    2  PVPP_ABC         INB  @BASEBOARD_FAB2_LIB.BASEBOARD_FAB2(SCH_1):PVPP_ABC

INDUCTOR  I124  L7F2   [INDUCTOR_SM-100NH,IND,D92183-0B]
    2  VR_FET_SW_P12V_STBY_PVDDQ_ABC    INB  @BASEBOARD_FAB2_LIB.BASEBOARD_FAB2(SCH_1):VR_FET_SW_P12V_STBY_PVDDQ_ABC
    1  P12V_STBY        INA  @BASEBOARD_FAB2_LIB.BASEBOARD_FAB2(SCH_1):P12V_STBY

INDUCTOR  I125  L7G1   [INDUCTOR_SM-0.12UH,IND,D92183-A]
    1  VR_PVDDQ_ABC_PH1_SW    INA  @BASEBOARD_FAB2_LIB.BASEBOARD_FAB2(SCH_1):VR_PVDDQ_ABC_PH1_SW
    2  PVDDQ_ABC        INB  @BASEBOARD_FAB2_LIB.BASEBOARD_FAB2(SCH_1):PVDDQ_ABC

INDUCTOR  I65  L7G2   [INDUCTOR_SM-0.12UH,IND,D92183-A]
    1  VR_PVDDQ_ABC_PH2_SW    INA  @BASEBOARD_FAB2_LIB.BASEBOARD_FAB2(SCH_1):VR_PVDDQ_ABC_PH2_SW
    2  PVDDQ_ABC        INB  @BASEBOARD_FAB2_LIB.BASEBOARD_FAB2(SCH_1):PVDDQ_ABC

INDUCTOR  I90  L8E1   [INDUCTOR_SM-2.2UH,IND,E98761-0A]
    1  VR_P5V_STBY_PHASE    INA  @BASEBOARD_FAB2_LIB.BASEBOARD_FAB2(SCH_1):VR_P5V_STBY_PHASE
    2  P5V_STBY         INB  @BASEBOARD_FAB2_LIB.BASEBOARD_FAB2(SCH_1):P5V_STBY

INDUCTOR  I173  L8F1   [INDUCTOR_SM-1.00UH,IND,E98679-A]
    1  VR_P3V3_STBY_PHASE    INA  @BASEBOARD_FAB2_LIB.BASEBOARD_FAB2(SCH_1):VR_P3V3_STBY_PHASE
    2  P3V3_STBY        INB  @BASEBOARD_FAB2_LIB.BASEBOARD_FAB2(SCH_1):P3V3_STBY

SNLABEL_A  I13  LB2B1  [SNLABEL_A_LABEL-EMPTY,N_A]

SNLABEL_A  I11  LB2F1  [SNLABEL_A_LABEL-EMPTY,N_A]

SNLABEL_A  I14  LB5B1  [SNLABEL_A_LABEL-EMPTY,N_A]

SNLABEL_A  I12  LB5F1  [SNLABEL_A_LABEL-EMPTY,N_A]

SNLABEL_A  I15  LB6T1  [SNLABEL_A_LABEL-EMPTY,N_A]

MOSFET_N_LCC3  I86  Q1B1   [MOSFET_N_LCC3-BSZ019N03LS,NFETA]
    5  P12V_STBY        DRN  @BASEBOARD_FAB2_LIB.BASEBOARD_FAB2(SCH_1):P12V_STBY
    4  P12V_FAN_SWITCH_G   GATE  @BASEBOARD_FAB2_LIB.BASEBOARD_FAB2(SCH_1):P12V_FAN_SWITCH_G
    1  P12V_FAN         SRC  @BASEBOARD_FAB2_LIB.BASEBOARD_FAB2(SCH_1):P12V_FAN

FET_N_DUAL_SMLF  I82  Q1D1   [FET_N_DUAL_SMLF-2N7002DW,FET,DA]
    3  A_HSC_ISET_S   DRAIN<0>  @BASEBOARD_FAB2_LIB.BASEBOARD_FAB2(SCH_1):A_HSC_ISET_S
    5  A_HSC_HIGH_EN  GATE<0>  @BASEBOARD_FAB2_LIB.BASEBOARD_FAB2(SCH_1):A_HSC_HIGH_EN
    4  AGND_HSC       SOURCE<0>  @BASEBOARD_FAB2_LIB.BASEBOARD_FAB2(SCH_1):AGND_HSC

FET_N_DUAL_SMLF  I86  Q1D1   [FET_N_DUAL_SMLF-2N7002DW,FET,DA]
    2  A_HSC_LOW_EN   GATE<0>  @BASEBOARD_FAB2_LIB.BASEBOARD_FAB2(SCH_1):A_HSC_LOW_EN
    6  A_HSC_ISET_S2  DRAIN<0>  @BASEBOARD_FAB2_LIB.BASEBOARD_FAB2(SCH_1):A_HSC_ISET_S2
    1  AGND_HSC       SOURCE<0>  @BASEBOARD_FAB2_LIB.BASEBOARD_FAB2(SCH_1):AGND_HSC

FET_N  I203  Q1D2   [FET_N_SOT23LF-2N7002,FET,C7925A]
    2  GND              SRC  @BASEBOARD_FAB2_LIB.BASEBOARD_FAB2(SCH_1):GND
    1  FM_OC_DETECT_EN_N   GATE  @BASEBOARD_FAB2_LIB.BASEBOARD_FAB2(SCH_1):FM_OC_DETECT_EN_N
    3  FM_OC_DETECT_EN    DRN  @BASEBOARD_FAB2_LIB.BASEBOARD_FAB2(SCH_1):FM_OC_DETECT_EN

NPN_SM  I58  Q1D3   [NPN_SM-MMBT3904,IC,C52245-001]
    2  GND                E  @BASEBOARD_FAB2_LIB.BASEBOARD_FAB2(SCH_1):GND
    3  A_HSC_TEMP         C  @BASEBOARD_FAB2_LIB.BASEBOARD_FAB2(SCH_1):A_HSC_TEMP
    1  A_HSC_TEMP         B  @BASEBOARD_FAB2_LIB.BASEBOARD_FAB2(SCH_1):A_HSC_TEMP

PNP  I27  Q1E1   [PNP_TO92-MPS2907,IC,G73554-001]
    2  ISENSE_TMP421_2_E      E  @BASEBOARD_FAB2_LIB.BASEBOARD_FAB2(SCH_1):ISENSE_TMP421_2_E
    3  ISENSE_TMP421_2_BC      C  @BASEBOARD_FAB2_LIB.BASEBOARD_FAB2(SCH_1):ISENSE_TMP421_2_BC
    1  ISENSE_TMP421_2_BC      B  @BASEBOARD_FAB2_LIB.BASEBOARD_FAB2(SCH_1):ISENSE_TMP421_2_BC

NPN_SM  I9   Q1L1   [NPN_SM-MMBT3904,IC,C52245-001]
    2  GND                E  @BASEBOARD_FAB2_LIB.BASEBOARD_FAB2(SCH_1):GND
    1  FM_UART_SEL_N      B  @BASEBOARD_FAB2_LIB.BASEBOARD_FAB2(SCH_1):FM_UART_SEL_N
    3  FM_SOL_UART_CH_SEL      C  @BASEBOARD_FAB2_LIB.BASEBOARD_FAB2(SCH_1):FM_SOL_UART_CH_SEL

FET_N_DUAL_SMLF  I187  Q1L2   [FET_N_DUAL_SMLF-NTJD4001N,FET,A]
    4  GND            SOURCE<0>  @BASEBOARD_FAB2_LIB.BASEBOARD_FAB2(SCH_1):GND
    5  FM_CPLD_DBG_PWR_EN_R_N  GATE<0>  @BASEBOARD_FAB2_LIB.BASEBOARD_FAB2(SCH_1):FM_CPLD_DBG_PWR_EN_R_N
    3  FM_CPLD_DBG_PWR_EN  DRAIN<0>  @BASEBOARD_FAB2_LIB.BASEBOARD_FAB2(SCH_1):FM_CPLD_DBG_PWR_EN

FET_N_DUAL_SMLF  I188  Q1L2   [FET_N_DUAL_SMLF-NTJD4001N,FET,A]
    1  P5V_STBY_DBG   SOURCE<0>  @BASEBOARD_FAB2_LIB.BASEBOARD_FAB2(SCH_1):P5V_STBY_DBG
    6  P5V_STBY       DRAIN<0>  @BASEBOARD_FAB2_LIB.BASEBOARD_FAB2(SCH_1):P5V_STBY
    2  FM_CPLD_DBG_PWR_EN  GATE<0>  @BASEBOARD_FAB2_LIB.BASEBOARD_FAB2(SCH_1):FM_CPLD_DBG_PWR_EN

NPN_SM  I8   Q1L3   [NPN_SM-MMBT3904,IC,C52245-001]
    2  GND                E  @BASEBOARD_FAB2_LIB.BASEBOARD_FAB2(SCH_1):GND
    1  FM_DB_UART_SEL4_N      B  @BASEBOARD_FAB2_LIB.BASEBOARD_FAB2(SCH_1):FM_DB_UART_SEL4_N
    3  FM_DB_PRESENT      C  @BASEBOARD_FAB2_LIB.BASEBOARD_FAB2(SCH_1):FM_DB_PRESENT

FET_N_DUAL_SMLF  I18  Q1L4   [FET_N_DUAL_SMLF-2N7002DW,FET,DA]
    4  TP_FET_Q56_4   SOURCE<0>  @BASEBOARD_FAB2_LIB.BASEBOARD_FAB2(SCH_1):TP_FET_Q56_4
    5  TP_FET_Q56_4   GATE<0>  @BASEBOARD_FAB2_LIB.BASEBOARD_FAB2(SCH_1):TP_FET_Q56_4
    3  TP_FET_Q56_3   DRAIN<0>  @BASEBOARD_FAB2_LIB.BASEBOARD_FAB2(SCH_1):TP_FET_Q56_3

FET_N_DUAL_SMLF  I19  Q1L4   [FET_N_DUAL_SMLF-2N7002DW,FET,DA]
    1  GND            SOURCE<0>  @BASEBOARD_FAB2_LIB.BASEBOARD_FAB2(SCH_1):GND
    6  FM_POST_CARD_PRES_BMC_N  DRAIN<0>  @BASEBOARD_FAB2_LIB.BASEBOARD_FAB2(SCH_1):FM_POST_CARD_PRES_BMC_N
    2  FM_DB_PRESENT  GATE<0>  @BASEBOARD_FAB2_LIB.BASEBOARD_FAB2(SCH_1):FM_DB_PRESENT

FET_N  I58  Q2P1   [FET_N_SOT23LF-2N7002,FET,C7925A]
    2  GND              SRC  @BASEBOARD_FAB2_LIB.BASEBOARD_FAB2(SCH_1):GND
    1  FM_PMBUS_ALERT_BUF_EN_N   GATE  @BASEBOARD_FAB2_LIB.BASEBOARD_FAB2(SCH_1):FM_PMBUS_ALERT_BUF_EN_N
    3  FM_PMBUS_ALERT_BUF_EN    DRN  @BASEBOARD_FAB2_LIB.BASEBOARD_FAB2(SCH_1):FM_PMBUS_ALERT_BUF_EN

FET_N  I124  Q2P2   [FET_N_SOT23-2N7002,FET,C79254-A]
    3  PWRGD_P5V_R      DRN  @BASEBOARD_FAB2_LIB.BASEBOARD_FAB2(SCH_1):PWRGD_P5V_R
    1  PWRGD_P5V_N     GATE  @BASEBOARD_FAB2_LIB.BASEBOARD_FAB2(SCH_1):PWRGD_P5V_N
    2  GND              SRC  @BASEBOARD_FAB2_LIB.BASEBOARD_FAB2(SCH_1):GND

NPN_SM  I330  Q2T1   [NPN_SM-MMBT3904,IC,C52245-001]
    1  H_CPU0_FAST_WAKE_B_N      B  @BASEBOARD_FAB2_LIB.BASEBOARD_FAB2(SCH_1):H_CPU0_FAST_WAKE_B_N
    3  H_CPU0_FAST_WAKE      C  @BASEBOARD_FAB2_LIB.BASEBOARD_FAB2(SCH_1):H_CPU0_FAST_WAKE
    2  GND                E  @BASEBOARD_FAB2_LIB.BASEBOARD_FAB2(SCH_1):GND

FET_N  I340  Q2T2   [FET_N_SOT23LF-2N7002,FET,C7925A]
    3  H_CPU0_FAST_WAKE_LVT3_N    DRN  @BASEBOARD_FAB2_LIB.BASEBOARD_FAB2(SCH_1):H_CPU0_FAST_WAKE_LVT3_N
    1  H_CPU0_FAST_WAKE   GATE  @BASEBOARD_FAB2_LIB.BASEBOARD_FAB2(SCH_1):H_CPU0_FAST_WAKE
    2  GND              SRC  @BASEBOARD_FAB2_LIB.BASEBOARD_FAB2(SCH_1):GND

FET_N_DUAL_SMLF  I113  Q2U1   [FET_N_DUAL_SMLF-NTJD4001N,FET,A]
    3  H_CPU0_MEMDEF_MEMHOT_G_N  DRAIN<0>  @BASEBOARD_FAB2_LIB.BASEBOARD_FAB2(SCH_1):H_CPU0_MEMDEF_MEMHOT_G_N
    4  GND            SOURCE<0>  @BASEBOARD_FAB2_LIB.BASEBOARD_FAB2(SCH_1):GND
    5  FM_SYS_THROTTLE_LVC3  GATE<0>  @BASEBOARD_FAB2_LIB.BASEBOARD_FAB2(SCH_1):FM_SYS_THROTTLE_LVC3

FET_N_DUAL_SMLF  I28  Q2U1   [FET_N_DUAL_SMLF-NTJD4001N,FET,A]
    6  H_CPU0_MEMABC_MEMHOT_G_N  DRAIN<0>  @BASEBOARD_FAB2_LIB.BASEBOARD_FAB2(SCH_1):H_CPU0_MEMABC_MEMHOT_G_N
    1  GND            SOURCE<0>  @BASEBOARD_FAB2_LIB.BASEBOARD_FAB2(SCH_1):GND
    2  FM_SYS_THROTTLE_LVC3  GATE<0>  @BASEBOARD_FAB2_LIB.BASEBOARD_FAB2(SCH_1):FM_SYS_THROTTLE_LVC3

FET_N_DUAL_SMLF  I89  Q3U1   [FET_N_DUAL_SMLF-NTJD4001N,FET,A]
    3  H_CPU0_MEMABC_MEMHOT_G_N  DRAIN<0>  @BASEBOARD_FAB2_LIB.BASEBOARD_FAB2(SCH_1):H_CPU0_MEMABC_MEMHOT_G_N
    5  H_CPU0_MEMABC_MEMHOT  GATE<0>  @BASEBOARD_FAB2_LIB.BASEBOARD_FAB2(SCH_1):H_CPU0_MEMABC_MEMHOT
    4  GND            SOURCE<0>  @BASEBOARD_FAB2_LIB.BASEBOARD_FAB2(SCH_1):GND

FET_N_DUAL_SMLF  I49  Q3U1   [FET_N_DUAL_SMLF-NTJD4001N,FET,A]
    2  IRQ_PVDDQ_ABC_VRHOT_LVT3_N  GATE<0>  @BASEBOARD_FAB2_LIB.BASEBOARD_FAB2(SCH_1):IRQ_PVDDQ_ABC_VRHOT_LVT3_N
    6  H_CPU0_MEMABC_MEMHOT  DRAIN<0>  @BASEBOARD_FAB2_LIB.BASEBOARD_FAB2(SCH_1):H_CPU0_MEMABC_MEMHOT
    1  GND            SOURCE<0>  @BASEBOARD_FAB2_LIB.BASEBOARD_FAB2(SCH_1):GND

FET_N_DUAL_SMLF  I77  Q4B1   [FET_N_DUAL_SMLF-NTJD4001N,FET,A]
    3  H_CPU1_MEMKLM_MEMHOT_G_N  DRAIN<0>  @BASEBOARD_FAB2_LIB.BASEBOARD_FAB2(SCH_1):H_CPU1_MEMKLM_MEMHOT_G_N
    5  H_CPU1_MEMKLM_MEMHOT  GATE<0>  @BASEBOARD_FAB2_LIB.BASEBOARD_FAB2(SCH_1):H_CPU1_MEMKLM_MEMHOT
    4  GND            SOURCE<0>  @BASEBOARD_FAB2_LIB.BASEBOARD_FAB2(SCH_1):GND

FET_N_DUAL_SMLF  I84  Q4B1   [FET_N_DUAL_SMLF-NTJD4001N,FET,A]
    2  IRQ_PVDDQ_KLM_VRHOT_LVT3_N  GATE<0>  @BASEBOARD_FAB2_LIB.BASEBOARD_FAB2(SCH_1):IRQ_PVDDQ_KLM_VRHOT_LVT3_N
    6  H_CPU1_MEMKLM_MEMHOT  DRAIN<0>  @BASEBOARD_FAB2_LIB.BASEBOARD_FAB2(SCH_1):H_CPU1_MEMKLM_MEMHOT
    1  GND            SOURCE<0>  @BASEBOARD_FAB2_LIB.BASEBOARD_FAB2(SCH_1):GND

FET_N_DUAL_SMLF  I33  Q4B2   [FET_N_DUAL_SMLF-NTJD4001N,FET,A]
    3  H_CPU1_MEMKLM_MEMHOT_G_N  DRAIN<0>  @BASEBOARD_FAB2_LIB.BASEBOARD_FAB2(SCH_1):H_CPU1_MEMKLM_MEMHOT_G_N
    4  GND            SOURCE<0>  @BASEBOARD_FAB2_LIB.BASEBOARD_FAB2(SCH_1):GND
    5  FM_SYS_THROTTLE_LVC3  GATE<0>  @BASEBOARD_FAB2_LIB.BASEBOARD_FAB2(SCH_1):FM_SYS_THROTTLE_LVC3

FET_N_DUAL_SMLF  I32  Q4B2   [FET_N_DUAL_SMLF-NTJD4001N,FET,A]
    6  H_CPU1_MEMGHJ_MEMHOT_G_N  DRAIN<0>  @BASEBOARD_FAB2_LIB.BASEBOARD_FAB2(SCH_1):H_CPU1_MEMGHJ_MEMHOT_G_N
    1  GND            SOURCE<0>  @BASEBOARD_FAB2_LIB.BASEBOARD_FAB2(SCH_1):GND
    2  FM_SYS_THROTTLE_LVC3  GATE<0>  @BASEBOARD_FAB2_LIB.BASEBOARD_FAB2(SCH_1):FM_SYS_THROTTLE_LVC3

FET_N_DUAL_SMLF  I102  Q4U1   [FET_N_DUAL_SMLF-NTJD4001N,FET,A]
    4  GND            SOURCE<0>  @BASEBOARD_FAB2_LIB.BASEBOARD_FAB2(SCH_1):GND
    3  FM_MEM_THERM_EVENT_LVT3_N  DRAIN<0>  @BASEBOARD_FAB2_LIB.BASEBOARD_FAB2(SCH_1):FM_MEM_THERM_EVENT_LVT3_N
    5  FM_DIMM_EVENT_FET  GATE<0>  @BASEBOARD_FAB2_LIB.BASEBOARD_FAB2(SCH_1):FM_DIMM_EVENT_FET

FET_N_DUAL_SMLF  I98  Q4U1   [FET_N_DUAL_SMLF-NTJD4001N,FET,A]
    1  GND            SOURCE<0>  @BASEBOARD_FAB2_LIB.BASEBOARD_FAB2(SCH_1):GND
    6  FM_DIMM_EVENT_FET  DRAIN<0>  @BASEBOARD_FAB2_LIB.BASEBOARD_FAB2(SCH_1):FM_DIMM_EVENT_FET
    2  FM_DIMM_EVENT_COD_N  GATE<0>  @BASEBOARD_FAB2_LIB.BASEBOARD_FAB2(SCH_1):FM_DIMM_EVENT_COD_N

FET_N  I18  Q6F1   [FET_N_SOT23-2N7002,FET,C79254-A]
    3  IRQ_DIMM_SAVE_N    DRN  @BASEBOARD_FAB2_LIB.BASEBOARD_FAB2(SCH_1):IRQ_DIMM_SAVE_N
    2  GND              SRC  @BASEBOARD_FAB2_LIB.BASEBOARD_FAB2(SCH_1):GND
    1  FM_ADR_COMPLETE_R   GATE  @BASEBOARD_FAB2_LIB.BASEBOARD_FAB2(SCH_1):FM_ADR_COMPLETE_R

FET_N  I10  Q7D1   [FET_N_SOT23-2N7002,FET,C79254-A]
    2  GND              SRC  @BASEBOARD_FAB2_LIB.BASEBOARD_FAB2(SCH_1):GND
    1  FM_THERMTRIP_DLY_R   GATE  @BASEBOARD_FAB2_LIB.BASEBOARD_FAB2(SCH_1):FM_THERMTRIP_DLY_R
    3  FM_PCH_LVC1_THERMTRIP_N    DRN  @BASEBOARD_FAB2_LIB.BASEBOARD_FAB2(SCH_1):FM_PCH_LVC1_THERMTRIP_N

FET_N_DUAL_SMLF  I64  Q7E1   [FET_N_DUAL_SMLF-NTJD4001N,FET,A]
    3  H_CPU0_MEMDEF_MEMHOT_G_N  DRAIN<0>  @BASEBOARD_FAB2_LIB.BASEBOARD_FAB2(SCH_1):H_CPU0_MEMDEF_MEMHOT_G_N
    5  H_CPU0_MEMDEF_MEMHOT  GATE<0>  @BASEBOARD_FAB2_LIB.BASEBOARD_FAB2(SCH_1):H_CPU0_MEMDEF_MEMHOT
    4  GND            SOURCE<0>  @BASEBOARD_FAB2_LIB.BASEBOARD_FAB2(SCH_1):GND

FET_N_DUAL_SMLF  I60  Q7E1   [FET_N_DUAL_SMLF-NTJD4001N,FET,A]
    2  IRQ_PVDDQ_DEF_VRHOT_LVT3_N  GATE<0>  @BASEBOARD_FAB2_LIB.BASEBOARD_FAB2(SCH_1):IRQ_PVDDQ_DEF_VRHOT_LVT3_N
    6  H_CPU0_MEMDEF_MEMHOT  DRAIN<0>  @BASEBOARD_FAB2_LIB.BASEBOARD_FAB2(SCH_1):H_CPU0_MEMDEF_MEMHOT
    1  GND            SOURCE<0>  @BASEBOARD_FAB2_LIB.BASEBOARD_FAB2(SCH_1):GND

FET_N_DUAL_SMLF  I75  Q7E2   [FET_N_DUAL_SMLF-NTJD4001N,FET,A]
    3  H_CPU1_MEMGHJ_MEMHOT_G_N  DRAIN<0>  @BASEBOARD_FAB2_LIB.BASEBOARD_FAB2(SCH_1):H_CPU1_MEMGHJ_MEMHOT_G_N
    5  H_CPU1_MEMGHJ_MEMHOT  GATE<0>  @BASEBOARD_FAB2_LIB.BASEBOARD_FAB2(SCH_1):H_CPU1_MEMGHJ_MEMHOT
    4  GND            SOURCE<0>  @BASEBOARD_FAB2_LIB.BASEBOARD_FAB2(SCH_1):GND

FET_N_DUAL_SMLF  I69  Q7E2   [FET_N_DUAL_SMLF-NTJD4001N,FET,A]
    2  IRQ_PVDDQ_GHJ_VRHOT_LVT3_N  GATE<0>  @BASEBOARD_FAB2_LIB.BASEBOARD_FAB2(SCH_1):IRQ_PVDDQ_GHJ_VRHOT_LVT3_N
    6  H_CPU1_MEMGHJ_MEMHOT  DRAIN<0>  @BASEBOARD_FAB2_LIB.BASEBOARD_FAB2(SCH_1):H_CPU1_MEMGHJ_MEMHOT
    1  GND            SOURCE<0>  @BASEBOARD_FAB2_LIB.BASEBOARD_FAB2(SCH_1):GND

FET_N_DUAL_SMLF  I51  Q7E3   [FET_N_DUAL_SMLF-NTJD4001N,FET,A]
    3  H_CPU1_PROCHOT_G_N  DRAIN<0>  @BASEBOARD_FAB2_LIB.BASEBOARD_FAB2(SCH_1):H_CPU1_PROCHOT_G_N
    4  GND            SOURCE<0>  @BASEBOARD_FAB2_LIB.BASEBOARD_FAB2(SCH_1):GND
    5  FM_SYS_THROTTLE_LVC3  GATE<0>  @BASEBOARD_FAB2_LIB.BASEBOARD_FAB2(SCH_1):FM_SYS_THROTTLE_LVC3

FET_N_DUAL_SMLF  I52  Q7E3   [FET_N_DUAL_SMLF-NTJD4001N,FET,A]
    6  H_CPU0_PROCHOT_G_N  DRAIN<0>  @BASEBOARD_FAB2_LIB.BASEBOARD_FAB2(SCH_1):H_CPU0_PROCHOT_G_N
    1  GND            SOURCE<0>  @BASEBOARD_FAB2_LIB.BASEBOARD_FAB2(SCH_1):GND
    2  FM_SYS_THROTTLE_LVC3  GATE<0>  @BASEBOARD_FAB2_LIB.BASEBOARD_FAB2(SCH_1):FM_SYS_THROTTLE_LVC3

FET_N  I104  Q7E4   [FET_N_SOT23-2N7002,FET,C79254-A]
    2  GND              SRC  @BASEBOARD_FAB2_LIB.BASEBOARD_FAB2(SCH_1):GND
    1  FM_THROTTLE_R_N   GATE  @BASEBOARD_FAB2_LIB.BASEBOARD_FAB2(SCH_1):FM_THROTTLE_R_N
    3  FM_SYS_THROTTLE_LVC3    DRN  @BASEBOARD_FAB2_LIB.BASEBOARD_FAB2(SCH_1):FM_SYS_THROTTLE_LVC3

FET_N_DUAL_SMLF  I59  Q7E5   [FET_N_DUAL_SMLF-NTJD4001N,FET,A]
    5  IRQ_CPU0_VRHOT  GATE<0>  @BASEBOARD_FAB2_LIB.BASEBOARD_FAB2(SCH_1):IRQ_CPU0_VRHOT
    3  H_CPU0_PROCHOT_G_N  DRAIN<0>  @BASEBOARD_FAB2_LIB.BASEBOARD_FAB2(SCH_1):H_CPU0_PROCHOT_G_N
    4  GND            SOURCE<0>  @BASEBOARD_FAB2_LIB.BASEBOARD_FAB2(SCH_1):GND

FET_N_DUAL_SMLF  I111  Q7E5   [FET_N_DUAL_SMLF-NTJD4001N,FET,A]
    6  IRQ_CPU0_VRHOT  DRAIN<0>  @BASEBOARD_FAB2_LIB.BASEBOARD_FAB2(SCH_1):IRQ_CPU0_VRHOT
    2  IRQ_CPU0_PROCHOT_G_N  GATE<0>  @BASEBOARD_FAB2_LIB.BASEBOARD_FAB2(SCH_1):IRQ_CPU0_PROCHOT_G_N
    1  GND            SOURCE<0>  @BASEBOARD_FAB2_LIB.BASEBOARD_FAB2(SCH_1):GND

FET_N_DUAL_SMLF  I69  Q7E6   [FET_N_DUAL_SMLF-NTJD4001N,FET,A]
    5  IRQ_CPU1_VRHOT  GATE<0>  @BASEBOARD_FAB2_LIB.BASEBOARD_FAB2(SCH_1):IRQ_CPU1_VRHOT
    3  H_CPU1_PROCHOT_G_N  DRAIN<0>  @BASEBOARD_FAB2_LIB.BASEBOARD_FAB2(SCH_1):H_CPU1_PROCHOT_G_N
    4  GND            SOURCE<0>  @BASEBOARD_FAB2_LIB.BASEBOARD_FAB2(SCH_1):GND

FET_N_DUAL_SMLF  I112  Q7E6   [FET_N_DUAL_SMLF-NTJD4001N,FET,A]
    6  IRQ_CPU1_VRHOT  DRAIN<0>  @BASEBOARD_FAB2_LIB.BASEBOARD_FAB2(SCH_1):IRQ_CPU1_VRHOT
    2  IRQ_CPU1_PROCHOT_G_N  GATE<0>  @BASEBOARD_FAB2_LIB.BASEBOARD_FAB2(SCH_1):IRQ_CPU1_PROCHOT_G_N
    1  GND            SOURCE<0>  @BASEBOARD_FAB2_LIB.BASEBOARD_FAB2(SCH_1):GND

MOSFET_N_LCC3  I88  Q7E7   [MOSFET_N_LCC3-BSZ019N03LS,NFETA]
    4  P12V_SWITCH_G   GATE  @BASEBOARD_FAB2_LIB.BASEBOARD_FAB2(SCH_1):P12V_SWITCH_G
    5  P12V_STBY        DRN  @BASEBOARD_FAB2_LIB.BASEBOARD_FAB2(SCH_1):P12V_STBY
    1  P12V             SRC  @BASEBOARD_FAB2_LIB.BASEBOARD_FAB2(SCH_1):P12V

FET_N  I119  Q7E8   [FET_N_SOT23-2N7002,FET,C79254-A]
    2  GND              SRC  @BASEBOARD_FAB2_LIB.BASEBOARD_FAB2(SCH_1):GND
    1  FM_SYS_THROTTLE_LVC3   GATE  @BASEBOARD_FAB2_LIB.BASEBOARD_FAB2(SCH_1):FM_SYS_THROTTLE_LVC3
    3  FM_PWRBRK_N      DRN  @BASEBOARD_FAB2_LIB.BASEBOARD_FAB2(SCH_1):FM_PWRBRK_N

MOSFET_N_LCC3  I87  Q8B1   [MOSFET_N_LCC3-BSZ019N03LS,NFETA]
    4  P5V_SWITCH_G    GATE  @BASEBOARD_FAB2_LIB.BASEBOARD_FAB2(SCH_1):P5V_SWITCH_G
    5  P5V_STBY         DRN  @BASEBOARD_FAB2_LIB.BASEBOARD_FAB2(SCH_1):P5V_STBY
    1  P5V              SRC  @BASEBOARD_FAB2_LIB.BASEBOARD_FAB2(SCH_1):P5V

NPN_DUAL  I36  Q8D1   [NPN_DUAL_SSOPLF-MBT3904,XSTR,CA]
    6  IRQ_DIMM_SAVE_LVT3_N   C<0>  @BASEBOARD_FAB2_LIB.BASEBOARD_FAB2(SCH_1):IRQ_DIMM_SAVE_LVT3_N
    2  IRQ_DIMM_SAVE_LVT3   B<0>  @BASEBOARD_FAB2_LIB.BASEBOARD_FAB2(SCH_1):IRQ_DIMM_SAVE_LVT3
    1  GND             E<0>  @BASEBOARD_FAB2_LIB.BASEBOARD_FAB2(SCH_1):GND

NPN_DUAL  I35  Q8D1   [NPN_DUAL_SSOPLF-MBT3904,XSTR,CA]
    5  IRQ_DIMM_SAVE_R_N   B<0>  @BASEBOARD_FAB2_LIB.BASEBOARD_FAB2(SCH_1):IRQ_DIMM_SAVE_R_N
    3  IRQ_DIMM_SAVE_LVT3   C<0>  @BASEBOARD_FAB2_LIB.BASEBOARD_FAB2(SCH_1):IRQ_DIMM_SAVE_LVT3
    4  GND             E<0>  @BASEBOARD_FAB2_LIB.BASEBOARD_FAB2(SCH_1):GND

FET_N  I4   Q8D2   [FET_N_SOT23-2N7002,FET,C79254-A]
    1  RST_PLTRST_BUF_N   GATE  @BASEBOARD_FAB2_LIB.BASEBOARD_FAB2(SCH_1):RST_PLTRST_BUF_N
    3  FM_PCH_BMC_THERMTRIP_N    DRN  @BASEBOARD_FAB2_LIB.BASEBOARD_FAB2(SCH_1):FM_PCH_BMC_THERMTRIP_N
    2  FM_PCH_BMC_THERMTRIP_EXI_STRAP_    SRC  @BASEBOARD_FAB2_LIB.BASEBOARD_FAB2(SCH_1):FM_PCH_BMC_THERMTRIP_EXI_STRAP_N

FET_N  I134  Q8E1   [FET_N_SOT23LF-2N7002,FET,C7925A]
    3  RST_PLTRST_TOP_SWAP    DRN  @BASEBOARD_FAB2_LIB.BASEBOARD_FAB2(SCH_1):RST_PLTRST_TOP_SWAP
    1  RST_PLTRST_N    GATE  @BASEBOARD_FAB2_LIB.BASEBOARD_FAB2(SCH_1):RST_PLTRST_N
    2  GND              SRC  @BASEBOARD_FAB2_LIB.BASEBOARD_FAB2(SCH_1):GND

FET_N  I13  Q8E2   [FET_N_SOT23LF-2N7002,FET,C7925A]
    1  RST_RSMRST_DLY   GATE  @BASEBOARD_FAB2_LIB.BASEBOARD_FAB2(SCH_1):RST_RSMRST_DLY
    3  IRQ_SML0_ALERT_N    DRN  @BASEBOARD_FAB2_LIB.BASEBOARD_FAB2(SCH_1):IRQ_SML0_ALERT_N
    2  GND              SRC  @BASEBOARD_FAB2_LIB.BASEBOARD_FAB2(SCH_1):GND

FET_N  I126  Q8F1   [FET_N_SOT23LF-2N7002,FET,C7925A]
    2  GND              SRC  @BASEBOARD_FAB2_LIB.BASEBOARD_FAB2(SCH_1):GND
    3  FM_DUAL_BIOS_SEL_N    DRN  @BASEBOARD_FAB2_LIB.BASEBOARD_FAB2(SCH_1):FM_DUAL_BIOS_SEL_N
    1  FM_BACKUP_BIOS_SEL_N   GATE  @BASEBOARD_FAB2_LIB.BASEBOARD_FAB2(SCH_1):FM_BACKUP_BIOS_SEL_N

FET_N  I67  Q8F2   [FET_N_SOT23LF-2N7002,FET,C7925A]
    2  GND              SRC  @BASEBOARD_FAB2_LIB.BASEBOARD_FAB2(SCH_1):GND
    1  FM_FAST_PROCHOT_EN_N   GATE  @BASEBOARD_FAB2_LIB.BASEBOARD_FAB2(SCH_1):FM_FAST_PROCHOT_EN_N
    3  FM_FAST_PROCHOT_EN    DRN  @BASEBOARD_FAB2_LIB.BASEBOARD_FAB2(SCH_1):FM_FAST_PROCHOT_EN

MOSFET_N_LCC3  I85  Q8G1   [MOSFET_N_LCC3-BSZ019N03LS,NFETA]
    4  P3V3_SWITCH_G   GATE  @BASEBOARD_FAB2_LIB.BASEBOARD_FAB2(SCH_1):P3V3_SWITCH_G
    5  P3V3_STBY        DRN  @BASEBOARD_FAB2_LIB.BASEBOARD_FAB2(SCH_1):P3V3_STBY
    1  P3V3             SRC  @BASEBOARD_FAB2_LIB.BASEBOARD_FAB2(SCH_1):P3V3

NPN_DUAL  I93  Q9A1   [NPN_DUAL_SSOPLF-MBT3904,EMPTY,A]
    6  XDP_CPU_TCK_BUF   C<0>  @BASEBOARD_FAB2_LIB.BASEBOARD_FAB2(SCH_1):XDP_CPU_TCK_BUF
    2  XDP_CPU_TCK_BUF   B<0>  @BASEBOARD_FAB2_LIB.BASEBOARD_FAB2(SCH_1):XDP_CPU_TCK_BUF
    1  XDP_CPU_GTL_TCK_R2   E<0>  @BASEBOARD_FAB2_LIB.BASEBOARD_FAB2(SCH_1):XDP_CPU_GTL_TCK_R2

NPN_DUAL  I94  Q9A1   [NPN_DUAL_SSOPLF-MBT3904,EMPTY,A]
    5  XDP_CPU_TCK_BUF   B<0>  @BASEBOARD_FAB2_LIB.BASEBOARD_FAB2(SCH_1):XDP_CPU_TCK_BUF
    4  XDP_CPU_TCK0    E<0>  @BASEBOARD_FAB2_LIB.BASEBOARD_FAB2(SCH_1):XDP_CPU_TCK0
    3  P3V3            C<0>  @BASEBOARD_FAB2_LIB.BASEBOARD_FAB2(SCH_1):P3V3

FET_N_DUAL_SMLF  I180  Q9A2   [FET_N_DUAL_SMLF-NTJD4001N,FET,A]
    4  GND            SOURCE<0>  @BASEBOARD_FAB2_LIB.BASEBOARD_FAB2(SCH_1):GND
    3  FM_PWR_LED_K   DRAIN<0>  @BASEBOARD_FAB2_LIB.BASEBOARD_FAB2(SCH_1):FM_PWR_LED_K
    5  FM_PWR_LED     GATE<0>  @BASEBOARD_FAB2_LIB.BASEBOARD_FAB2(SCH_1):FM_PWR_LED

FET_N_DUAL_SMLF  I175  Q9A2   [FET_N_DUAL_SMLF-NTJD4001N,FET,A]
    1  GND            SOURCE<0>  @BASEBOARD_FAB2_LIB.BASEBOARD_FAB2(SCH_1):GND
    2  FM_PWR_LED_N   GATE<0>  @BASEBOARD_FAB2_LIB.BASEBOARD_FAB2(SCH_1):FM_PWR_LED_N
    6  FM_PWR_LED     DRAIN<0>  @BASEBOARD_FAB2_LIB.BASEBOARD_FAB2(SCH_1):FM_PWR_LED

FET_N  I49  Q9A3   [FET_N_SOT23LF-2N7002,FET,C7925A]
    2  GND              SRC  @BASEBOARD_FAB2_LIB.BASEBOARD_FAB2(SCH_1):GND
    3  FM_SPEAKER_PCH_N    DRN  @BASEBOARD_FAB2_LIB.BASEBOARD_FAB2(SCH_1):FM_SPEAKER_PCH_N
    1  FM_BIOS_TOP_SWAP_SPKR   GATE  @BASEBOARD_FAB2_LIB.BASEBOARD_FAB2(SCH_1):FM_BIOS_TOP_SWAP_SPKR

PNP  I3   Q9B1   [PNP_TO92-MPS2907,IC,G73554-001]
    2  ISENSE_TMP421_1_E      E  @BASEBOARD_FAB2_LIB.BASEBOARD_FAB2(SCH_1):ISENSE_TMP421_1_E
    3  ISENSE_TMP421_1_BC      C  @BASEBOARD_FAB2_LIB.BASEBOARD_FAB2(SCH_1):ISENSE_TMP421_1_BC
    1  ISENSE_TMP421_1_BC      B  @BASEBOARD_FAB2_LIB.BASEBOARD_FAB2(SCH_1):ISENSE_TMP421_1_BC

FET_N_DUAL_SMLF  I55  Q9E1   [FET_N_DUAL_SMLF-NTJD4001N,FET,A]
    4  GND            SOURCE<0>  @BASEBOARD_FAB2_LIB.BASEBOARD_FAB2(SCH_1):GND
    3  FM_HEARTBEAT_LED_K  DRAIN<0>  @BASEBOARD_FAB2_LIB.BASEBOARD_FAB2(SCH_1):FM_HEARTBEAT_LED_K
    5  FM_HEARTBEAT_LED  GATE<0>  @BASEBOARD_FAB2_LIB.BASEBOARD_FAB2(SCH_1):FM_HEARTBEAT_LED

FET_N_DUAL_SMLF  I135  Q9E1   [FET_N_DUAL_SMLF-NTJD4001N,FET,A]
    1  GND            SOURCE<0>  @BASEBOARD_FAB2_LIB.BASEBOARD_FAB2(SCH_1):GND
    6  FM_HEARTBEAT_LED  DRAIN<0>  @BASEBOARD_FAB2_LIB.BASEBOARD_FAB2(SCH_1):FM_HEARTBEAT_LED
    2  FM_BMC_HEARTBEAT_N  GATE<0>  @BASEBOARD_FAB2_LIB.BASEBOARD_FAB2(SCH_1):FM_BMC_HEARTBEAT_N

FET_N_DUAL_SMLF  I79  Q9F1   [FET_N_DUAL_SMLF-NTJD4001N,FET,A]
    4  GND            SOURCE<0>  @BASEBOARD_FAB2_LIB.BASEBOARD_FAB2(SCH_1):GND
    3  FM_RED_LED_CATHODE  DRAIN<0>  @BASEBOARD_FAB2_LIB.BASEBOARD_FAB2(SCH_1):FM_RED_LED_CATHODE
    5  FM_BMC_FAULT_LED  GATE<0>  @BASEBOARD_FAB2_LIB.BASEBOARD_FAB2(SCH_1):FM_BMC_FAULT_LED

FET_N_DUAL_SMLF  I80  Q9F1   [FET_N_DUAL_SMLF-NTJD4001N,FET,A]
    1  GND            SOURCE<0>  @BASEBOARD_FAB2_LIB.BASEBOARD_FAB2(SCH_1):GND
    2  FM_BMC_FAULT_LED_N  GATE<0>  @BASEBOARD_FAB2_LIB.BASEBOARD_FAB2(SCH_1):FM_BMC_FAULT_LED_N
    6  FM_BMC_FAULT_LED  DRAIN<0>  @BASEBOARD_FAB2_LIB.BASEBOARD_FAB2(SCH_1):FM_BMC_FAULT_LED

FET_N_DUAL_SMLF  I157  Q9G1   [FET_N_DUAL_SMLF-NTJD4001N,FET,A]
    3  P3V_BAT_SOURCE_R  DRAIN<0>  @BASEBOARD_FAB2_LIB.BASEBOARD_FAB2(SCH_1):P3V_BAT_SOURCE_R
    5  FM_BATTERY_SENSE_EN  GATE<0>  @BASEBOARD_FAB2_LIB.BASEBOARD_FAB2(SCH_1):FM_BATTERY_SENSE_EN
    4  A_P3V_BAT_SCALED  SOURCE<0>  @BASEBOARD_FAB2_LIB.BASEBOARD_FAB2(SCH_1):A_P3V_BAT_SCALED

FET_N_DUAL_SMLF  I162  Q9G1   [FET_N_DUAL_SMLF-NTJD4001N,FET,A]
    1  GND            SOURCE<0>  @BASEBOARD_FAB2_LIB.BASEBOARD_FAB2(SCH_1):GND
    2  FM_BATTERY_SENSE_EN_N  GATE<0>  @BASEBOARD_FAB2_LIB.BASEBOARD_FAB2(SCH_1):FM_BATTERY_SENSE_EN_N
    6  FM_BATTERY_SENSE_EN  DRAIN<0>  @BASEBOARD_FAB2_LIB.BASEBOARD_FAB2(SCH_1):FM_BATTERY_SENSE_EN

FET_N_DUAL_SMLF  I199  Q9P1   [FET_N_DUAL_SMLF-2N7002DW,FET,DA]
    3  IRQ_UV_DETECT_N  DRAIN<0>  @BASEBOARD_FAB2_LIB.BASEBOARD_FAB2(SCH_1):IRQ_UV_DETECT_N
    4  GND            SOURCE<0>  @BASEBOARD_FAB2_LIB.BASEBOARD_FAB2(SCH_1):GND
    5  A_P12V_STBY_FPH_GATE  GATE<0>  @BASEBOARD_FAB2_LIB.BASEBOARD_FAB2(SCH_1):A_P12V_STBY_FPH_GATE

FET_N_DUAL_SMLF  I196  Q9P1   [FET_N_DUAL_SMLF-2N7002DW,FET,DA]
    1  GND            SOURCE<0>  @BASEBOARD_FAB2_LIB.BASEBOARD_FAB2(SCH_1):GND
    2  A_HSC_LOW_GATE  GATE<0>  @BASEBOARD_FAB2_LIB.BASEBOARD_FAB2(SCH_1):A_HSC_LOW_GATE
    6  A_HSC_LOW_DRAIN  DRAIN<0>  @BASEBOARD_FAB2_LIB.BASEBOARD_FAB2(SCH_1):A_HSC_LOW_DRAIN

NPN_SM  I181  Q9T1   [NPN_SM-MMBT3904,IC,C52245-001]
    2  GND                E  @BASEBOARD_FAB2_LIB.BASEBOARD_FAB2(SCH_1):GND
    3  FM_P12V_HOTSWAP0_EN      C  @BASEBOARD_FAB2_LIB.BASEBOARD_FAB2(SCH_1):FM_P12V_HOTSWAP0_EN
    1  FM_MATED_IN_D2_N      B  @BASEBOARD_FAB2_LIB.BASEBOARD_FAB2(SCH_1):FM_MATED_IN_D2_N

RES  I58  R1A1   [RES_0603-120.0,1%,1/10W,CHIP,GA]
    1  PVDDQ_KLM          A  @BASEBOARD_FAB2_LIB.BASEBOARD_FAB2(SCH_1):PVDDQ_KLM
    2  GND                B  @BASEBOARD_FAB2_LIB.BASEBOARD_FAB2(SCH_1):GND

RES  I105  R1A2   [RES_0402-68.1K,1%,1/16W,EMPTY,A]
    1  VR_PVDDQ_KLM_PH2_OCSET      A  @BASEBOARD_FAB2_LIB.BASEBOARD_FAB2(SCH_1):VR_PVDDQ_KLM_PH2_OCSET
    2  GND                B  @BASEBOARD_FAB2_LIB.BASEBOARD_FAB2(SCH_1):GND

RES  I103  R1A3   [RES_0402-68.1K,1%,1/16W,EMPTY,A]
    1  VR_PVDDQ_KLM_PH1_OCSET      A  @BASEBOARD_FAB2_LIB.BASEBOARD_FAB2(SCH_1):VR_PVDDQ_KLM_PH1_OCSET
    2  GND                B  @BASEBOARD_FAB2_LIB.BASEBOARD_FAB2(SCH_1):GND

RES  I79  R1B1   [RES_0402-1.00K,1%,1/16W,CHIP,GA]
    1  P3V3_STBY          A  @BASEBOARD_FAB2_LIB.BASEBOARD_FAB2(SCH_1):P3V3_STBY
    2  IRQ_PVDDQ_KLM_VRHOT_LVT3_R_N      B  @BASEBOARD_FAB2_LIB.BASEBOARD_FAB2(SCH_1):IRQ_PVDDQ_KLM_VRHOT_LVT3_R_N

RES  I17  R1B2   [RES_0402-1.00K,1%,1/16W,CHIP,GA]
    2  PWRGD_PVDDQ_KLM_R      B  @BASEBOARD_FAB2_LIB.BASEBOARD_FAB2(SCH_1):PWRGD_PVDDQ_KLM_R
    1  P3V3_STBY          A  @BASEBOARD_FAB2_LIB.BASEBOARD_FAB2(SCH_1):P3V3_STBY

RES  I82  R1B4   [RES_0402-33.2,1%,1/16W,CHIP,G2A]
    1  IRQ_PVDDQ_KLM_VRHOT_LVT3_R_N      A  @BASEBOARD_FAB2_LIB.BASEBOARD_FAB2(SCH_1):IRQ_PVDDQ_KLM_VRHOT_LVT3_R_N
    2  IRQ_PVDDQ_KLM_VRHOT_LVT3_N      B  @BASEBOARD_FAB2_LIB.BASEBOARD_FAB2(SCH_1):IRQ_PVDDQ_KLM_VRHOT_LVT3_N

RES  I14  R1B5   [RES_0402-22.1,1.0%,1/16W,CHIP,A]
    1  PWRGD_PVDDQ_KLM_R      A  @BASEBOARD_FAB2_LIB.BASEBOARD_FAB2(SCH_1):PWRGD_PVDDQ_KLM_R
    2  PWRGD_PVDDQ_KLM      B  @BASEBOARD_FAB2_LIB.BASEBOARD_FAB2(SCH_1):PWRGD_PVDDQ_KLM

RES  I21  R1B6   [RES_0402-20.0,1%,1/16W,CHIP,G2A]
    2  SMB_VR_STBY_LVC3_SCL      B  @BASEBOARD_FAB2_LIB.BASEBOARD_FAB2(SCH_1):SMB_VR_STBY_LVC3_SCL
    1  SMB_VR_SCL_VDDQ_KLM      A  @BASEBOARD_FAB2_LIB.BASEBOARD_FAB2(SCH_1):SMB_VR_SCL_VDDQ_KLM

RES  I22  R1B7   [RES_0402-20.0,1%,1/16W,CHIP,G2A]
    2  SMB_VR_STBY_LVC3_SDA      B  @BASEBOARD_FAB2_LIB.BASEBOARD_FAB2(SCH_1):SMB_VR_STBY_LVC3_SDA
    1  SMB_VR_SDA_VDDQ_KLM      A  @BASEBOARD_FAB2_LIB.BASEBOARD_FAB2(SCH_1):SMB_VR_SDA_VDDQ_KLM

RES  I53  R1B8   [RES_0402-150.0,1%,1/16W,CHIP,GA]
    2  SVID_CLK_PVDDQ_KLM      B  @BASEBOARD_FAB2_LIB.BASEBOARD_FAB2(SCH_1):SVID_CLK_PVDDQ_KLM
    1  SVID_CLK1_CPU1_R      A  @BASEBOARD_FAB2_LIB.BASEBOARD_FAB2(SCH_1):SVID_CLK1_CPU1_R

RES  I58  R1B9   [RES_0402-1.5K,1%,1/16W,CHIP,G2A]
    1  VR_PVDDQ_KLM_VINSEN      A  @BASEBOARD_FAB2_LIB.BASEBOARD_FAB2(SCH_1):VR_PVDDQ_KLM_VINSEN
    2  GND                B  @BASEBOARD_FAB2_LIB.BASEBOARD_FAB2(SCH_1):GND

RES  I23  R1B10  [RES_0402-0.0,5%,1/16W,CHIP,G21A]
    1  SVID_VDIO_PVDDQ_KLM      A  @BASEBOARD_FAB2_LIB.BASEBOARD_FAB2(SCH_1):SVID_VDIO_PVDDQ_KLM
    2  SVID_DIO1_CPU1_R      B  @BASEBOARD_FAB2_LIB.BASEBOARD_FAB2(SCH_1):SVID_DIO1_CPU1_R

RES  I16  R1B11  [RES_0402-0.0,5%,1/16W,CHIP,G21A]
    1  SVID_ALERT_PVDDQ_KLM      A  @BASEBOARD_FAB2_LIB.BASEBOARD_FAB2(SCH_1):SVID_ALERT_PVDDQ_KLM
    2  SVID_ALERT1_CPU1_R_N      B  @BASEBOARD_FAB2_LIB.BASEBOARD_FAB2(SCH_1):SVID_ALERT1_CPU1_R_N

RES  I78  R1B12  [RES_0402-3.16K,1%,1/16W,CHIP,GA]
    1  VR_PVDDQ_KLM_XADDR1      A  @BASEBOARD_FAB2_LIB.BASEBOARD_FAB2(SCH_1):VR_PVDDQ_KLM_XADDR1
    2  GND                B  @BASEBOARD_FAB2_LIB.BASEBOARD_FAB2(SCH_1):GND

RES  I13  R1B13  [RES_0402-2.26K,1.0%,1/16W,EMPTA]
    2  PU_VR_PVDDQ_KLM_FAULT1      B  @BASEBOARD_FAB2_LIB.BASEBOARD_FAB2(SCH_1):PU_VR_PVDDQ_KLM_FAULT1
    1  P3V3_STBY          A  @BASEBOARD_FAB2_LIB.BASEBOARD_FAB2(SCH_1):P3V3_STBY

RES  I137  R1B14  [RES_0402-0.0,5%,1/16W,CHIP,G21A]
    1  VR_PVDDQ_KLM_AIINSEN_R      A  @BASEBOARD_FAB2_LIB.BASEBOARD_FAB2(SCH_1):VR_PVDDQ_KLM_AIINSEN_R
    2  VR_PVDDQ_KLM_AIINSEN      B  @BASEBOARD_FAB2_LIB.BASEBOARD_FAB2(SCH_1):VR_PVDDQ_KLM_AIINSEN

RES  I77  R1B15  [RES_0402-5.36K,1.0%,1/16W,CHIPA]
    1  VR_PVDDQ_KLM_XADDR2      A  @BASEBOARD_FAB2_LIB.BASEBOARD_FAB2(SCH_1):VR_PVDDQ_KLM_XADDR2
    2  GND                B  @BASEBOARD_FAB2_LIB.BASEBOARD_FAB2(SCH_1):GND

RES  I32  R1B16  [RES_0402-10.0,1%,1/16W,CHIP,G2A]
    1  VSENSE_PVDDQ_KLM_P      A  @BASEBOARD_FAB2_LIB.BASEBOARD_FAB2(SCH_1):VSENSE_PVDDQ_KLM_P
    2  VR_PVDDQ_KLM_AVSP      B  @BASEBOARD_FAB2_LIB.BASEBOARD_FAB2(SCH_1):VR_PVDDQ_KLM_AVSP

RES  I39  R1B20  [RES_2010-0.001,1%,1W,CHIP,E309A]
    2  VR_FET_SW_P12V_STBY_PVCCIN_CPU1      B  @BASEBOARD_FAB2_LIB.BASEBOARD_FAB2(SCH_1):VR_FET_SW_P12V_STBY_PVCCIN_CPU1
    1  VR_FET_SW_P12V_PVCCIN_CPU1_R      A  @BASEBOARD_FAB2_LIB.BASEBOARD_FAB2(SCH_1):VR_FET_SW_P12V_PVCCIN_CPU1_R

RES  I70  R1B21  [RES_0402-4.75K,1%,1/16W,CHIP,GA]
    1  P3V3_STBY          A  @BASEBOARD_FAB2_LIB.BASEBOARD_FAB2(SCH_1):P3V3_STBY
    2  FAN_TACH2          B  @BASEBOARD_FAB2_LIB.BASEBOARD_FAB2(SCH_1):FAN_TACH2

RES  I67  R1B22  [RES_0402-100.0,1%,1/16W,CHIP,GA]
    2  FAN_TACH2_CPU1_D2      B  @BASEBOARD_FAB2_LIB.BASEBOARD_FAB2(SCH_1):FAN_TACH2_CPU1_D2
    1  FAN_TACH2          A  @BASEBOARD_FAB2_LIB.BASEBOARD_FAB2(SCH_1):FAN_TACH2

RES  I124  R1B23  [RES_0402-100.0,1%,1/16W,CHIP,GA]
    2  FAN_TACH3_CPU1_D2      B  @BASEBOARD_FAB2_LIB.BASEBOARD_FAB2(SCH_1):FAN_TACH3_CPU1_D2
    1  FAN_TACH3          A  @BASEBOARD_FAB2_LIB.BASEBOARD_FAB2(SCH_1):FAN_TACH3

RES  I126  R1B24  [RES_0402-4.75K,1%,1/16W,CHIP,GA]
    1  P3V3_STBY          A  @BASEBOARD_FAB2_LIB.BASEBOARD_FAB2(SCH_1):P3V3_STBY
    2  FAN_TACH3          B  @BASEBOARD_FAB2_LIB.BASEBOARD_FAB2(SCH_1):FAN_TACH3

RES  I26  R1C1   [RES_0402-221,1.0%,1/16W,CHIP,GA]
    2  SVID_ALERT1_CPU1_R_N      B  @BASEBOARD_FAB2_LIB.BASEBOARD_FAB2(SCH_1):SVID_ALERT1_CPU1_R_N
    1  SVID_ALERT1_CPU1_N      A  @BASEBOARD_FAB2_LIB.BASEBOARD_FAB2(SCH_1):SVID_ALERT1_CPU1_N

RES  I24  R1C2   [RES_0402-0.0,5%,1/16W,CHIP,G21A]
    2  SVID_DIO1_CPU1_R      B  @BASEBOARD_FAB2_LIB.BASEBOARD_FAB2(SCH_1):SVID_DIO1_CPU1_R
    1  SVID_DIO1_CPU1      A  @BASEBOARD_FAB2_LIB.BASEBOARD_FAB2(SCH_1):SVID_DIO1_CPU1

RES  I25  R1C3   [RES_0402-0.0,5%,1/16W,CHIP,G21A]
    2  SVID_CLK1_CPU1_R      B  @BASEBOARD_FAB2_LIB.BASEBOARD_FAB2(SCH_1):SVID_CLK1_CPU1_R
    1  SVID_CLK1_CPU1      A  @BASEBOARD_FAB2_LIB.BASEBOARD_FAB2(SCH_1):SVID_CLK1_CPU1

RES  I33  R1C4   [RES_0402-100.0,1%,1/16W,CHIP,GA]
    1  VSENSE_PVSA_CPU1_N      A  @BASEBOARD_FAB2_LIB.BASEBOARD_FAB2(SCH_1):VSENSE_PVSA_CPU1_N
    2  GND                B  @BASEBOARD_FAB2_LIB.BASEBOARD_FAB2(SCH_1):GND

RES  I32  R1C5   [RES_0402-0.0,5%,1/16W,CHIP,G21A]
    2  VSENSE_PVSA_CPU1_SKT_VRTN      B  @BASEBOARD_FAB2_LIB.BASEBOARD_FAB2(SCH_1):VSENSE_PVSA_CPU1_SKT_VRTN
    1  VSENSE_PVSA_CPU1_N      A  @BASEBOARD_FAB2_LIB.BASEBOARD_FAB2(SCH_1):VSENSE_PVSA_CPU1_N

RES  I34  R1C6   [RES_0402-1.00K,1%,1/16W,EMPTY,A]
    1  VSENSE_PVSA_CPU1_P      A  @BASEBOARD_FAB2_LIB.BASEBOARD_FAB2(SCH_1):VSENSE_PVSA_CPU1_P
    2  VSENSE_PVSA_CPU1_N      B  @BASEBOARD_FAB2_LIB.BASEBOARD_FAB2(SCH_1):VSENSE_PVSA_CPU1_N

RES  I31  R1C7   [RES_0402-0.0,5%,1/16W,CHIP,G21A]
    2  VSENSE_PVSA_CPU1_SKT_VSEN      B  @BASEBOARD_FAB2_LIB.BASEBOARD_FAB2(SCH_1):VSENSE_PVSA_CPU1_SKT_VSEN
    1  VSENSE_PVSA_CPU1_P      A  @BASEBOARD_FAB2_LIB.BASEBOARD_FAB2(SCH_1):VSENSE_PVSA_CPU1_P

RES  I104  R1C9   [RES_0402-0.0,5%,1/16W,EMPTY,G2A]
    1  IRQ_BOARD_BMC_ALERT_N      A  @BASEBOARD_FAB2_LIB.BASEBOARD_FAB2(SCH_1):IRQ_BOARD_BMC_ALERT_N
    2  FAN_TACH2_R        B  @BASEBOARD_FAB2_LIB.BASEBOARD_FAB2(SCH_1):FAN_TACH2_R

RES  I101  R1C10  [RES_0402-0.0,5%,1/16W,EMPTY,G2A]
    1  SMB_LAN_STBY_LVC3_SDA      A  @BASEBOARD_FAB2_LIB.BASEBOARD_FAB2(SCH_1):SMB_LAN_STBY_LVC3_SDA
    2  FAN_TACH3_R        B  @BASEBOARD_FAB2_LIB.BASEBOARD_FAB2(SCH_1):FAN_TACH3_R

RES  I97  R1C11  [RES_0402-0.0,5%,1/16W,EMPTY,G2A]
    1  SMB_LAN_STBY_LVC3_SCL      A  @BASEBOARD_FAB2_LIB.BASEBOARD_FAB2(SCH_1):SMB_LAN_STBY_LVC3_SCL
    2  FAN_TACH1_R        B  @BASEBOARD_FAB2_LIB.BASEBOARD_FAB2(SCH_1):FAN_TACH1_R

RES  I29  R1C12  [RES_0402-100.0,1%,1/16W,CHIP,GA]
    1  VSENSE_PVSA_CPU1_P      A  @BASEBOARD_FAB2_LIB.BASEBOARD_FAB2(SCH_1):VSENSE_PVSA_CPU1_P
    2  PVSA_CPU1          B  @BASEBOARD_FAB2_LIB.BASEBOARD_FAB2(SCH_1):PVSA_CPU1

RES  I49  R1C13  [RES_0402-100.0K,1%,1/16W,CHIP,B]
    2  VR_PVCCIN_CPU1_AVINSEN      B  @BASEBOARD_FAB2_LIB.BASEBOARD_FAB2(SCH_1):VR_PVCCIN_CPU1_AVINSEN
    1  VR_FET_SW_P12V_STBY_PVCCIN_CPU1      A  @BASEBOARD_FAB2_LIB.BASEBOARD_FAB2(SCH_1):VR_FET_SW_P12V_STBY_PVCCIN_CPU1

RES  I46  R1C14  [RES_0402-0.0,5%,1/16W,CHIP,G21A]
    2  VR_PVCCIN_CPU1_VDD      B  @BASEBOARD_FAB2_LIB.BASEBOARD_FAB2(SCH_1):VR_PVCCIN_CPU1_VDD
    1  P3V3_STBY          A  @BASEBOARD_FAB2_LIB.BASEBOARD_FAB2(SCH_1):P3V3_STBY

RES  I56  R1C16  [RES_0402-1.5K,1%,1/16W,CHIP,G2A]
    1  VR_PVCCIN_CPU1_AVINSEN      A  @BASEBOARD_FAB2_LIB.BASEBOARD_FAB2(SCH_1):VR_PVCCIN_CPU1_AVINSEN
    2  GND                B  @BASEBOARD_FAB2_LIB.BASEBOARD_FAB2(SCH_1):GND

RES  I34  R1C18  [RES_0402-2.26K,1.0%,1/16W,EMPTA]
    2  PU_VR_PVCCIN_CPU1_IMON      B  @BASEBOARD_FAB2_LIB.BASEBOARD_FAB2(SCH_1):PU_VR_PVCCIN_CPU1_IMON
    1  P3V3_STBY          A  @BASEBOARD_FAB2_LIB.BASEBOARD_FAB2(SCH_1):P3V3_STBY

RES  I77  R1C21  [RES_0402-10.0,1%,1/16W,CHIP,G2A]
    1  VSENSE_PVSA_CPU1_P      A  @BASEBOARD_FAB2_LIB.BASEBOARD_FAB2(SCH_1):VSENSE_PVSA_CPU1_P
    2  VSENSE_PVSA_CPU1_BVSP      B  @BASEBOARD_FAB2_LIB.BASEBOARD_FAB2(SCH_1):VSENSE_PVSA_CPU1_BVSP

RES  I27  R1C23  [RES_0402-0.0,5%,1/16W,CHIP,G21A]
    2  SMB_VR_STBY_LVC3_SDA      B  @BASEBOARD_FAB2_LIB.BASEBOARD_FAB2(SCH_1):SMB_VR_STBY_LVC3_SDA
    1  SMB_VR_SDA_R1      A  @BASEBOARD_FAB2_LIB.BASEBOARD_FAB2(SCH_1):SMB_VR_SDA_R1

RES  I28  R1C25  [RES_0402-0.0,5%,1/16W,CHIP,G21A]
    2  SMB_VR_STBY_LVC3_SCL      B  @BASEBOARD_FAB2_LIB.BASEBOARD_FAB2(SCH_1):SMB_VR_STBY_LVC3_SCL
    1  SMB_VR_SCL_R1      A  @BASEBOARD_FAB2_LIB.BASEBOARD_FAB2(SCH_1):SMB_VR_SCL_R1

RES  I35  R1C28  [RES_0402-1.00K,1%,1/16W,CHIP,GA]
    2  VR_VRRDY_PVCCIN_CPU1      B  @BASEBOARD_FAB2_LIB.BASEBOARD_FAB2(SCH_1):VR_VRRDY_PVCCIN_CPU1
    1  P3V3_STBY          A  @BASEBOARD_FAB2_LIB.BASEBOARD_FAB2(SCH_1):P3V3_STBY

RES  I113  R1C30  [RES_0402-22.1,1.0%,1/16W,CHIP,A]
    1  VR_VRRDY_PVCCIN_CPU1      A  @BASEBOARD_FAB2_LIB.BASEBOARD_FAB2(SCH_1):VR_VRRDY_PVCCIN_CPU1
    2  PWRGD_PVCCIN_CPU1      B  @BASEBOARD_FAB2_LIB.BASEBOARD_FAB2(SCH_1):PWRGD_PVCCIN_CPU1

RES  I110  R1C31  [RES_0402-0.0,5%,1/16W,EMPTY,G2A]
    1  FM_XRC_READY_N      A  @BASEBOARD_FAB2_LIB.BASEBOARD_FAB2(SCH_1):FM_XRC_READY_N
    2  FAN_TACH0_R        B  @BASEBOARD_FAB2_LIB.BASEBOARD_FAB2(SCH_1):FAN_TACH0_R

RES  I312  R1C32  [RES_0402-1.00K,1%,1/16W,CHIP,GA]
    2  PD_PIROM_CPU1_ADDR2      B  @BASEBOARD_FAB2_LIB.BASEBOARD_FAB2(SCH_1):PD_PIROM_CPU1_ADDR2
    1  GND                A  @BASEBOARD_FAB2_LIB.BASEBOARD_FAB2(SCH_1):GND

RES  I313  R1C33  [RES_0402-1.00K,1%,1/16W,CHIP,GA]
    2  PD_PIROM_CPU1_ADDR1      B  @BASEBOARD_FAB2_LIB.BASEBOARD_FAB2(SCH_1):PD_PIROM_CPU1_ADDR1
    1  GND                A  @BASEBOARD_FAB2_LIB.BASEBOARD_FAB2(SCH_1):GND

RES  I320  R1C34  [RES_0402-10.0K,1%,1/16W,CHIP,GA]
    2  PU_PIROM_CPU1_ADDR0      B  @BASEBOARD_FAB2_LIB.BASEBOARD_FAB2(SCH_1):PU_PIROM_CPU1_ADDR0
    1  P3V3_STBY          A  @BASEBOARD_FAB2_LIB.BASEBOARD_FAB2(SCH_1):P3V3_STBY

RES  I336  R1C35  [RES_0402-3.32K,1%,1/16W,EMPTY,A]
    1  P3V3_STBY          A  @BASEBOARD_FAB2_LIB.BASEBOARD_FAB2(SCH_1):P3V3_STBY
    2  FM_CPU1_SM_WP      B  @BASEBOARD_FAB2_LIB.BASEBOARD_FAB2(SCH_1):FM_CPU1_SM_WP

RES  I337  R1C36  [RES_0402-1.00K,1%,1/16W,CHIP,GA]
    2  GND                B  @BASEBOARD_FAB2_LIB.BASEBOARD_FAB2(SCH_1):GND
    1  FM_CPU1_SM_WP      A  @BASEBOARD_FAB2_LIB.BASEBOARD_FAB2(SCH_1):FM_CPU1_SM_WP

RES  I52  R1C37  [RES_0402-68.1K,1%,1/16W,EMPTY,A]
    1  VR_PVSA_CPU1_OCSET      A  @BASEBOARD_FAB2_LIB.BASEBOARD_FAB2(SCH_1):VR_PVSA_CPU1_OCSET
    2  GND                B  @BASEBOARD_FAB2_LIB.BASEBOARD_FAB2(SCH_1):GND

RES  I116  R1D1   [RES_0402-33.2,1%,1/16W,CHIP,G2A]
    1  PWRGD_PVSA_CPU1_R      A  @BASEBOARD_FAB2_LIB.BASEBOARD_FAB2(SCH_1):PWRGD_PVSA_CPU1_R
    2  PWRGD_PVSA_CPU1      B  @BASEBOARD_FAB2_LIB.BASEBOARD_FAB2(SCH_1):PWRGD_PVSA_CPU1

RES  I38  R1D2   [RES_0402-0.0,5%,1/16W,CHIP,G21A]
    1  SVID_VDIO_PVCCIN_CPU1      A  @BASEBOARD_FAB2_LIB.BASEBOARD_FAB2(SCH_1):SVID_VDIO_PVCCIN_CPU1
    2  SVID_DIO0_CPU1_R      B  @BASEBOARD_FAB2_LIB.BASEBOARD_FAB2(SCH_1):SVID_DIO0_CPU1_R

RES  I37  R1D3   [RES_0402-0.0,5%,1/16W,CHIP,G21A]
    1  SVID_VALERT_VCCIN_CPU1      A  @BASEBOARD_FAB2_LIB.BASEBOARD_FAB2(SCH_1):SVID_VALERT_VCCIN_CPU1
    2  SVID_ALERT0_CPU1_R_N      B  @BASEBOARD_FAB2_LIB.BASEBOARD_FAB2(SCH_1):SVID_ALERT0_CPU1_R_N

RES  I79  R1D4   [RES_0402-10.0,1%,1/16W,CHIP,G2A]
    1  VSENSE_PVCCIN_CPU1_P      A  @BASEBOARD_FAB2_LIB.BASEBOARD_FAB2(SCH_1):VSENSE_PVCCIN_CPU1_P
    2  VSENSE_PVCCIN_CPU1_AVSP      B  @BASEBOARD_FAB2_LIB.BASEBOARD_FAB2(SCH_1):VSENSE_PVCCIN_CPU1_AVSP

RES  I6   R1D6   [RES_0402-1.00K,1%,1/16W,CHIP,GA]
    1  P3V3_STBY          A  @BASEBOARD_FAB2_LIB.BASEBOARD_FAB2(SCH_1):P3V3_STBY
    2  IRQ_PVCCIN_CPU1_VRHOT_LVC3_R_N      B  @BASEBOARD_FAB2_LIB.BASEBOARD_FAB2(SCH_1):IRQ_PVCCIN_CPU1_VRHOT_LVC3_R_N

RES  I7   R1D7   [RES_0402-2.26K,1.0%,1/16W,CHIPA]
    1  P3V3_STBY          A  @BASEBOARD_FAB2_LIB.BASEBOARD_FAB2(SCH_1):P3V3_STBY
    2  FM_PVCCIN_CPU1_PWR_IN_ALERT_N      B  @BASEBOARD_FAB2_LIB.BASEBOARD_FAB2(SCH_1):FM_PVCCIN_CPU1_PWR_IN_ALERT_N

RES  I36  R1D8   [RES_0402-1.00K,1%,1/16W,CHIP,GA]
    2  PWRGD_PVSA_CPU1_R      B  @BASEBOARD_FAB2_LIB.BASEBOARD_FAB2(SCH_1):PWRGD_PVSA_CPU1_R
    1  P3V3_STBY          A  @BASEBOARD_FAB2_LIB.BASEBOARD_FAB2(SCH_1):P3V3_STBY

RES  I54  R1D9   [RES_0402-150.0,1%,1/16W,CHIP,GA]
    2  SVID_VCLK_PVCCIN_CPU1      B  @BASEBOARD_FAB2_LIB.BASEBOARD_FAB2(SCH_1):SVID_VCLK_PVCCIN_CPU1
    1  SVID_CLK0_CPU1_R      A  @BASEBOARD_FAB2_LIB.BASEBOARD_FAB2(SCH_1):SVID_CLK0_CPU1_R

RES  I189  R1D10  [RES_0402-10.0K,1%,1/16W,CHIP,GA]
    1  P3V3_STBY          A  @BASEBOARD_FAB2_LIB.BASEBOARD_FAB2(SCH_1):P3V3_STBY
    2  A_HSC_LOW_GATE      B  @BASEBOARD_FAB2_LIB.BASEBOARD_FAB2(SCH_1):A_HSC_LOW_GATE

RES  I88  R1D11  [RES_0402-100.0K,1%,1/16W,CHIP,A]
    1  A_HSC_LOW_EN       A  @BASEBOARD_FAB2_LIB.BASEBOARD_FAB2(SCH_1):A_HSC_LOW_EN
    2  AGND_HSC           B  @BASEBOARD_FAB2_LIB.BASEBOARD_FAB2(SCH_1):AGND_HSC

RES  I174  R1D12  [RES_0402-10.0K,1%,1/16W,CHIP,GA]
    1  A_HSC_LOW          A  @BASEBOARD_FAB2_LIB.BASEBOARD_FAB2(SCH_1):A_HSC_LOW
    2  AGND_HSC           B  @BASEBOARD_FAB2_LIB.BASEBOARD_FAB2(SCH_1):AGND_HSC

RES  I84  R1D13  [RES_0402-90.9K,1%,1/16W,CHIP,GA]
    1  A_HSC_ISET_S       A  @BASEBOARD_FAB2_LIB.BASEBOARD_FAB2(SCH_1):A_HSC_ISET_S
    2  A_HSC_ISET         B  @BASEBOARD_FAB2_LIB.BASEBOARD_FAB2(SCH_1):A_HSC_ISET

RES  I173  R1D14  [RES_0402-105.0K,1%,1/16W,CHIP,A]
    2  A_HSC_LOW          B  @BASEBOARD_FAB2_LIB.BASEBOARD_FAB2(SCH_1):A_HSC_LOW
    1  A_HSC_CSOUT        A  @BASEBOARD_FAB2_LIB.BASEBOARD_FAB2(SCH_1):A_HSC_CSOUT

RES  I92  R1D15  [RES_0402-100.0K,1%,1/16W,CHIP,A]
    1  P12V_PSU           A  @BASEBOARD_FAB2_LIB.BASEBOARD_FAB2(SCH_1):P12V_PSU
    2  A_HSC_OCP_SEL      B  @BASEBOARD_FAB2_LIB.BASEBOARD_FAB2(SCH_1):A_HSC_OCP_SEL

RES  I85  R1D16  [RES_0402-69.8K,1%,1/16W,CHIP,GA]
    2  A_HSC_ISET_S2      B  @BASEBOARD_FAB2_LIB.BASEBOARD_FAB2(SCH_1):A_HSC_ISET_S2
    1  A_HSC_ISET         A  @BASEBOARD_FAB2_LIB.BASEBOARD_FAB2(SCH_1):A_HSC_ISET

RES  I87  R1D18  [RES_0402-100.0K,1%,1/16W,CHIP,A]
    1  A_HSC_HIGH_EN      A  @BASEBOARD_FAB2_LIB.BASEBOARD_FAB2(SCH_1):A_HSC_HIGH_EN
    2  AGND_HSC           B  @BASEBOARD_FAB2_LIB.BASEBOARD_FAB2(SCH_1):AGND_HSC

RES  I175  R1D19  [RES_0402-10.0K,1%,1/16W,CHIP,GA]
    1  A_HSC_HIGH         A  @BASEBOARD_FAB2_LIB.BASEBOARD_FAB2(SCH_1):A_HSC_HIGH
    2  AGND_HSC           B  @BASEBOARD_FAB2_LIB.BASEBOARD_FAB2(SCH_1):AGND_HSC

RES  I172  R1D20  [RES_0402-150.0K,1%,1/16W,CHIP,A]
    2  A_HSC_HIGH         B  @BASEBOARD_FAB2_LIB.BASEBOARD_FAB2(SCH_1):A_HSC_HIGH
    1  A_HSC_CSOUT        A  @BASEBOARD_FAB2_LIB.BASEBOARD_FAB2(SCH_1):A_HSC_CSOUT

RES  I204  R1D21  [RES_0402-4.75K,1%,1/16W,CHIP,GA]
    1  P3V3_STBY          A  @BASEBOARD_FAB2_LIB.BASEBOARD_FAB2(SCH_1):P3V3_STBY
    2  FM_OC_DETECT_EN      B  @BASEBOARD_FAB2_LIB.BASEBOARD_FAB2(SCH_1):FM_OC_DETECT_EN

RES  I158  R1D22  [RES_0402-10.0K,1%,1/16W,CHIP,GA]
    1  P3V3_STBY          A  @BASEBOARD_FAB2_LIB.BASEBOARD_FAB2(SCH_1):P3V3_STBY
    2  FM_OC_DETECT_N      B  @BASEBOARD_FAB2_LIB.BASEBOARD_FAB2(SCH_1):FM_OC_DETECT_N

RES  I191  R1D23  [RES_0402-10.0K,1%,1/16W,CHIP,GA]
    1  P3V3_STBY          A  @BASEBOARD_FAB2_LIB.BASEBOARD_FAB2(SCH_1):P3V3_STBY
    2  IRQ_OC_DETECT_N      B  @BASEBOARD_FAB2_LIB.BASEBOARD_FAB2(SCH_1):IRQ_OC_DETECT_N

RES  I27  R1D24  [RES_0402-0.0,5%,1/16W,CHIP,G21A]
    1  SMB_BMC_PMBUS_STBY_LVC3_SCL      A  @BASEBOARD_FAB2_LIB.BASEBOARD_FAB2(SCH_1):SMB_BMC_PMBUS_STBY_LVC3_SCL
    2  SMB_3V3SB_HSC_SCL_R      B  @BASEBOARD_FAB2_LIB.BASEBOARD_FAB2(SCH_1):SMB_3V3SB_HSC_SCL_R

RES  I28  R1D25  [RES_0402-0.0,5%,1/16W,CHIP,G21A]
    1  SMB_BMC_PMBUS_STBY_LVC3_SDA      A  @BASEBOARD_FAB2_LIB.BASEBOARD_FAB2(SCH_1):SMB_BMC_PMBUS_STBY_LVC3_SDA
    2  SMB_3V3SB_HSC_SDA_R      B  @BASEBOARD_FAB2_LIB.BASEBOARD_FAB2(SCH_1):SMB_3V3SB_HSC_SDA_R

RES  I109  R1D26  [RES_0402-33.2,1%,1/16W,CHIP,G2A]
    1  IRQ_SML1_PMBUS_ALERT_R_N      A  @BASEBOARD_FAB2_LIB.BASEBOARD_FAB2(SCH_1):IRQ_SML1_PMBUS_ALERT_R_N
    2  IRQ_SML1_PMBUS_ALERT_N      B  @BASEBOARD_FAB2_LIB.BASEBOARD_FAB2(SCH_1):IRQ_SML1_PMBUS_ALERT_N

RES  I38  R1D27  [RES_0402-4.75K,1%,1/16W,EMPTY,A]
    2  FM_P12V_HSC_ADR2      B  @BASEBOARD_FAB2_LIB.BASEBOARD_FAB2(SCH_1):FM_P12V_HSC_ADR2
    1  A_HSC_VCAP         A  @BASEBOARD_FAB2_LIB.BASEBOARD_FAB2(SCH_1):A_HSC_VCAP

RES  I26  R1D28  [RES_0402-100.0,1%,1/16W,EMPTY,A]
    1  PD_HSC_RETRY_N      A  @BASEBOARD_FAB2_LIB.BASEBOARD_FAB2(SCH_1):PD_HSC_RETRY_N
    2  AGND_HSC           B  @BASEBOARD_FAB2_LIB.BASEBOARD_FAB2(SCH_1):AGND_HSC

RES  I37  R1D29  [RES_0402-4.75K,1%,1/16W,EMPTY,A]
    2  FM_P12V_HSC_ADR1      B  @BASEBOARD_FAB2_LIB.BASEBOARD_FAB2(SCH_1):FM_P12V_HSC_ADR1
    1  A_HSC_VCAP         A  @BASEBOARD_FAB2_LIB.BASEBOARD_FAB2(SCH_1):A_HSC_VCAP

RES  I110  R1D30  [RES_0402-33.2,1%,1/16W,CHIP,G2A]
    1  IRQ_HSC_FAULT_R_N      A  @BASEBOARD_FAB2_LIB.BASEBOARD_FAB2(SCH_1):IRQ_HSC_FAULT_R_N
    2  IRQ_HSC_FAULT_N      B  @BASEBOARD_FAB2_LIB.BASEBOARD_FAB2(SCH_1):IRQ_HSC_FAULT_N

RES  I43  R1D31  [RES_0402-6.19K,1%,1/16W,CHIP,GA]
    1  PWRGD_P12V_R       A  @BASEBOARD_FAB2_LIB.BASEBOARD_FAB2(SCH_1):PWRGD_P12V_R
    2  GND                B  @BASEBOARD_FAB2_LIB.BASEBOARD_FAB2(SCH_1):GND

RES  I17  R1D32  [RES_0402-100.0K,1%,1/16W,CHIP,A]
    1  A_HSC_VCAP         A  @BASEBOARD_FAB2_LIB.BASEBOARD_FAB2(SCH_1):A_HSC_VCAP
    2  A_HSC_ISTART       B  @BASEBOARD_FAB2_LIB.BASEBOARD_FAB2(SCH_1):A_HSC_ISTART

RES  I108  R1D33  [RES_0402-33.2,1%,1/16W,CHIP,G2A]
    1  PWRGD_P12V_R       A  @BASEBOARD_FAB2_LIB.BASEBOARD_FAB2(SCH_1):PWRGD_P12V_R
    2  PWRGD_P12V_HSC      B  @BASEBOARD_FAB2_LIB.BASEBOARD_FAB2(SCH_1):PWRGD_P12V_HSC

RES  I102  R1D34  [RES_0402-16K,1.0%,1/16W,CHIP,GA]
    1  A_HSC_ISTART       A  @BASEBOARD_FAB2_LIB.BASEBOARD_FAB2(SCH_1):A_HSC_ISTART
    2  AGND_HSC           B  @BASEBOARD_FAB2_LIB.BASEBOARD_FAB2(SCH_1):AGND_HSC

RES  I12  R1D35  [RES_0402-4.75K,1%,1/16W,CHIP,GA]
    1  P3V3_STBY          A  @BASEBOARD_FAB2_LIB.BASEBOARD_FAB2(SCH_1):P3V3_STBY
    2  FM_OC_DETECT_EN_N      B  @BASEBOARD_FAB2_LIB.BASEBOARD_FAB2(SCH_1):FM_OC_DETECT_EN_N

RES  I65  R1D36  [RES_0402-1.00K,1%,1/16W,CHIP,GA]
    1  P12V_STBY          A  @BASEBOARD_FAB2_LIB.BASEBOARD_FAB2(SCH_1):P12V_STBY
    2  A_HSC_VOUT         B  @BASEBOARD_FAB2_LIB.BASEBOARD_FAB2(SCH_1):A_HSC_VOUT

RES  I15  R1D37  [RES_0402-100.0K,1%,1/16W,CHIP,A]
    1  A_HSC_VCAP         A  @BASEBOARD_FAB2_LIB.BASEBOARD_FAB2(SCH_1):A_HSC_VCAP
    2  A_HSC_ISET         B  @BASEBOARD_FAB2_LIB.BASEBOARD_FAB2(SCH_1):A_HSC_ISET

RES  I16  R1D39  [RES_0402-100.0K,1%,1/16W,CHIP,A]
    1  A_HSC_VCAP         A  @BASEBOARD_FAB2_LIB.BASEBOARD_FAB2(SCH_1):A_HSC_VCAP
    2  A_HSC_PSET         B  @BASEBOARD_FAB2_LIB.BASEBOARD_FAB2(SCH_1):A_HSC_PSET

RES  I100  R1D40  [RES_0402-40.2K,1%,1/16W,CHIP,GA]
    1  A_HSC_PSET         A  @BASEBOARD_FAB2_LIB.BASEBOARD_FAB2(SCH_1):A_HSC_PSET
    2  AGND_HSC           B  @BASEBOARD_FAB2_LIB.BASEBOARD_FAB2(SCH_1):AGND_HSC

RES  I19  R1D41  [RES_0805-0.0,5%,1/8W,CHIP,G221A]
    1  GND                A  @BASEBOARD_FAB2_LIB.BASEBOARD_FAB2(SCH_1):GND
    2  AGND_HSC           B  @BASEBOARD_FAB2_LIB.BASEBOARD_FAB2(SCH_1):AGND_HSC

RES  I13  R1D42  [RES_0402-11K,1%,1/16W,CHIP,G21A]
    1  A_HSC_UV           A  @BASEBOARD_FAB2_LIB.BASEBOARD_FAB2(SCH_1):A_HSC_UV
    2  AGND_HSC           B  @BASEBOARD_FAB2_LIB.BASEBOARD_FAB2(SCH_1):AGND_HSC

RES  I9   R1D43  [RES_0402-7.5K,1%,1/16W,CHIP,G2A]
    1  A_HSC_OV           A  @BASEBOARD_FAB2_LIB.BASEBOARD_FAB2(SCH_1):A_HSC_OV
    2  AGND_HSC           B  @BASEBOARD_FAB2_LIB.BASEBOARD_FAB2(SCH_1):AGND_HSC

RES  I44  R1D44  [RES_0402-0.0,5%,1/16W,CHIP,G21A]
    1  A_HSC_MOP          A  @BASEBOARD_FAB2_LIB.BASEBOARD_FAB2(SCH_1):A_HSC_MOP
    2  A_HSC_HSP          B  @BASEBOARD_FAB2_LIB.BASEBOARD_FAB2(SCH_1):A_HSC_HSP

RES  I43  R1D45  [RES_0402-0.0,5%,1/16W,CHIP,G21A]
    1  A_HSC_MON          A  @BASEBOARD_FAB2_LIB.BASEBOARD_FAB2(SCH_1):A_HSC_MON
    2  A_HSC_HSN          B  @BASEBOARD_FAB2_LIB.BASEBOARD_FAB2(SCH_1):A_HSC_HSN

RES  I48  R1D46  [RES_0402-10.0,1%,1/16W,CHIP,G2A]
    1  P12V_HSC_SENP0      A  @BASEBOARD_FAB2_LIB.BASEBOARD_FAB2(SCH_1):P12V_HSC_SENP0
    2  A_HSC_HSP          B  @BASEBOARD_FAB2_LIB.BASEBOARD_FAB2(SCH_1):A_HSC_HSP

RES  I52  R1D47  [RES_0402-10.0,1%,1/16W,CHIP,G2A]
    1  P12V_HSC_SENN0      A  @BASEBOARD_FAB2_LIB.BASEBOARD_FAB2(SCH_1):P12V_HSC_SENN0
    2  A_HSC_HSN          B  @BASEBOARD_FAB2_LIB.BASEBOARD_FAB2(SCH_1):A_HSC_HSN

RES  I60  R1D48  [RES_0402-10.0,1%,1/16W,CHIP,G2A]
    2  A_HSC_GATE3_R      B  @BASEBOARD_FAB2_LIB.BASEBOARD_FAB2(SCH_1):A_HSC_GATE3_R
    1  A_HSC_GATE         A  @BASEBOARD_FAB2_LIB.BASEBOARD_FAB2(SCH_1):A_HSC_GATE

RES_PWR_6PAD  I50  R1D49  [RES_PWR_6PAD-0.001,1%,3W,CHIP,A]
    5  P12V_PSU           5  @BASEBOARD_FAB2_LIB.BASEBOARD_FAB2(SCH_1):P12V_PSU
    1  P12V_PSU           1  @BASEBOARD_FAB2_LIB.BASEBOARD_FAB2(SCH_1):P12V_PSU
    6  P12V_MB0_SW        6  @BASEBOARD_FAB2_LIB.BASEBOARD_FAB2(SCH_1):P12V_MB0_SW
    2  P12V_MB0_SW        2  @BASEBOARD_FAB2_LIB.BASEBOARD_FAB2(SCH_1):P12V_MB0_SW
    3  P12V_HSC_SENP0      3  @BASEBOARD_FAB2_LIB.BASEBOARD_FAB2(SCH_1):P12V_HSC_SENP0
    4  P12V_HSC_SENN0      4  @BASEBOARD_FAB2_LIB.BASEBOARD_FAB2(SCH_1):P12V_HSC_SENN0

RES  I154  R1D51  [RES_0402-10.0,1%,1/16W,CHIP,G2A]
    2  A_HSC_GATE         B  @BASEBOARD_FAB2_LIB.BASEBOARD_FAB2(SCH_1):A_HSC_GATE
    1  A_HSC_C            A  @BASEBOARD_FAB2_LIB.BASEBOARD_FAB2(SCH_1):A_HSC_C

RES  I59  R1D52  [RES_0402-68.1K,1%,1/16W,EMPTY,A]
    1  VR_PVCCIN_CPU1_PH5_OCSET      A  @BASEBOARD_FAB2_LIB.BASEBOARD_FAB2(SCH_1):VR_PVCCIN_CPU1_PH5_OCSET
    2  GND                B  @BASEBOARD_FAB2_LIB.BASEBOARD_FAB2(SCH_1):GND

RES  I33  R1D53  [RES_0402-2.26K,1.0%,1/16W,EMPTA]
    2  PU_VR_PVCCIN_CPU1_FLT1_SMBALT_N      B  @BASEBOARD_FAB2_LIB.BASEBOARD_FAB2(SCH_1):PU_VR_PVCCIN_CPU1_FLT1_SMBALT_N_IMON
    1  P3V3_STBY          A  @BASEBOARD_FAB2_LIB.BASEBOARD_FAB2(SCH_1):P3V3_STBY

RES  I75  R1D54  [RES_0402-68.1K,1%,1/16W,EMPTY,A]
    1  VR_PVCCIN_CPU1_PH4_OCSET      A  @BASEBOARD_FAB2_LIB.BASEBOARD_FAB2(SCH_1):VR_PVCCIN_CPU1_PH4_OCSET
    2  GND                B  @BASEBOARD_FAB2_LIB.BASEBOARD_FAB2(SCH_1):GND

RES  I76  R1D55  [RES_0402-68.1K,1%,1/16W,EMPTY,A]
    1  VR_PVCCIN_CPU1_PH3_OCSET      A  @BASEBOARD_FAB2_LIB.BASEBOARD_FAB2(SCH_1):VR_PVCCIN_CPU1_PH3_OCSET
    2  GND                B  @BASEBOARD_FAB2_LIB.BASEBOARD_FAB2(SCH_1):GND

RES  I56  R1E1   [RES_0402-10.0,1%,1/16W,CHIP,G2A]
    2  A_HSC_GATE1_R      B  @BASEBOARD_FAB2_LIB.BASEBOARD_FAB2(SCH_1):A_HSC_GATE1_R
    1  A_HSC_GATE         A  @BASEBOARD_FAB2_LIB.BASEBOARD_FAB2(SCH_1):A_HSC_GATE

RES  I7   R1E3   [RES_0603-100.0,1%,1/10W,CHIP,GA]
    1  PVCCIN_CPU1        A  @BASEBOARD_FAB2_LIB.BASEBOARD_FAB2(SCH_1):PVCCIN_CPU1
    2  GND                B  @BASEBOARD_FAB2_LIB.BASEBOARD_FAB2(SCH_1):GND

RES  I15  R1E4   [RES_0402-100.0,1%,1/16W,CHIP,GA]
    1  VSENSE_PVCCIN_CPU1_P      A  @BASEBOARD_FAB2_LIB.BASEBOARD_FAB2(SCH_1):VSENSE_PVCCIN_CPU1_P
    2  PVCCIN_CPU1        B  @BASEBOARD_FAB2_LIB.BASEBOARD_FAB2(SCH_1):PVCCIN_CPU1

RES  I3   R1E5   [RES_0402-1.00K,1%,1/16W,EMPTY,A]
    1  VSENSE_PVCCIN_CPU1_P      A  @BASEBOARD_FAB2_LIB.BASEBOARD_FAB2(SCH_1):VSENSE_PVCCIN_CPU1_P
    2  VSENSE_PVCCIN_CPU1_N      B  @BASEBOARD_FAB2_LIB.BASEBOARD_FAB2(SCH_1):VSENSE_PVCCIN_CPU1_N

RES  I11  R1E6   [RES_0402-0.0,5%,1/16W,CHIP,G21A]
    2  VSENSE_PVCCIN_CPU1_SKT_VSEN      B  @BASEBOARD_FAB2_LIB.BASEBOARD_FAB2(SCH_1):VSENSE_PVCCIN_CPU1_SKT_VSEN
    1  VSENSE_PVCCIN_CPU1_P      A  @BASEBOARD_FAB2_LIB.BASEBOARD_FAB2(SCH_1):VSENSE_PVCCIN_CPU1_P

RES  I10  R1E7   [RES_0402-0.0,5%,1/16W,CHIP,G21A]
    2  VSENSE_PVCCIN_CPU1_SKT_VRTN      B  @BASEBOARD_FAB2_LIB.BASEBOARD_FAB2(SCH_1):VSENSE_PVCCIN_CPU1_SKT_VRTN
    1  VSENSE_PVCCIN_CPU1_N      A  @BASEBOARD_FAB2_LIB.BASEBOARD_FAB2(SCH_1):VSENSE_PVCCIN_CPU1_N

RES  I9   R1E8   [RES_0402-100.0,1%,1/16W,CHIP,GA]
    1  VSENSE_PVCCIN_CPU1_N      A  @BASEBOARD_FAB2_LIB.BASEBOARD_FAB2(SCH_1):VSENSE_PVCCIN_CPU1_N
    2  GND                B  @BASEBOARD_FAB2_LIB.BASEBOARD_FAB2(SCH_1):GND

RES  I34  R1E9   [RES_0402-1.00K,1%,1/16W,CHIP,GA]
    2  PU_TMP421_2_A0      B  @BASEBOARD_FAB2_LIB.BASEBOARD_FAB2(SCH_1):PU_TMP421_2_A0
    1  P3V3_STBY          A  @BASEBOARD_FAB2_LIB.BASEBOARD_FAB2(SCH_1):P3V3_STBY

RES  I38  R1E10  [RES_0402-1.00K,1%,1/16W,CHIP,GA]
    2  PD_TMP421_2_A1      B  @BASEBOARD_FAB2_LIB.BASEBOARD_FAB2(SCH_1):PD_TMP421_2_A1
    1  P3V3_STBY          A  @BASEBOARD_FAB2_LIB.BASEBOARD_FAB2(SCH_1):P3V3_STBY

RES  I120  R1E11  [RES_0402-10.0K,1%,1/16W,EMPTY,A]
    1  P3V3_STBY          A  @BASEBOARD_FAB2_LIB.BASEBOARD_FAB2(SCH_1):P3V3_STBY
    2  FM_ENABLE_FAN_POWER      B  @BASEBOARD_FAB2_LIB.BASEBOARD_FAB2(SCH_1):FM_ENABLE_FAN_POWER

RES  I51  R1E12  [RES_0402-4.75K,1%,1/16W,CHIP,GA]
    1  P5V_STBY           A  @BASEBOARD_FAB2_LIB.BASEBOARD_FAB2(SCH_1):P5V_STBY
    2  FAN_PWM_OUT_SYS0_R      B  @BASEBOARD_FAB2_LIB.BASEBOARD_FAB2(SCH_1):FAN_PWM_OUT_SYS0_R

RES  I67  R1E13  [RES_0402-68.1K,1%,1/16W,EMPTY,A]
    1  VR_PVCCIN_CPU1_PH2_OCSET      A  @BASEBOARD_FAB2_LIB.BASEBOARD_FAB2(SCH_1):VR_PVCCIN_CPU1_PH2_OCSET
    2  GND                B  @BASEBOARD_FAB2_LIB.BASEBOARD_FAB2(SCH_1):GND

RES  I68  R1E14  [RES_0402-68.1K,1%,1/16W,EMPTY,A]
    1  VR_PVCCIN_CPU1_PH1_OCSET      A  @BASEBOARD_FAB2_LIB.BASEBOARD_FAB2(SCH_1):VR_PVCCIN_CPU1_PH1_OCSET
    2  GND                B  @BASEBOARD_FAB2_LIB.BASEBOARD_FAB2(SCH_1):GND

RES  I45  R1F1   [RES_0402-4.75K,1%,1/16W,CHIP,GA]
    1  P3V3_STBY          A  @BASEBOARD_FAB2_LIB.BASEBOARD_FAB2(SCH_1):P3V3_STBY
    2  FAN_TACH0          B  @BASEBOARD_FAB2_LIB.BASEBOARD_FAB2(SCH_1):FAN_TACH0

RES  I43  R1F2   [RES_0402-100.0,1%,1/16W,CHIP,GA]
    2  FAN_TACH0_CPU0_D2      B  @BASEBOARD_FAB2_LIB.BASEBOARD_FAB2(SCH_1):FAN_TACH0_CPU0_D2
    1  FAN_TACH0          A  @BASEBOARD_FAB2_LIB.BASEBOARD_FAB2(SCH_1):FAN_TACH0

RES  I131  R1F3   [RES_1206-0.002,1%,1W,CHIP,G521A]
    2  P12V_STBY          B  @BASEBOARD_FAB2_LIB.BASEBOARD_FAB2(SCH_1):P12V_STBY
    1  P12V_NVDIMM_GHJ      A  @BASEBOARD_FAB2_LIB.BASEBOARD_FAB2(SCH_1):P12V_NVDIMM_GHJ

RES  I7   R1F4   [RES_0402-2,1.0%,1/16W,CHIP,G21A]
    2  M_G_VREF           B  @BASEBOARD_FAB2_LIB.BASEBOARD_FAB2(SCH_1):M_G_VREF
    1  M_G_CPU_VREF       A  @BASEBOARD_FAB2_LIB.BASEBOARD_FAB2(SCH_1):M_G_CPU_VREF

RES  I6   R1F5   [RES_0402-1.00K,1%,1/16W,CHIP,GA]
    1  PVDDQ_GHJ          A  @BASEBOARD_FAB2_LIB.BASEBOARD_FAB2(SCH_1):PVDDQ_GHJ
    2  M_G_VREF           B  @BASEBOARD_FAB2_LIB.BASEBOARD_FAB2(SCH_1):M_G_VREF

RES  I2   R1F6   [RES_0402-1.00K,1%,1/16W,CHIP,GA]
    1  M_G_VREF           A  @BASEBOARD_FAB2_LIB.BASEBOARD_FAB2(SCH_1):M_G_VREF
    2  GND                B  @BASEBOARD_FAB2_LIB.BASEBOARD_FAB2(SCH_1):GND

RES  I268  R1F8   [RES_0402-0.0,5%,1/16W,CHIP,G21A]
    2  FAN_TACH0_R        B  @BASEBOARD_FAB2_LIB.BASEBOARD_FAB2(SCH_1):FAN_TACH0_R
    1  FAN_TACH0          A  @BASEBOARD_FAB2_LIB.BASEBOARD_FAB2(SCH_1):FAN_TACH0

RES  I107  R1F9   [RES_0402-0.0,5%,1/16W,EMPTY,G2A]
    1  FM_BMC_READY_N      A  @BASEBOARD_FAB2_LIB.BASEBOARD_FAB2(SCH_1):FM_BMC_READY_N
    2  FAN_PWM_OUT_SYS0_R1      B  @BASEBOARD_FAB2_LIB.BASEBOARD_FAB2(SCH_1):FAN_PWM_OUT_SYS0_R1

RES  I25  R1G1   [RES_0402-2,1.0%,1/16W,CHIP,G21A]
    2  M_H_VREF           B  @BASEBOARD_FAB2_LIB.BASEBOARD_FAB2(SCH_1):M_H_VREF
    1  M_H_CPU_VREF       A  @BASEBOARD_FAB2_LIB.BASEBOARD_FAB2(SCH_1):M_H_CPU_VREF

RES  I19  R1G2   [RES_0402-1.00K,1%,1/16W,CHIP,GA]
    1  PVDDQ_GHJ          A  @BASEBOARD_FAB2_LIB.BASEBOARD_FAB2(SCH_1):PVDDQ_GHJ
    2  M_H_VREF           B  @BASEBOARD_FAB2_LIB.BASEBOARD_FAB2(SCH_1):M_H_VREF

RES  I20  R1G3   [RES_0402-1.00K,1%,1/16W,CHIP,GA]
    1  M_H_VREF           A  @BASEBOARD_FAB2_LIB.BASEBOARD_FAB2(SCH_1):M_H_VREF
    2  GND                B  @BASEBOARD_FAB2_LIB.BASEBOARD_FAB2(SCH_1):GND

RES  I32  R1G5   [RES_0402-10.0,1%,1/16W,CHIP,G2A]
    1  VSENSE_PVDDQ_GHJ_P      A  @BASEBOARD_FAB2_LIB.BASEBOARD_FAB2(SCH_1):VSENSE_PVDDQ_GHJ_P
    2  VR_PVDDQ_GHJ_AVSP      B  @BASEBOARD_FAB2_LIB.BASEBOARD_FAB2(SCH_1):VR_PVDDQ_GHJ_AVSP

RES  I13  R1G6   [RES_0402-2.26K,1.0%,1/16W,EMPTA]
    2  PU_VR_PVDDQ_GHJ_FAULT1      B  @BASEBOARD_FAB2_LIB.BASEBOARD_FAB2(SCH_1):PU_VR_PVDDQ_GHJ_FAULT1
    1  P3V3_STBY          A  @BASEBOARD_FAB2_LIB.BASEBOARD_FAB2(SCH_1):P3V3_STBY

RES  I53  R1G7   [RES_0402-150.0,1%,1/16W,CHIP,GA]
    2  SVID_CLK_PVDDQ_GHJ      B  @BASEBOARD_FAB2_LIB.BASEBOARD_FAB2(SCH_1):SVID_CLK_PVDDQ_GHJ
    1  SVID_CLK1_CPU1_R      A  @BASEBOARD_FAB2_LIB.BASEBOARD_FAB2(SCH_1):SVID_CLK1_CPU1_R

RES  I82  R1G8   [RES_0402-33.2,1%,1/16W,CHIP,G2A]
    1  IRQ_PVDDQ_GHJ_VRHOT_LVT3_R_N      A  @BASEBOARD_FAB2_LIB.BASEBOARD_FAB2(SCH_1):IRQ_PVDDQ_GHJ_VRHOT_LVT3_R_N
    2  IRQ_PVDDQ_GHJ_VRHOT_LVT3_N      B  @BASEBOARD_FAB2_LIB.BASEBOARD_FAB2(SCH_1):IRQ_PVDDQ_GHJ_VRHOT_LVT3_N

RES  I16  R1G9   [RES_0402-0.0,5%,1/16W,CHIP,G21A]
    1  SVID_ALERT_PVDDQ_GHJ      A  @BASEBOARD_FAB2_LIB.BASEBOARD_FAB2(SCH_1):SVID_ALERT_PVDDQ_GHJ
    2  SVID_ALERT1_CPU1_R_N      B  @BASEBOARD_FAB2_LIB.BASEBOARD_FAB2(SCH_1):SVID_ALERT1_CPU1_R_N

RES  I23  R1G10  [RES_0402-0.0,5%,1/16W,CHIP,G21A]
    1  SVID_VDIO_PVDDQ_GHJ      A  @BASEBOARD_FAB2_LIB.BASEBOARD_FAB2(SCH_1):SVID_VDIO_PVDDQ_GHJ
    2  SVID_DIO1_CPU1_R      B  @BASEBOARD_FAB2_LIB.BASEBOARD_FAB2(SCH_1):SVID_DIO1_CPU1_R

RES  I79  R1G11  [RES_0402-1.00K,1%,1/16W,CHIP,GA]
    1  P3V3_STBY          A  @BASEBOARD_FAB2_LIB.BASEBOARD_FAB2(SCH_1):P3V3_STBY
    2  IRQ_PVDDQ_GHJ_VRHOT_LVT3_R_N      B  @BASEBOARD_FAB2_LIB.BASEBOARD_FAB2(SCH_1):IRQ_PVDDQ_GHJ_VRHOT_LVT3_R_N

RES  I14  R1G12  [RES_0402-22.1,1.0%,1/16W,CHIP,A]
    1  PWRGD_PVDDQ_GHJ_R      A  @BASEBOARD_FAB2_LIB.BASEBOARD_FAB2(SCH_1):PWRGD_PVDDQ_GHJ_R
    2  PWRGD_PVDDQ_GHJ      B  @BASEBOARD_FAB2_LIB.BASEBOARD_FAB2(SCH_1):PWRGD_PVDDQ_GHJ

RES  I41  R1G14  [RES_0402-2,1.0%,1/16W,CHIP,G21A]
    2  M_J_VREF           B  @BASEBOARD_FAB2_LIB.BASEBOARD_FAB2(SCH_1):M_J_VREF
    1  M_J_CPU_VREF       A  @BASEBOARD_FAB2_LIB.BASEBOARD_FAB2(SCH_1):M_J_CPU_VREF

RES  I35  R1G15  [RES_0402-1.00K,1%,1/16W,CHIP,GA]
    1  PVDDQ_GHJ          A  @BASEBOARD_FAB2_LIB.BASEBOARD_FAB2(SCH_1):PVDDQ_GHJ
    2  M_J_VREF           B  @BASEBOARD_FAB2_LIB.BASEBOARD_FAB2(SCH_1):M_J_VREF

RES  I17  R1G16  [RES_0402-1.00K,1%,1/16W,CHIP,GA]
    2  PWRGD_PVDDQ_GHJ_R      B  @BASEBOARD_FAB2_LIB.BASEBOARD_FAB2(SCH_1):PWRGD_PVDDQ_GHJ_R
    1  P3V3_STBY          A  @BASEBOARD_FAB2_LIB.BASEBOARD_FAB2(SCH_1):P3V3_STBY

RES  I36  R1G17  [RES_0402-1.00K,1%,1/16W,CHIP,GA]
    1  M_J_VREF           A  @BASEBOARD_FAB2_LIB.BASEBOARD_FAB2(SCH_1):M_J_VREF
    2  GND                B  @BASEBOARD_FAB2_LIB.BASEBOARD_FAB2(SCH_1):GND

RES  I21  R1G19  [RES_0402-0.0,5%,1/16W,CHIP,G21A]
    2  SMB_VR_STBY_LVC3_SCL      B  @BASEBOARD_FAB2_LIB.BASEBOARD_FAB2(SCH_1):SMB_VR_STBY_LVC3_SCL
    1  SMB_VR_SCL_VDDQ_GHJ      A  @BASEBOARD_FAB2_LIB.BASEBOARD_FAB2(SCH_1):SMB_VR_SCL_VDDQ_GHJ

RES  I58  R1G20  [RES_0603-120.0,1%,1/10W,CHIP,GA]
    1  PVDDQ_GHJ          A  @BASEBOARD_FAB2_LIB.BASEBOARD_FAB2(SCH_1):PVDDQ_GHJ
    2  GND                B  @BASEBOARD_FAB2_LIB.BASEBOARD_FAB2(SCH_1):GND

RES  I22  R1G21  [RES_0402-0.0,5%,1/16W,CHIP,G21A]
    2  SMB_VR_STBY_LVC3_SDA      B  @BASEBOARD_FAB2_LIB.BASEBOARD_FAB2(SCH_1):SMB_VR_STBY_LVC3_SDA
    1  SMB_VR_SDA_VDDQ_GHJ      A  @BASEBOARD_FAB2_LIB.BASEBOARD_FAB2(SCH_1):SMB_VR_SDA_VDDQ_GHJ

RES  I78  R1G22  [RES_0402-5.36K,1.0%,1/16W,CHIPA]
    1  VR_PVDDQ_GHJ_XADDR2      A  @BASEBOARD_FAB2_LIB.BASEBOARD_FAB2(SCH_1):VR_PVDDQ_GHJ_XADDR2
    2  GND                B  @BASEBOARD_FAB2_LIB.BASEBOARD_FAB2(SCH_1):GND

RES  I77  R1G23  [RES_0402-4.02K,1%,1/16W,CHIP,GA]
    1  VR_PVDDQ_GHJ_XADDR1      A  @BASEBOARD_FAB2_LIB.BASEBOARD_FAB2(SCH_1):VR_PVDDQ_GHJ_XADDR1
    2  GND                B  @BASEBOARD_FAB2_LIB.BASEBOARD_FAB2(SCH_1):GND

RES  I58  R1G24  [RES_0402-1.5K,1%,1/16W,CHIP,G2A]
    1  VR_PVDDQ_GHJ_VINSEN      A  @BASEBOARD_FAB2_LIB.BASEBOARD_FAB2(SCH_1):VR_PVDDQ_GHJ_VINSEN
    2  GND                B  @BASEBOARD_FAB2_LIB.BASEBOARD_FAB2(SCH_1):GND

RES  I114  R1G25  [RES_0402-68.1K,1%,1/16W,EMPTY,A]
    1  VR_PVDDQ_GHJ_PH2_OCSET      A  @BASEBOARD_FAB2_LIB.BASEBOARD_FAB2(SCH_1):VR_PVDDQ_GHJ_PH2_OCSET
    2  GND                B  @BASEBOARD_FAB2_LIB.BASEBOARD_FAB2(SCH_1):GND

RES  I112  R1G26  [RES_0402-68.1K,1%,1/16W,EMPTY,A]
    1  VR_PVDDQ_GHJ_PH1_OCSET      A  @BASEBOARD_FAB2_LIB.BASEBOARD_FAB2(SCH_1):VR_PVDDQ_GHJ_PH1_OCSET
    2  GND                B  @BASEBOARD_FAB2_LIB.BASEBOARD_FAB2(SCH_1):GND

RES  I88  R1G27  [RES_0402-0.0,5%,1/16W,CHIP,G21A]
    1  VR_PVDDQ_GHJ_VD12      A  @BASEBOARD_FAB2_LIB.BASEBOARD_FAB2(SCH_1):VR_PVDDQ_GHJ_VD12
    2  VR_PVDDQ_GHJ_AIREF2      B  @BASEBOARD_FAB2_LIB.BASEBOARD_FAB2(SCH_1):VR_PVDDQ_GHJ_AIREF2

RES  I87  R1G28  [RES_0402-0.0,5%,1/16W,CHIP,G21A]
    1  VR_PVDDQ_GHJ_VD12      A  @BASEBOARD_FAB2_LIB.BASEBOARD_FAB2(SCH_1):VR_PVDDQ_GHJ_VD12
    2  VR_PVDDQ_GHJ_AIREF1      B  @BASEBOARD_FAB2_LIB.BASEBOARD_FAB2(SCH_1):VR_PVDDQ_GHJ_AIREF1

RES  I25  R1L1   [RES_0402-2.0K,1%,1/16W,CHIP,G2A]
    2  PU_DATAIN1_SATA_2      B  @BASEBOARD_FAB2_LIB.BASEBOARD_FAB2(SCH_1):PU_DATAIN1_SATA_2
    1  P3V3               A  @BASEBOARD_FAB2_LIB.BASEBOARD_FAB2(SCH_1):P3V3

RES  I186  R1L2   [RES_0402-10.0,1%,1/16W,CHIP,G2A]
    2  FM_CPLD_DBG_PWR_EN_R_N      B  @BASEBOARD_FAB2_LIB.BASEBOARD_FAB2(SCH_1):FM_CPLD_DBG_PWR_EN_R_N
    1  FM_CPLD_DBG_PWR_EN_N      A  @BASEBOARD_FAB2_LIB.BASEBOARD_FAB2(SCH_1):FM_CPLD_DBG_PWR_EN_N

RES  I5   R1L3   [RES_0402-1.00K,1%,1/16W,CHIP,GA]
    1  PD_SATA2_CONTROLLER_TYPE      A  @BASEBOARD_FAB2_LIB.BASEBOARD_FAB2(SCH_1):PD_SATA2_CONTROLLER_TYPE
    2  GND                B  @BASEBOARD_FAB2_LIB.BASEBOARD_FAB2(SCH_1):GND

RES  I7   R1L4   [RES_0402-40.2K,1%,1/16W,CHIP,GA]
    1  FM_UART_SWITCH_N      A  @BASEBOARD_FAB2_LIB.BASEBOARD_FAB2(SCH_1):FM_UART_SWITCH_N
    2  FM_UART_SEL_N      B  @BASEBOARD_FAB2_LIB.BASEBOARD_FAB2(SCH_1):FM_UART_SEL_N

RES  I10  R1L5   [RES_0402-1.00K,1%,1/16W,CHIP,GA]
    1  P3V3_STBY          A  @BASEBOARD_FAB2_LIB.BASEBOARD_FAB2(SCH_1):P3V3_STBY
    2  FM_SOL_UART_CH_SEL      B  @BASEBOARD_FAB2_LIB.BASEBOARD_FAB2(SCH_1):FM_SOL_UART_CH_SEL

RES  I6   R1L6   [RES_0402-0.0,5%,1/16W,CHIP,G21A]
    1  FM_UART_SWITCH_N      A  @BASEBOARD_FAB2_LIB.BASEBOARD_FAB2(SCH_1):FM_UART_SWITCH_N
    2  FM_DB_UART_SEL0_N      B  @BASEBOARD_FAB2_LIB.BASEBOARD_FAB2(SCH_1):FM_DB_UART_SEL0_N

RES  I382  R1L7   [RES_0402-4.75K,1%,1/16W,CHIP,GA]
    1  P3V3_STBY          A  @BASEBOARD_FAB2_LIB.BASEBOARD_FAB2(SCH_1):P3V3_STBY
    2  FM_BMC_CPLD_MP_RST_N      B  @BASEBOARD_FAB2_LIB.BASEBOARD_FAB2(SCH_1):FM_BMC_CPLD_MP_RST_N

RES  I58  R1L8   [RES_0402-470.0,5%,1/16W,CHIP,GA]
    1  P5V_STBY           A  @BASEBOARD_FAB2_LIB.BASEBOARD_FAB2(SCH_1):P5V_STBY
    2  FP_ID_LED_XOR_R      B  @BASEBOARD_FAB2_LIB.BASEBOARD_FAB2(SCH_1):FP_ID_LED_XOR_R

RES  I130  R1L9   [RES_0402-100.0K,1%,1/16W,CHIP,A]
    1  P12V_STBY          A  @BASEBOARD_FAB2_LIB.BASEBOARD_FAB2(SCH_1):P12V_STBY
    2  FM_CPLD_DBG_PWR_EN      B  @BASEBOARD_FAB2_LIB.BASEBOARD_FAB2(SCH_1):FM_CPLD_DBG_PWR_EN

RES  I76  R1L11  [RES_0402-10.0,1%,1/16W,CHIP,G2A]
    2  LED_POSTCODE_7_R      B  @BASEBOARD_FAB2_LIB.BASEBOARD_FAB2(SCH_1):LED_POSTCODE_7_R
    1  LED_POSTCODE_7      A  @BASEBOARD_FAB2_LIB.BASEBOARD_FAB2(SCH_1):LED_POSTCODE_7

RES  I63  R1L12  [RES_0402-0.0,5%,1/16W,CHIP,G21A]
    2  PWRGD_P3V3_R       B  @BASEBOARD_FAB2_LIB.BASEBOARD_FAB2(SCH_1):PWRGD_P3V3_R
    1  PWRGD_P3V3         A  @BASEBOARD_FAB2_LIB.BASEBOARD_FAB2(SCH_1):PWRGD_P3V3

RES  I6   R1L13  [RES_0402-1.00K,1%,1/16W,CHIP,GA]
    1  XDP_SYSPWROK       A  @BASEBOARD_FAB2_LIB.BASEBOARD_FAB2(SCH_1):XDP_SYSPWROK
    2  P3V3_STBY          B  @BASEBOARD_FAB2_LIB.BASEBOARD_FAB2(SCH_1):P3V3_STBY

RES  I75  R1L14  [RES_0402-10.0,1%,1/16W,CHIP,G2A]
    2  LED_POSTCODE_6_R      B  @BASEBOARD_FAB2_LIB.BASEBOARD_FAB2(SCH_1):LED_POSTCODE_6_R
    1  LED_POSTCODE_6      A  @BASEBOARD_FAB2_LIB.BASEBOARD_FAB2(SCH_1):LED_POSTCODE_6

RES  I60  R1L15  [RES_0402-150.0,1%,1/16W,CHIP,GA]
    2  XDP_CPU_TMS        B  @BASEBOARD_FAB2_LIB.BASEBOARD_FAB2(SCH_1):XDP_CPU_TMS
    1  PVCCIO_CPU0        A  @BASEBOARD_FAB2_LIB.BASEBOARD_FAB2(SCH_1):PVCCIO_CPU0

RES  I68  R1L16  [RES_0402-49.9,1%,1/16W,CHIP,G2A]
    1  PWRGD_P3V3_R1      A  @BASEBOARD_FAB2_LIB.BASEBOARD_FAB2(SCH_1):PWRGD_P3V3_R1
    2  PWRGD_P3V3         B  @BASEBOARD_FAB2_LIB.BASEBOARD_FAB2(SCH_1):PWRGD_P3V3

RES  I56  R1L17  [RES_0402-150.0,1%,1/16W,CHIP,GA]
    1  XDP_CPU_PWR_DEBUG_N      A  @BASEBOARD_FAB2_LIB.BASEBOARD_FAB2(SCH_1):XDP_CPU_PWR_DEBUG_N
    2  PVCCIO_CPU0        B  @BASEBOARD_FAB2_LIB.BASEBOARD_FAB2(SCH_1):PVCCIO_CPU0

RES  I74  R1L18  [RES_0402-10.0,1%,1/16W,CHIP,G2A]
    2  LED_POSTCODE_5_R      B  @BASEBOARD_FAB2_LIB.BASEBOARD_FAB2(SCH_1):LED_POSTCODE_5_R
    1  LED_POSTCODE_5      A  @BASEBOARD_FAB2_LIB.BASEBOARD_FAB2(SCH_1):LED_POSTCODE_5

RES  I24  R1L19  [RES_0402-4.75K,1%,1/16W,EMPTY,A]
    1  P3V3_STBY          A  @BASEBOARD_FAB2_LIB.BASEBOARD_FAB2(SCH_1):P3V3_STBY
    2  FM_DEBUG_RST_BTN_N      B  @BASEBOARD_FAB2_LIB.BASEBOARD_FAB2(SCH_1):FM_DEBUG_RST_BTN_N

RES  I73  R1L20  [RES_0402-10.0,1%,1/16W,CHIP,G2A]
    2  LED_POSTCODE_4_R      B  @BASEBOARD_FAB2_LIB.BASEBOARD_FAB2(SCH_1):LED_POSTCODE_4_R
    1  LED_POSTCODE_4      A  @BASEBOARD_FAB2_LIB.BASEBOARD_FAB2(SCH_1):LED_POSTCODE_4

RES  I43  R1L21  [RES_0402-64.9,1.0%,1/16W,CHIP,A]
    1  P3V3               A  @BASEBOARD_FAB2_LIB.BASEBOARD_FAB2(SCH_1):P3V3
    2  FP_LED_HDD_ACTIVITY_AND_R_N      B  @BASEBOARD_FAB2_LIB.BASEBOARD_FAB2(SCH_1):FP_LED_HDD_ACTIVITY_AND_R_N

RES  I22  R1L22  [RES_0402-200.0,1%,1/16W,CHIP,GA]
    2  FP_RST_BTN_R_N      B  @BASEBOARD_FAB2_LIB.BASEBOARD_FAB2(SCH_1):FP_RST_BTN_R_N
    1  FM_DEBUG_RST_BTN_N      A  @BASEBOARD_FAB2_LIB.BASEBOARD_FAB2(SCH_1):FM_DEBUG_RST_BTN_N

RES  I13  R1L23  [RES_0402-1.00K,1%,1/16W,CHIP,GA]
    1  XDP_PWRGD_RST_N      A  @BASEBOARD_FAB2_LIB.BASEBOARD_FAB2(SCH_1):XDP_PWRGD_RST_N
    2  P3V3_STBY          B  @BASEBOARD_FAB2_LIB.BASEBOARD_FAB2(SCH_1):P3V3_STBY

RES  I68  R1L24  [RES_0402-10.0,1%,1/16W,CHIP,G2A]
    2  LED_POSTCODE_3_R      B  @BASEBOARD_FAB2_LIB.BASEBOARD_FAB2(SCH_1):LED_POSTCODE_3_R
    1  LED_POSTCODE_3      A  @BASEBOARD_FAB2_LIB.BASEBOARD_FAB2(SCH_1):LED_POSTCODE_3

RES  I67  R1L25  [RES_0402-10.0,1%,1/16W,CHIP,G2A]
    2  LED_POSTCODE_2_R      B  @BASEBOARD_FAB2_LIB.BASEBOARD_FAB2(SCH_1):LED_POSTCODE_2_R
    1  LED_POSTCODE_2      A  @BASEBOARD_FAB2_LIB.BASEBOARD_FAB2(SCH_1):LED_POSTCODE_2

RES  I13  R1L26  [RES_0402-33.2,1%,1/16W,CHIP,G2A]
    1  FM_PWR_BTN_R_N      A  @BASEBOARD_FAB2_LIB.BASEBOARD_FAB2(SCH_1):FM_PWR_BTN_R_N
    2  FM_PWR_BTN_N       B  @BASEBOARD_FAB2_LIB.BASEBOARD_FAB2(SCH_1):FM_PWR_BTN_N

RES  I5   R1L27  [RES_0402-4.75K,1%,1/16W,CHIP,GA]
    1  P3V3_STBY          A  @BASEBOARD_FAB2_LIB.BASEBOARD_FAB2(SCH_1):P3V3_STBY
    2  FP_PWR_BTN_R_N      B  @BASEBOARD_FAB2_LIB.BASEBOARD_FAB2(SCH_1):FP_PWR_BTN_R_N

RES  I66  R1L28  [RES_0402-4.75K,1%,1/16W,CHIP,GA]
    1  P3V3_STBY          A  @BASEBOARD_FAB2_LIB.BASEBOARD_FAB2(SCH_1):P3V3_STBY
    2  FM_DEBUG_RST_BTN_R1_N      B  @BASEBOARD_FAB2_LIB.BASEBOARD_FAB2(SCH_1):FM_DEBUG_RST_BTN_R1_N

RES  I68  R1L29  [RES_0402-33.2,1%,1/16W,CHIP,G2A]
    1  FM_DEBUG_RST_BTN_R1_N      A  @BASEBOARD_FAB2_LIB.BASEBOARD_FAB2(SCH_1):FM_DEBUG_RST_BTN_R1_N
    2  FM_DEBUG_RST_BTN_N      B  @BASEBOARD_FAB2_LIB.BASEBOARD_FAB2(SCH_1):FM_DEBUG_RST_BTN_N

RES  I66  R1L30  [RES_0402-10.0,1%,1/16W,CHIP,G2A]
    2  LED_POSTCODE_1_R      B  @BASEBOARD_FAB2_LIB.BASEBOARD_FAB2(SCH_1):LED_POSTCODE_1_R
    1  LED_POSTCODE_1      A  @BASEBOARD_FAB2_LIB.BASEBOARD_FAB2(SCH_1):LED_POSTCODE_1

RES  I4   R1L31  [RES_0402-200.0,1%,1/16W,CHIP,GA]
    1  FP_PWR_BTN_R_N      A  @BASEBOARD_FAB2_LIB.BASEBOARD_FAB2(SCH_1):FP_PWR_BTN_R_N
    2  FP_PWR_BTN_R1_N      B  @BASEBOARD_FAB2_LIB.BASEBOARD_FAB2(SCH_1):FP_PWR_BTN_R1_N

RES  I65  R1L32  [RES_0402-10.0,1%,1/16W,CHIP,G2A]
    2  LED_POSTCODE_0_R      B  @BASEBOARD_FAB2_LIB.BASEBOARD_FAB2(SCH_1):LED_POSTCODE_0_R
    1  LED_POSTCODE_0      A  @BASEBOARD_FAB2_LIB.BASEBOARD_FAB2(SCH_1):LED_POSTCODE_0

RES  I45  R1L33  [RES_0402-221,1.0%,1/16W,CHIP,GA]
    2  P3V3_STBY          B  @BASEBOARD_FAB2_LIB.BASEBOARD_FAB2(SCH_1):P3V3_STBY
    1  FM_BEEP_LED_P      A  @BASEBOARD_FAB2_LIB.BASEBOARD_FAB2(SCH_1):FM_BEEP_LED_P

RES  I11  R1L36  [RES_0402-1.00K,1%,1/16W,CHIP,GA]
    1  P3V3_STBY          A  @BASEBOARD_FAB2_LIB.BASEBOARD_FAB2(SCH_1):P3V3_STBY
    2  FM_DB_PRESENT      B  @BASEBOARD_FAB2_LIB.BASEBOARD_FAB2(SCH_1):FM_DB_PRESENT

RES  I33  R1L37  [RES_0402-301.0,1%,1/16W,CHIP,GA]
    1  P5V_STBY           A  @BASEBOARD_FAB2_LIB.BASEBOARD_FAB2(SCH_1):P5V_STBY
    2  LED_P5V_STBY       B  @BASEBOARD_FAB2_LIB.BASEBOARD_FAB2(SCH_1):LED_P5V_STBY

RES  I22  R1L38  [RES_0402-1.00K,1%,1/16W,CHIP,GA]
    1  P3V3_STBY          A  @BASEBOARD_FAB2_LIB.BASEBOARD_FAB2(SCH_1):P3V3_STBY
    2  FM_POST_CARD_PRES_BMC_N      B  @BASEBOARD_FAB2_LIB.BASEBOARD_FAB2(SCH_1):FM_POST_CARD_PRES_BMC_N

RES  I76  R1L39  [RES_0402-100.0,1%,1/16W,CHIP,GA]
    2  XDP_PRDY_N         B  @BASEBOARD_FAB2_LIB.BASEBOARD_FAB2(SCH_1):XDP_PRDY_N
    1  P1V05_PCH_STBY      A  @BASEBOARD_FAB2_LIB.BASEBOARD_FAB2(SCH_1):P1V05_PCH_STBY

RES  I59  R1L40  [RES_0402-0.0,5%,1/16W,CHIP,G21A]
    1  USB3_P01_RXP       A  @BASEBOARD_FAB2_LIB.BASEBOARD_FAB2(SCH_1):USB3_P01_RXP
    2  USB3_P01_FB_RXP      B  @BASEBOARD_FAB2_LIB.BASEBOARD_FAB2(SCH_1):USB3_P01_FB_RXP

RES  I77  R1L41  [RES_0402-100.0,1%,1/16W,CHIP,GA]
    2  XDP_PREQ_N         B  @BASEBOARD_FAB2_LIB.BASEBOARD_FAB2(SCH_1):XDP_PREQ_N
    1  P1V05_PCH_STBY      A  @BASEBOARD_FAB2_LIB.BASEBOARD_FAB2(SCH_1):P1V05_PCH_STBY

RES  I58  R1L42  [RES_0402-0.0,5%,1/16W,CHIP,G21A]
    1  USB3_P01_RXN       A  @BASEBOARD_FAB2_LIB.BASEBOARD_FAB2(SCH_1):USB3_P01_RXN
    2  USB3_P01_FB_RXN      B  @BASEBOARD_FAB2_LIB.BASEBOARD_FAB2(SCH_1):USB3_P01_FB_RXN

RES  I131  R1L43  [RES_0402-330,5%,1/16W,CHIP,G21A]
    2  P3V3_STBY          B  @BASEBOARD_FAB2_LIB.BASEBOARD_FAB2(SCH_1):P3V3_STBY
    1  FM_UARTSW_LSB_R_N      A  @BASEBOARD_FAB2_LIB.BASEBOARD_FAB2(SCH_1):FM_UARTSW_LSB_R_N

RES  I136  R1L44  [RES_0402-330,5%,1/16W,CHIP,G21A]
    2  P3V3_STBY          B  @BASEBOARD_FAB2_LIB.BASEBOARD_FAB2(SCH_1):P3V3_STBY
    1  FM_UARTSW_MSB_R_N      A  @BASEBOARD_FAB2_LIB.BASEBOARD_FAB2(SCH_1):FM_UARTSW_MSB_R_N

RES  I61  R1M1   [RES_0402-0.0,5%,1/16W,CHIP,G21A]
    2  USB3_P01_FB_TXP      B  @BASEBOARD_FAB2_LIB.BASEBOARD_FAB2(SCH_1):USB3_P01_FB_TXP
    1  USB3_P01_C_TXP      A  @BASEBOARD_FAB2_LIB.BASEBOARD_FAB2(SCH_1):USB3_P01_C_TXP

RES  I60  R1M2   [RES_0402-0.0,5%,1/16W,CHIP,G21A]
    2  USB3_P01_FB_TXN      B  @BASEBOARD_FAB2_LIB.BASEBOARD_FAB2(SCH_1):USB3_P01_FB_TXN
    1  USB3_P01_C_TXN      A  @BASEBOARD_FAB2_LIB.BASEBOARD_FAB2(SCH_1):USB3_P01_C_TXN

RES  I51  R1M3   [RES_0402-100.0,1%,1/16W,CHIP,GA]
    2  XDP_CPU_PRDY_N      B  @BASEBOARD_FAB2_LIB.BASEBOARD_FAB2(SCH_1):XDP_CPU_PRDY_N
    1  PVCCIO_CPU0        A  @BASEBOARD_FAB2_LIB.BASEBOARD_FAB2(SCH_1):PVCCIO_CPU0

RES  I54  R1M4   [RES_0402-100.0,1%,1/16W,CHIP,GA]
    2  XDP_CPU_PREQ_N      B  @BASEBOARD_FAB2_LIB.BASEBOARD_FAB2(SCH_1):XDP_CPU_PREQ_N
    1  PVCCIO_CPU0        A  @BASEBOARD_FAB2_LIB.BASEBOARD_FAB2(SCH_1):PVCCIO_CPU0

RES  I16  R1M5   [RES_0402-0.0,5%,1/16W,CHIP,G21A]
    2  USB2_P01_ESD_DP      B  @BASEBOARD_FAB2_LIB.BASEBOARD_FAB2(SCH_1):USB2_P01_ESD_DP
    1  USB2_P01_DP        A  @BASEBOARD_FAB2_LIB.BASEBOARD_FAB2(SCH_1):USB2_P01_DP

RES  I31  R1M6   [RES_0402-0.0,5%,1/16W,CHIP,G21A]
    2  USB2_P01_ESD_DN      B  @BASEBOARD_FAB2_LIB.BASEBOARD_FAB2(SCH_1):USB2_P01_ESD_DN
    1  USB2_P01_DN        A  @BASEBOARD_FAB2_LIB.BASEBOARD_FAB2(SCH_1):USB2_P01_DN

RES  I74  R1M8   [RES_0402-20.0,1%,1/16W,CHIP,G2A]
    1  SMB_SENSOR_TMP421_1_SCL      A  @BASEBOARD_FAB2_LIB.BASEBOARD_FAB2(SCH_1):SMB_SENSOR_TMP421_1_SCL
    2  SMB_SENSOR_STBY_LVC3_SCL      B  @BASEBOARD_FAB2_LIB.BASEBOARD_FAB2(SCH_1):SMB_SENSOR_STBY_LVC3_SCL

RES  I8   R1M9   [RES_0402-20.0,1%,1/16W,CHIP,G2A]
    1  SMB_SENSOR_TMP421_1_SDA      A  @BASEBOARD_FAB2_LIB.BASEBOARD_FAB2(SCH_1):SMB_SENSOR_TMP421_1_SDA
    2  SMB_SENSOR_STBY_LVC3_SDA      B  @BASEBOARD_FAB2_LIB.BASEBOARD_FAB2(SCH_1):SMB_SENSOR_STBY_LVC3_SDA

RES  I6   R1M10  [RES_0402-0.0,5%,1/16W,CHIP,G21A]
    2  LED_SATA_ACT_R_N      B  @BASEBOARD_FAB2_LIB.BASEBOARD_FAB2(SCH_1):LED_SATA_ACT_R_N
    1  LED_PCH_SATA_HDD_N      A  @BASEBOARD_FAB2_LIB.BASEBOARD_FAB2(SCH_1):LED_PCH_SATA_HDD_N

RES  I9   R1M11  [RES_0402-10.0K,1%,1/16W,CHIP,GA]
    1  P3V3               A  @BASEBOARD_FAB2_LIB.BASEBOARD_FAB2(SCH_1):P3V3
    2  LED_SATA_ACT_R_N      B  @BASEBOARD_FAB2_LIB.BASEBOARD_FAB2(SCH_1):LED_SATA_ACT_R_N

RES  I8   R1M12  [RES_0402-10.0K,1%,1/16W,CHIP,GA]
    1  P3V3               A  @BASEBOARD_FAB2_LIB.BASEBOARD_FAB2(SCH_1):P3V3
    2  LED_SAS_ACT_R_N      B  @BASEBOARD_FAB2_LIB.BASEBOARD_FAB2(SCH_1):LED_SAS_ACT_R_N

RES  I3   R1M13  [RES_0402-0.0,5%,1/16W,CHIP,G21A]
    2  LED_SAS_ACT_R_N      B  @BASEBOARD_FAB2_LIB.BASEBOARD_FAB2(SCH_1):LED_SAS_ACT_R_N
    1  LED_PCH_SSATA_HDD_N      A  @BASEBOARD_FAB2_LIB.BASEBOARD_FAB2(SCH_1):LED_PCH_SSATA_HDD_N

RES  I220  R1M14  [RES_0402-200.0,1%,1/16W,CHIP,GA]
    2  RST_PCIE_CPU_DEV0_R_N      B  @BASEBOARD_FAB2_LIB.BASEBOARD_FAB2(SCH_1):RST_PCIE_CPU_DEV0_R_N
    1  RST_PCIE_CPU_DEV0_N      A  @BASEBOARD_FAB2_LIB.BASEBOARD_FAB2(SCH_1):RST_PCIE_CPU_DEV0_N

RES  I339  R1M15  [RES_0402-0.0,5%,1/16W,CHIP,G21A]
    2  RMII_BMC_OCP_CRSDV_R      B  @BASEBOARD_FAB2_LIB.BASEBOARD_FAB2(SCH_1):RMII_BMC_OCP_CRSDV_R
    1  RMII_BMC_OCP_CRSDV      A  @BASEBOARD_FAB2_LIB.BASEBOARD_FAB2(SCH_1):RMII_BMC_OCP_CRSDV

RES  I337  R1M16  [RES_0402-0.0,5%,1/16W,CHIP,G21A]
    2  RMII_BMC_OCP_RXD1_R      B  @BASEBOARD_FAB2_LIB.BASEBOARD_FAB2(SCH_1):RMII_BMC_OCP_RXD1_R
    1  RMII_BMC_OCP_RXD1      A  @BASEBOARD_FAB2_LIB.BASEBOARD_FAB2(SCH_1):RMII_BMC_OCP_RXD1

RES  I338  R1M17  [RES_0402-0.0,5%,1/16W,CHIP,G21A]
    2  RMII_BMC_OCP_RXD0_R      B  @BASEBOARD_FAB2_LIB.BASEBOARD_FAB2(SCH_1):RMII_BMC_OCP_RXD0_R
    1  RMII_BMC_OCP_RXD0      A  @BASEBOARD_FAB2_LIB.BASEBOARD_FAB2(SCH_1):RMII_BMC_OCP_RXD0

RES  I340  R1M18  [RES_0402-0.0,5%,1/16W,CHIP,G21A]
    1  RMII_BMC_OCP_RXER_R      A  @BASEBOARD_FAB2_LIB.BASEBOARD_FAB2(SCH_1):RMII_BMC_OCP_RXER_R
    2  RMII_BMC_OCP_RXER      B  @BASEBOARD_FAB2_LIB.BASEBOARD_FAB2(SCH_1):RMII_BMC_OCP_RXER

RES  I202  R1M19  [RES_0402-1.00K,1%,1/16W,CHIP,GA]
    1  P1V8_MCP_CPU0      A  @BASEBOARD_FAB2_LIB.BASEBOARD_FAB2(SCH_1):P1V8_MCP_CPU0
    2  JTAG_MCP_TMS       B  @BASEBOARD_FAB2_LIB.BASEBOARD_FAB2(SCH_1):JTAG_MCP_TMS

RES  I204  R1M20  [RES_0402-1.00K,1%,1/16W,CHIP,GA]
    1  P1V8_MCP_CPU0      A  @BASEBOARD_FAB2_LIB.BASEBOARD_FAB2(SCH_1):P1V8_MCP_CPU0
    2  JTAG_MCP_MUX_TDI      B  @BASEBOARD_FAB2_LIB.BASEBOARD_FAB2(SCH_1):JTAG_MCP_MUX_TDI

RES  I205  R1M21  [RES_0402-1.00K,1%,1/16W,CHIP,GA]
    1  P1V8_MCP_CPU0      A  @BASEBOARD_FAB2_LIB.BASEBOARD_FAB2(SCH_1):P1V8_MCP_CPU0
    2  JTAG_MCP_TRST_N      B  @BASEBOARD_FAB2_LIB.BASEBOARD_FAB2(SCH_1):JTAG_MCP_TRST_N

RES  I195  R1M22  [RES_0402-49.9,1%,1/16W,CHIP,G2A]
    1  JTAG_MCP_TMS_R1      A  @BASEBOARD_FAB2_LIB.BASEBOARD_FAB2(SCH_1):JTAG_MCP_TMS_R1
    2  JTAG_MCP_TMS       B  @BASEBOARD_FAB2_LIB.BASEBOARD_FAB2(SCH_1):JTAG_MCP_TMS

RES  I199  R1M23  [RES_0402-1.00K,1%,1/16W,EMPTY,A]
    1  JTAG_MCP_TRST_N      A  @BASEBOARD_FAB2_LIB.BASEBOARD_FAB2(SCH_1):JTAG_MCP_TRST_N
    2  GND                B  @BASEBOARD_FAB2_LIB.BASEBOARD_FAB2(SCH_1):GND

RES  I105  R1M24  [RES_0402-10.0K,1%,1/16W,CHIP,GA]
    1  P3V3_STBY          A  @BASEBOARD_FAB2_LIB.BASEBOARD_FAB2(SCH_1):P3V3_STBY
    2  FM_OC0_USB_N       B  @BASEBOARD_FAB2_LIB.BASEBOARD_FAB2(SCH_1):FM_OC0_USB_N

RES  I111  R1M25  [RES_0402-10.0K,1%,1/16W,CHIP,GA]
    2  GND                B  @BASEBOARD_FAB2_LIB.BASEBOARD_FAB2(SCH_1):GND
    1  FM_USB_P0_EN_BOOT_BIOS_STRAP_N      A  @BASEBOARD_FAB2_LIB.BASEBOARD_FAB2(SCH_1):FM_USB_P0_EN_BOOT_BIOS_STRAP_N

RES  I195  R1R1   [RES_0402-0.0,5%,1/16W,CHIP,G21A]
    2  RST_PLTRST_SPRV_R_N      B  @BASEBOARD_FAB2_LIB.BASEBOARD_FAB2(SCH_1):RST_PLTRST_SPRV_R_N
    1  RST_PLTRST_N       A  @BASEBOARD_FAB2_LIB.BASEBOARD_FAB2(SCH_1):RST_PLTRST_N

RES  I11  R1R3   [RES_0402-3.32K,1%,1/16W,CHIP,GA]
    2  PU_NV_WP_N         B  @BASEBOARD_FAB2_LIB.BASEBOARD_FAB2(SCH_1):PU_NV_WP_N
    1  P3V3_STBY          A  @BASEBOARD_FAB2_LIB.BASEBOARD_FAB2(SCH_1):P3V3_STBY

RES  I119  R1R4   [RES_0402-10.0K,1%,1/16W,CHIP,GA]
    2  RMII_BMC_PCH_SPRNGVLLE_TXD0      B  @BASEBOARD_FAB2_LIB.BASEBOARD_FAB2(SCH_1):RMII_BMC_PCH_SPRNGVLLE_TXD0
    1  P3V3_STBY          A  @BASEBOARD_FAB2_LIB.BASEBOARD_FAB2(SCH_1):P3V3_STBY

RES  I73  R1R5   [RES_0402-4.75K,1%,1/16W,CHIP,GA]
    1  P3V3_STBY          A  @BASEBOARD_FAB2_LIB.BASEBOARD_FAB2(SCH_1):P3V3_STBY
    2  FM_FAST_PROCHOT_THROTTLE_DLY_BU      B  @BASEBOARD_FAB2_LIB.BASEBOARD_FAB2(SCH_1):FM_FAST_PROCHOT_THROTTLE_DLY_BUF_N

RES  I14  R1R6   [RES_0402-3.32K,1%,1/16W,EMPTY,A]
    1  SPI_NIC_MOSI       A  @BASEBOARD_FAB2_LIB.BASEBOARD_FAB2(SCH_1):SPI_NIC_MOSI
    2  GND                B  @BASEBOARD_FAB2_LIB.BASEBOARD_FAB2(SCH_1):GND

RES  I12  R1R7   [RES_0402-20.0K,1%,1/16W,CHIP,GA]
    2  SPI_NIC_MOSI       B  @BASEBOARD_FAB2_LIB.BASEBOARD_FAB2(SCH_1):SPI_NIC_MOSI
    1  P3V3_STBY          A  @BASEBOARD_FAB2_LIB.BASEBOARD_FAB2(SCH_1):P3V3_STBY

RES  I51  R1R8   [RES_0402-0.0,5%,1/16W,CHIP,G21A]
    1  FM_THROTTLE_R1_N      A  @BASEBOARD_FAB2_LIB.BASEBOARD_FAB2(SCH_1):FM_THROTTLE_R1_N
    2  FM_THROTTLE_N      B  @BASEBOARD_FAB2_LIB.BASEBOARD_FAB2(SCH_1):FM_THROTTLE_N

RES  I10  R1R9   [RES_0402-3.32K,1%,1/16W,CHIP,GA]
    2  PU_NV_HOLD_N       B  @BASEBOARD_FAB2_LIB.BASEBOARD_FAB2(SCH_1):PU_NV_HOLD_N
    1  P3V3_STBY          A  @BASEBOARD_FAB2_LIB.BASEBOARD_FAB2(SCH_1):P3V3_STBY

RES  I108  R1R10  [RES_0402-10.0K,1%,1/16W,CHIP,GA]
    2  RMII_SPRNGVLLE_BMC_PCH_RXD0      B  @BASEBOARD_FAB2_LIB.BASEBOARD_FAB2(SCH_1):RMII_SPRNGVLLE_BMC_PCH_RXD0
    1  P3V3_STBY          A  @BASEBOARD_FAB2_LIB.BASEBOARD_FAB2(SCH_1):P3V3_STBY

RES  I66  R1R11  [RES_0402-4.75K,1%,1/16W,CHIP,GA]
    2  P3V3_STBY          B  @BASEBOARD_FAB2_LIB.BASEBOARD_FAB2(SCH_1):P3V3_STBY
    1  FM_BMC_DISABLE      A  @BASEBOARD_FAB2_LIB.BASEBOARD_FAB2(SCH_1):FM_BMC_DISABLE

RES  I213  R1R12  [RES_0402-10.0K,1%,1/16W,CHIP,GA]
    2  GND                B  @BASEBOARD_FAB2_LIB.BASEBOARD_FAB2(SCH_1):GND
    1  CLK_50M_CKMNG_SPRVLLE      A  @BASEBOARD_FAB2_LIB.BASEBOARD_FAB2(SCH_1):CLK_50M_CKMNG_SPRVLLE

RES  I109  R1R13  [RES_0402-10.0K,1%,1/16W,CHIP,GA]
    2  RMII_SPRNGVLLE_BMC_PCH_RXD1      B  @BASEBOARD_FAB2_LIB.BASEBOARD_FAB2(SCH_1):RMII_SPRNGVLLE_BMC_PCH_RXD1
    1  P3V3_STBY          A  @BASEBOARD_FAB2_LIB.BASEBOARD_FAB2(SCH_1):P3V3_STBY

RES  I237  R1R15  [RES_0603-0,5.0%,1/10W,CHIP,G22A]
    2  P0V9_LAN_I210      B  @BASEBOARD_FAB2_LIB.BASEBOARD_FAB2(SCH_1):P0V9_LAN_I210
    1  P0V9_LAN           A  @BASEBOARD_FAB2_LIB.BASEBOARD_FAB2(SCH_1):P0V9_LAN

RES  I93  R1R16  [RES_0402-2.21K,1%,1/16W,CHIP,GA]
    2  SMB_PCH_MEZZ_LOM2_SCL      B  @BASEBOARD_FAB2_LIB.BASEBOARD_FAB2(SCH_1):SMB_PCH_MEZZ_LOM2_SCL
    1  P3V3_STBY          A  @BASEBOARD_FAB2_LIB.BASEBOARD_FAB2(SCH_1):P3V3_STBY

RES  I94  R1R17  [RES_0402-2.21K,1%,1/16W,CHIP,GA]
    2  SMB_PCH_MEZZ_LOM2_SDA      B  @BASEBOARD_FAB2_LIB.BASEBOARD_FAB2(SCH_1):SMB_PCH_MEZZ_LOM2_SDA
    1  P3V3_STBY          A  @BASEBOARD_FAB2_LIB.BASEBOARD_FAB2(SCH_1):P3V3_STBY

RES  I88  R1R18  [RES_0402-2.21K,1%,1/16W,CHIP,GA]
    2  SMB_PCH_MEZZ_LOM0_SCL      B  @BASEBOARD_FAB2_LIB.BASEBOARD_FAB2(SCH_1):SMB_PCH_MEZZ_LOM0_SCL
    1  P3V3_STBY          A  @BASEBOARD_FAB2_LIB.BASEBOARD_FAB2(SCH_1):P3V3_STBY

RES  I89  R1R19  [RES_0402-2.21K,1%,1/16W,CHIP,GA]
    2  SMB_PCH_MEZZ_LOM0_SDA      B  @BASEBOARD_FAB2_LIB.BASEBOARD_FAB2(SCH_1):SMB_PCH_MEZZ_LOM0_SDA
    1  P3V3_STBY          A  @BASEBOARD_FAB2_LIB.BASEBOARD_FAB2(SCH_1):P3V3_STBY

RES  I91  R1R20  [RES_0402-2.21K,1%,1/16W,CHIP,GA]
    2  SMB_PCH_MEZZ_LOM1_SCL      B  @BASEBOARD_FAB2_LIB.BASEBOARD_FAB2(SCH_1):SMB_PCH_MEZZ_LOM1_SCL
    1  P3V3_STBY          A  @BASEBOARD_FAB2_LIB.BASEBOARD_FAB2(SCH_1):P3V3_STBY

RES  I90  R1R21  [RES_0402-2.21K,1%,1/16W,CHIP,GA]
    2  SMB_PCH_MEZZ_LOM1_SDA      B  @BASEBOARD_FAB2_LIB.BASEBOARD_FAB2(SCH_1):SMB_PCH_MEZZ_LOM1_SDA
    1  P3V3_STBY          A  @BASEBOARD_FAB2_LIB.BASEBOARD_FAB2(SCH_1):P3V3_STBY

RES  I92  R1R22  [RES_0402-2.21K,1%,1/16W,CHIP,GA]
    2  SMB_PCH_MEZZ_LOM3_SDA      B  @BASEBOARD_FAB2_LIB.BASEBOARD_FAB2(SCH_1):SMB_PCH_MEZZ_LOM3_SDA
    1  P3V3_STBY          A  @BASEBOARD_FAB2_LIB.BASEBOARD_FAB2(SCH_1):P3V3_STBY

RES  I95  R1R23  [RES_0402-2.21K,1%,1/16W,CHIP,GA]
    2  SMB_PCH_MEZZ_LOM3_SCL      B  @BASEBOARD_FAB2_LIB.BASEBOARD_FAB2(SCH_1):SMB_PCH_MEZZ_LOM3_SCL
    1  P3V3_STBY          A  @BASEBOARD_FAB2_LIB.BASEBOARD_FAB2(SCH_1):P3V3_STBY

RES  I214  R1T1   [RES_0402-10.0K,1%,1/16W,CHIP,GA]
    1  RMII_BMC_PCH_SPRNGVLLE_CRSDV      A  @BASEBOARD_FAB2_LIB.BASEBOARD_FAB2(SCH_1):RMII_BMC_PCH_SPRNGVLLE_CRSDV
    2  GND                B  @BASEBOARD_FAB2_LIB.BASEBOARD_FAB2(SCH_1):GND

RES  I49  R1T2   [RES_0402-665,1.0%,1/16W,CHIP,GA]
    2  SMB_SLOTX24_STBY_LVC3_SCL_R      B  @BASEBOARD_FAB2_LIB.BASEBOARD_FAB2(SCH_1):SMB_SLOTX24_STBY_LVC3_SCL_R
    1  P3V3_STBY          A  @BASEBOARD_FAB2_LIB.BASEBOARD_FAB2(SCH_1):P3V3_STBY

RES  I46  R1T3   [RES_0402-665,1.0%,1/16W,CHIP,GA]
    2  SMB_SLOTX24_STBY_LVC3_SDA_R      B  @BASEBOARD_FAB2_LIB.BASEBOARD_FAB2(SCH_1):SMB_SLOTX24_STBY_LVC3_SDA_R
    1  P3V3_STBY          A  @BASEBOARD_FAB2_LIB.BASEBOARD_FAB2(SCH_1):P3V3_STBY

RES  I14  R1T4   [RES_0402-2.7K,1%,1/16W,CHIP,G2A]
    1  P3V3_STBY          A  @BASEBOARD_FAB2_LIB.BASEBOARD_FAB2(SCH_1):P3V3_STBY
    2  FM_BOARD_REV_ID0      B  @BASEBOARD_FAB2_LIB.BASEBOARD_FAB2(SCH_1):FM_BOARD_REV_ID0

RES  I11  R1T5   [RES_0402-2.7K,1%,1/16W,EMPTY,GA]
    1  P3V3_STBY          A  @BASEBOARD_FAB2_LIB.BASEBOARD_FAB2(SCH_1):P3V3_STBY
    2  FM_BOARD_REV_ID2      B  @BASEBOARD_FAB2_LIB.BASEBOARD_FAB2(SCH_1):FM_BOARD_REV_ID2

RES  I13  R1T6   [RES_0402-2.7K,1%,1/16W,EMPTY,GA]
    1  P3V3_STBY          A  @BASEBOARD_FAB2_LIB.BASEBOARD_FAB2(SCH_1):P3V3_STBY
    2  FM_BOARD_REV_ID1      B  @BASEBOARD_FAB2_LIB.BASEBOARD_FAB2(SCH_1):FM_BOARD_REV_ID1

RES  I50  R1T7   [RES_0402-20.0,1%,1/16W,CHIP,G2A]
    1  SMB_SLOTX24_STBY_LVC3_SCL_R      A  @BASEBOARD_FAB2_LIB.BASEBOARD_FAB2(SCH_1):SMB_SLOTX24_STBY_LVC3_SCL_R
    2  SMB_SLOTX24_BMC_STBY_LVC3_SCL      B  @BASEBOARD_FAB2_LIB.BASEBOARD_FAB2(SCH_1):SMB_SLOTX24_BMC_STBY_LVC3_SCL

RES  I4   R1T8   [RES_0402-20.0,1%,1/16W,CHIP,G2A]
    1  SMB_SLOTX24_STBY_LVC3_SDA_R      A  @BASEBOARD_FAB2_LIB.BASEBOARD_FAB2(SCH_1):SMB_SLOTX24_STBY_LVC3_SDA_R
    2  SMB_SLOTX24_BMC_STBY_LVC3_SDA      B  @BASEBOARD_FAB2_LIB.BASEBOARD_FAB2(SCH_1):SMB_SLOTX24_BMC_STBY_LVC3_SDA

RES  I72  R1T9   [RES_0402-22.1,1.0%,1/16W,CHIP,A]
    1  PWRGD_P1V538_BMC_STBY_R      A  @BASEBOARD_FAB2_LIB.BASEBOARD_FAB2(SCH_1):PWRGD_P1V538_BMC_STBY_R
    2  PWRGD_P1V538_BMC_STBY      B  @BASEBOARD_FAB2_LIB.BASEBOARD_FAB2(SCH_1):PWRGD_P1V538_BMC_STBY

RES  I5   R1T10  [RES_0402-1.00K,1%,1/16W,EMPTY,A]
    2  GND                B  @BASEBOARD_FAB2_LIB.BASEBOARD_FAB2(SCH_1):GND
    1  FM_BOARD_REV_ID0      A  @BASEBOARD_FAB2_LIB.BASEBOARD_FAB2(SCH_1):FM_BOARD_REV_ID0

RES  I7   R1T11  [RES_0402-1.00K,1%,1/16W,CHIP,GA]
    2  GND                B  @BASEBOARD_FAB2_LIB.BASEBOARD_FAB2(SCH_1):GND
    1  FM_BOARD_REV_ID2      A  @BASEBOARD_FAB2_LIB.BASEBOARD_FAB2(SCH_1):FM_BOARD_REV_ID2

RES  I6   R1T12  [RES_0402-1.00K,1%,1/16W,CHIP,GA]
    2  GND                B  @BASEBOARD_FAB2_LIB.BASEBOARD_FAB2(SCH_1):GND
    1  FM_BOARD_REV_ID1      A  @BASEBOARD_FAB2_LIB.BASEBOARD_FAB2(SCH_1):FM_BOARD_REV_ID1

RES  I43  R1T13  [RES_0402-4.75K,1%,1/16W,EMPTY,A]
    2  P3V3_STBY          B  @BASEBOARD_FAB2_LIB.BASEBOARD_FAB2(SCH_1):P3V3_STBY
    1  FM_ROMA<23>        A  @BASEBOARD_FAB2_LIB.BASEBOARD_FAB2(SCH_1):FM_ROMA<23>

RES  I54  R1T14  [RES_0402-4.75K,1%,1/16W,CHIP,GA]
    2  P3V3_STBY          B  @BASEBOARD_FAB2_LIB.BASEBOARD_FAB2(SCH_1):P3V3_STBY
    1  FM_ROMA<12>        A  @BASEBOARD_FAB2_LIB.BASEBOARD_FAB2(SCH_1):FM_ROMA<12>

RES  I183  R1T15  [RES_0402-0.0,5%,1/16W,EMPTY,G2A]
    2  FM_BMC_ONCTL_R_N      B  @BASEBOARD_FAB2_LIB.BASEBOARD_FAB2(SCH_1):FM_BMC_ONCTL_R_N
    1  FM_BMC_ONCTL_N      A  @BASEBOARD_FAB2_LIB.BASEBOARD_FAB2(SCH_1):FM_BMC_ONCTL_N

RES  I61  R1T16  [RES_0402-4.75K,1%,1/16W,EMPTY,A]
    2  P3V3_STBY          B  @BASEBOARD_FAB2_LIB.BASEBOARD_FAB2(SCH_1):P3V3_STBY
    1  FM_ROMA<5>         A  @BASEBOARD_FAB2_LIB.BASEBOARD_FAB2(SCH_1):FM_ROMA<5>

RES  I112  R1T17  [RES_0402-4.75K,1%,1/16W,EMPTY,A]
    2  P3V3_STBY          B  @BASEBOARD_FAB2_LIB.BASEBOARD_FAB2(SCH_1):P3V3_STBY
    1  FM_ROMA<21>        A  @BASEBOARD_FAB2_LIB.BASEBOARD_FAB2(SCH_1):FM_ROMA<21>

RES  I48  R1T18  [RES_0402-4.75K,1%,1/16W,EMPTY,A]
    2  P3V3_STBY          B  @BASEBOARD_FAB2_LIB.BASEBOARD_FAB2(SCH_1):P3V3_STBY
    1  FM_ROMA<18>        A  @BASEBOARD_FAB2_LIB.BASEBOARD_FAB2(SCH_1):FM_ROMA<18>

RES  I57  R1T19  [RES_0402-4.75K,1%,1/16W,EMPTY,A]
    2  P3V3_STBY          B  @BASEBOARD_FAB2_LIB.BASEBOARD_FAB2(SCH_1):P3V3_STBY
    1  FM_ROMA<9>         A  @BASEBOARD_FAB2_LIB.BASEBOARD_FAB2(SCH_1):FM_ROMA<9>

RES  I49  R1T20  [RES_0402-4.75K,1%,1/16W,EMPTY,A]
    2  P3V3_STBY          B  @BASEBOARD_FAB2_LIB.BASEBOARD_FAB2(SCH_1):P3V3_STBY
    1  FM_ROMA<17>        A  @BASEBOARD_FAB2_LIB.BASEBOARD_FAB2(SCH_1):FM_ROMA<17>

RES  I53  R1T21  [RES_0402-4.75K,1%,1/16W,EMPTY,A]
    2  P3V3_STBY          B  @BASEBOARD_FAB2_LIB.BASEBOARD_FAB2(SCH_1):P3V3_STBY
    1  FM_ROMA<13>        A  @BASEBOARD_FAB2_LIB.BASEBOARD_FAB2(SCH_1):FM_ROMA<13>

RES  I50  R1T22  [RES_0402-4.75K,1%,1/16W,EMPTY,A]
    2  P3V3_STBY          B  @BASEBOARD_FAB2_LIB.BASEBOARD_FAB2(SCH_1):P3V3_STBY
    1  FM_ROMA<16>        A  @BASEBOARD_FAB2_LIB.BASEBOARD_FAB2(SCH_1):FM_ROMA<16>

RES  I184  R1T23  [RES_0402-0.0,5%,1/16W,EMPTY,G2A]
    2  GND                B  @BASEBOARD_FAB2_LIB.BASEBOARD_FAB2(SCH_1):GND
    1  FM_BMC_ONCTL_R_N      A  @BASEBOARD_FAB2_LIB.BASEBOARD_FAB2(SCH_1):FM_BMC_ONCTL_R_N

RES  I127  R1T24  [RES_0402-0.0,5%,1/16W,EMPTY,G2A]
    1  FM_FLASH_DESC_OVERRIDE_R      A  @BASEBOARD_FAB2_LIB.BASEBOARD_FAB2(SCH_1):FM_FLASH_DESC_OVERRIDE_R
    2  FM_FLASH_DESC_OVERRIDE      B  @BASEBOARD_FAB2_LIB.BASEBOARD_FAB2(SCH_1):FM_FLASH_DESC_OVERRIDE

RES  I461  R1T25  [RES_0402-8.2K,1%,1/16W,CHIP,G2A]
    2  GND                B  @BASEBOARD_FAB2_LIB.BASEBOARD_FAB2(SCH_1):GND
    1  A_USB2VRES         A  @BASEBOARD_FAB2_LIB.BASEBOARD_FAB2(SCH_1):A_USB2VRES

RES  I35  R1T26  [RES_0402-22.1,1.0%,1/16W,CHIP,A]
    2  SPI_BMC_BT_CS_R_N      B  @BASEBOARD_FAB2_LIB.BASEBOARD_FAB2(SCH_1):SPI_BMC_BT_CS_R_N
    1  SPI_BMC_BT_CS_N      A  @BASEBOARD_FAB2_LIB.BASEBOARD_FAB2(SCH_1):SPI_BMC_BT_CS_N

RES  I32  R1T27  [RES_0402-240,1.0%,1/16W,CHIP,GA]
    2  GND                B  @BASEBOARD_FAB2_LIB.BASEBOARD_FAB2(SCH_1):GND
    1  A_M_BMC_ZQ         A  @BASEBOARD_FAB2_LIB.BASEBOARD_FAB2(SCH_1):A_M_BMC_ZQ

RES  I121  R1T28  [RES_0402-22.1,1.0%,1/16W,CHIP,A]
    1  RMII_BMC_PCH_SPRNGVLLE_TXD0_R      A  @BASEBOARD_FAB2_LIB.BASEBOARD_FAB2(SCH_1):RMII_BMC_PCH_SPRNGVLLE_TXD0_R
    2  RMII_BMC_PCH_SPRNGVLLE_TXD0      B  @BASEBOARD_FAB2_LIB.BASEBOARD_FAB2(SCH_1):RMII_BMC_PCH_SPRNGVLLE_TXD0

RES  I61  R1T29  [RES_0402-1.00K,1%,1/16W,CHIP,GA]
    1  M_BMC_DDR3_MVREF      A  @BASEBOARD_FAB2_LIB.BASEBOARD_FAB2(SCH_1):M_BMC_DDR3_MVREF
    2  GND                B  @BASEBOARD_FAB2_LIB.BASEBOARD_FAB2(SCH_1):GND

RES  I60  R1T30  [RES_0402-1.00K,1%,1/16W,CHIP,GA]
    1  P1V538_BMC_STBY      A  @BASEBOARD_FAB2_LIB.BASEBOARD_FAB2(SCH_1):P1V538_BMC_STBY
    2  M_BMC_DDR3_MVREF      B  @BASEBOARD_FAB2_LIB.BASEBOARD_FAB2(SCH_1):M_BMC_DDR3_MVREF

RES  I238  R1T32  [RES_0603-0,5.0%,1/10W,CHIP,G22A]
    2  P1V5_LAN_I210      B  @BASEBOARD_FAB2_LIB.BASEBOARD_FAB2(SCH_1):P1V5_LAN_I210
    1  P1V5_LAN           A  @BASEBOARD_FAB2_LIB.BASEBOARD_FAB2(SCH_1):P1V5_LAN

RES  I240  R1T33  [RES_0603-0,5.0%,1/10W,EMPTY,G2A]
    2  P3V3_STBY_P1V5_LAN_I210      B  @BASEBOARD_FAB2_LIB.BASEBOARD_FAB2(SCH_1):P3V3_STBY_P1V5_LAN_I210
    1  P1V5_LAN           A  @BASEBOARD_FAB2_LIB.BASEBOARD_FAB2(SCH_1):P1V5_LAN

RES  I239  R1T34  [RES_0603-0,5.0%,1/10W,CHIP,G22A]
    2  P3V3_STBY_P1V5_LAN_I210      B  @BASEBOARD_FAB2_LIB.BASEBOARD_FAB2(SCH_1):P3V3_STBY_P1V5_LAN_I210
    1  P3V3_STBY          A  @BASEBOARD_FAB2_LIB.BASEBOARD_FAB2(SCH_1):P3V3_STBY

RES  I135  R1T35  [RES_0402-0.0,5%,1/16W,EMPTY,G2A]
    2  FM_CPU0_PROCHOT_PCH_N      B  @BASEBOARD_FAB2_LIB.BASEBOARD_FAB2(SCH_1):FM_CPU0_PROCHOT_PCH_N
    1  FM_CPU0_PROCHOT_LVT3_N      A  @BASEBOARD_FAB2_LIB.BASEBOARD_FAB2(SCH_1):FM_CPU0_PROCHOT_LVT3_N

RES  I122  R1T36  [RES_0402-0.0,5%,1/16W,CHIP,G21A]
    1  FM_CPU0_PROCHOT_LVT3_N      A  @BASEBOARD_FAB2_LIB.BASEBOARD_FAB2(SCH_1):FM_CPU0_PROCHOT_LVT3_N
    2  FM_CPU0_PROCHOT_LVT3_BMC_N      B  @BASEBOARD_FAB2_LIB.BASEBOARD_FAB2(SCH_1):FM_CPU0_PROCHOT_LVT3_BMC_N

RES  I123  R1T37  [RES_0402-0.0,5%,1/16W,CHIP,G21A]
    1  FM_CPU1_PROCHOT_LVT3_N      A  @BASEBOARD_FAB2_LIB.BASEBOARD_FAB2(SCH_1):FM_CPU1_PROCHOT_LVT3_N
    2  FM_CPU1_PROCHOT_LVT3_BMC_N      B  @BASEBOARD_FAB2_LIB.BASEBOARD_FAB2(SCH_1):FM_CPU1_PROCHOT_LVT3_BMC_N

RES  I137  R1T38  [RES_0402-0.0,5%,1/16W,EMPTY,G2A]
    2  FM_CPU1_PROCHOT_PCH_N      B  @BASEBOARD_FAB2_LIB.BASEBOARD_FAB2(SCH_1):FM_CPU1_PROCHOT_PCH_N
    1  FM_CPU1_PROCHOT_LVT3_N      A  @BASEBOARD_FAB2_LIB.BASEBOARD_FAB2(SCH_1):FM_CPU1_PROCHOT_LVT3_N

RES  I144  R1U1   [RES_0402-100.0K,1%,1/16W,CHIP,A]
    2  GND                B  @BASEBOARD_FAB2_LIB.BASEBOARD_FAB2(SCH_1):GND
    1  FAN_TACH0          A  @BASEBOARD_FAB2_LIB.BASEBOARD_FAB2(SCH_1):FAN_TACH0

RES  I145  R1U2   [RES_0402-100.0K,1%,1/16W,CHIP,A]
    2  GND                B  @BASEBOARD_FAB2_LIB.BASEBOARD_FAB2(SCH_1):GND
    1  FAN_TACH1          A  @BASEBOARD_FAB2_LIB.BASEBOARD_FAB2(SCH_1):FAN_TACH1

RES  I114  R1U3   [RES_0402-0.0,5%,1/16W,CHIP,G21A]
    2  GND_NIC            B  @BASEBOARD_FAB2_LIB.BASEBOARD_FAB2(SCH_1):GND_NIC
    1  GND                A  @BASEBOARD_FAB2_LIB.BASEBOARD_FAB2(SCH_1):GND

RES  I149  R1U4   [RES_0402-100.0K,1%,1/16W,CHIP,A]
    2  GND                B  @BASEBOARD_FAB2_LIB.BASEBOARD_FAB2(SCH_1):GND
    1  FAN_TACH2          A  @BASEBOARD_FAB2_LIB.BASEBOARD_FAB2(SCH_1):FAN_TACH2

RES  I148  R1U5   [RES_0402-100.0K,1%,1/16W,CHIP,A]
    2  GND                B  @BASEBOARD_FAB2_LIB.BASEBOARD_FAB2(SCH_1):GND
    1  FAN_TACH3          A  @BASEBOARD_FAB2_LIB.BASEBOARD_FAB2(SCH_1):FAN_TACH3

RES  I128  R1U6   [RES_0402-10.0K,1%,1/16W,CHIP,GA]
    2  GND                B  @BASEBOARD_FAB2_LIB.BASEBOARD_FAB2(SCH_1):GND
    1  FM_BIOS_SPI_BMC_CTRL      A  @BASEBOARD_FAB2_LIB.BASEBOARD_FAB2(SCH_1):FM_BIOS_SPI_BMC_CTRL

RES  I127  R1U7   [RES_0402-10.0K,1%,1/16W,CHIP,GA]
    2  PD_SP_ENTEST       B  @BASEBOARD_FAB2_LIB.BASEBOARD_FAB2(SCH_1):PD_SP_ENTEST
    1  GND                A  @BASEBOARD_FAB2_LIB.BASEBOARD_FAB2(SCH_1):GND

RES  I223  R1U8   [RES_0402-0.0,5%,1/16W,CHIP,G21A]
    1  SMB_VR_STBY_LVC3_SDA_R      A  @BASEBOARD_FAB2_LIB.BASEBOARD_FAB2(SCH_1):SMB_VR_STBY_LVC3_SDA_R
    2  SMB_VR_STBY_LVC3_SDA      B  @BASEBOARD_FAB2_LIB.BASEBOARD_FAB2(SCH_1):SMB_VR_STBY_LVC3_SDA

RES  I232  R1U9   [RES_0402-20.0,1%,1/16W,CHIP,G2A]
    1  SMB_SMLINK0_STBY_LVC3_SCL_R      A  @BASEBOARD_FAB2_LIB.BASEBOARD_FAB2(SCH_1):SMB_SMLINK0_STBY_LVC3_SCL_R
    2  SMB_SMLINK0_STBY_LVC3_SCL      B  @BASEBOARD_FAB2_LIB.BASEBOARD_FAB2(SCH_1):SMB_SMLINK0_STBY_LVC3_SCL

RES  I233  R1U10  [RES_0402-20.0,1%,1/16W,CHIP,G2A]
    1  SMB_SMLINK0_STBY_LVC3_SDA_R      A  @BASEBOARD_FAB2_LIB.BASEBOARD_FAB2(SCH_1):SMB_SMLINK0_STBY_LVC3_SDA_R
    2  SMB_SMLINK0_STBY_LVC3_SDA      B  @BASEBOARD_FAB2_LIB.BASEBOARD_FAB2(SCH_1):SMB_SMLINK0_STBY_LVC3_SDA

RES  I222  R1U11  [RES_0402-0.0,5%,1/16W,CHIP,G21A]
    1  SMB_VR_STBY_LVC3_SCL_R      A  @BASEBOARD_FAB2_LIB.BASEBOARD_FAB2(SCH_1):SMB_VR_STBY_LVC3_SCL_R
    2  SMB_VR_STBY_LVC3_SCL      B  @BASEBOARD_FAB2_LIB.BASEBOARD_FAB2(SCH_1):SMB_VR_STBY_LVC3_SCL

RES  I547  R1U12  [RES_0402-51,5.0%,1/16W,CHIP,G2A]
    1  SGPIO_BMC_LD_R_N      A  @BASEBOARD_FAB2_LIB.BASEBOARD_FAB2(SCH_1):SGPIO_BMC_LD_R_N
    2  SGPIO_BMC_LD_N      B  @BASEBOARD_FAB2_LIB.BASEBOARD_FAB2(SCH_1):SGPIO_BMC_LD_N

RES  I546  R1U13  [RES_0402-51,5.0%,1/16W,CHIP,G2A]
    1  SGPIO_BMC_DOUT_R      A  @BASEBOARD_FAB2_LIB.BASEBOARD_FAB2(SCH_1):SGPIO_BMC_DOUT_R
    2  SGPIO_BMC_DOUT      B  @BASEBOARD_FAB2_LIB.BASEBOARD_FAB2(SCH_1):SGPIO_BMC_DOUT

RES  I548  R1U14  [RES_0402-51,5.0%,1/16W,CHIP,G2A]
    1  SGPIO_BMC_CLK_R      A  @BASEBOARD_FAB2_LIB.BASEBOARD_FAB2(SCH_1):SGPIO_BMC_CLK_R
    2  SGPIO_BMC_CLK      B  @BASEBOARD_FAB2_LIB.BASEBOARD_FAB2(SCH_1):SGPIO_BMC_CLK

RES  I22  R1U15  [RES_0402-1.00K,1%,1/16W,EMPTY,A]
    2  GND                B  @BASEBOARD_FAB2_LIB.BASEBOARD_FAB2(SCH_1):GND
    1  FM_BOARD_SKU_ID3      A  @BASEBOARD_FAB2_LIB.BASEBOARD_FAB2(SCH_1):FM_BOARD_SKU_ID3

RES  I20  R1U16  [RES_0402-1.00K,1%,1/16W,EMPTY,A]
    2  GND                B  @BASEBOARD_FAB2_LIB.BASEBOARD_FAB2(SCH_1):GND
    1  FM_BOARD_SKU_ID1      A  @BASEBOARD_FAB2_LIB.BASEBOARD_FAB2(SCH_1):FM_BOARD_SKU_ID1

RES  I21  R1U17  [RES_0402-1.00K,1%,1/16W,CHIP,GA]
    2  GND                B  @BASEBOARD_FAB2_LIB.BASEBOARD_FAB2(SCH_1):GND
    1  FM_BOARD_SKU_ID2      A  @BASEBOARD_FAB2_LIB.BASEBOARD_FAB2(SCH_1):FM_BOARD_SKU_ID2

RES  I19  R1U18  [RES_0402-1.00K,1%,1/16W,CHIP,GA]
    2  GND                B  @BASEBOARD_FAB2_LIB.BASEBOARD_FAB2(SCH_1):GND
    1  FM_BOARD_SKU_ID0      A  @BASEBOARD_FAB2_LIB.BASEBOARD_FAB2(SCH_1):FM_BOARD_SKU_ID0

RES  I226  R1U19  [RES_0402-20.0,1%,1/16W,CHIP,G2A]
    2  SMB_SPRINGVILLE_STBY_LVC3_SCL      B  @BASEBOARD_FAB2_LIB.BASEBOARD_FAB2(SCH_1):SMB_SPRINGVILLE_STBY_LVC3_SCL
    1  SMB_SMLINK0_STBY_LVC3_SCL      A  @BASEBOARD_FAB2_LIB.BASEBOARD_FAB2(SCH_1):SMB_SMLINK0_STBY_LVC3_SCL

RES  I225  R1U20  [RES_0402-20.0,1%,1/16W,CHIP,G2A]
    2  SMB_SPRINGVILLE_STBY_LVC3_SDA      B  @BASEBOARD_FAB2_LIB.BASEBOARD_FAB2(SCH_1):SMB_SPRINGVILLE_STBY_LVC3_SDA
    1  SMB_SMLINK0_STBY_LVC3_SDA      A  @BASEBOARD_FAB2_LIB.BASEBOARD_FAB2(SCH_1):SMB_SMLINK0_STBY_LVC3_SDA

RES  I24  R1U21  [RES_0402-2.7K,1%,1/16W,CHIP,G2A]
    1  P3V3_STBY          A  @BASEBOARD_FAB2_LIB.BASEBOARD_FAB2(SCH_1):P3V3_STBY
    2  FM_BOARD_SKU_ID3      B  @BASEBOARD_FAB2_LIB.BASEBOARD_FAB2(SCH_1):FM_BOARD_SKU_ID3

RES  I27  R1U22  [RES_0402-2.7K,1%,1/16W,CHIP,G2A]
    1  P3V3_STBY          A  @BASEBOARD_FAB2_LIB.BASEBOARD_FAB2(SCH_1):P3V3_STBY
    2  FM_BOARD_SKU_ID1      B  @BASEBOARD_FAB2_LIB.BASEBOARD_FAB2(SCH_1):FM_BOARD_SKU_ID1

RES  I28  R1U23  [RES_0402-2.7K,1%,1/16W,EMPTY,GA]
    1  P3V3_STBY          A  @BASEBOARD_FAB2_LIB.BASEBOARD_FAB2(SCH_1):P3V3_STBY
    2  FM_BOARD_SKU_ID0      B  @BASEBOARD_FAB2_LIB.BASEBOARD_FAB2(SCH_1):FM_BOARD_SKU_ID0

RES  I25  R1U24  [RES_0402-2.7K,1%,1/16W,EMPTY,GA]
    1  P3V3_STBY          A  @BASEBOARD_FAB2_LIB.BASEBOARD_FAB2(SCH_1):P3V3_STBY
    2  FM_BOARD_SKU_ID2      B  @BASEBOARD_FAB2_LIB.BASEBOARD_FAB2(SCH_1):FM_BOARD_SKU_ID2

RES  I79  R1U25  [RES_0402-20.0,1%,1/16W,CHIP,G2A]
    2  SMB_SENSOR_STBY_LVC3_SCL      B  @BASEBOARD_FAB2_LIB.BASEBOARD_FAB2(SCH_1):SMB_SENSOR_STBY_LVC3_SCL
    1  SMB_SENSOR_PCH_STBY_LVC3_SCL      A  @BASEBOARD_FAB2_LIB.BASEBOARD_FAB2(SCH_1):SMB_SENSOR_PCH_STBY_LVC3_SCL

RES  I148  R1U26  [RES_0402-5.11K,1%,1/16W,CHIP,GA]
    1  P3V3               A  @BASEBOARD_FAB2_LIB.BASEBOARD_FAB2(SCH_1):P3V3
    2  A_P3V3_SCALED      B  @BASEBOARD_FAB2_LIB.BASEBOARD_FAB2(SCH_1):A_P3V3_SCALED

RES  I149  R1U27  [RES_0402-8.2K,1%,1/16W,CHIP,G2A]
    2  GND                B  @BASEBOARD_FAB2_LIB.BASEBOARD_FAB2(SCH_1):GND
    1  A_P3V3_SCALED      A  @BASEBOARD_FAB2_LIB.BASEBOARD_FAB2(SCH_1):A_P3V3_SCALED

RES  I142  R1U28  [RES_0402-3.48K,1.0%,1/16W,CHIPA]
    2  GND                B  @BASEBOARD_FAB2_LIB.BASEBOARD_FAB2(SCH_1):GND
    1  A_P5V_SCALED       A  @BASEBOARD_FAB2_LIB.BASEBOARD_FAB2(SCH_1):A_P5V_SCALED

RES  I141  R1U29  [RES_0402-5.11K,1%,1/16W,CHIP,GA]
    1  P5V                A  @BASEBOARD_FAB2_LIB.BASEBOARD_FAB2(SCH_1):P5V
    2  A_P5V_SCALED       B  @BASEBOARD_FAB2_LIB.BASEBOARD_FAB2(SCH_1):A_P5V_SCALED

RES  I2   R1U30  [RES_0402-1.00K,1%,1/16W,CHIP,GA]
    1  PD_DIR_2           A  @BASEBOARD_FAB2_LIB.BASEBOARD_FAB2(SCH_1):PD_DIR_2
    2  GND                B  @BASEBOARD_FAB2_LIB.BASEBOARD_FAB2(SCH_1):GND

RES  I78  R1U31  [RES_0402-20.0,1%,1/16W,CHIP,G2A]
    2  SMB_SENSOR_STBY_LVC3_SDA      B  @BASEBOARD_FAB2_LIB.BASEBOARD_FAB2(SCH_1):SMB_SENSOR_STBY_LVC3_SDA
    1  SMB_SENSOR_PCH_STBY_LVC3_SDA      A  @BASEBOARD_FAB2_LIB.BASEBOARD_FAB2(SCH_1):SMB_SENSOR_PCH_STBY_LVC3_SDA

RES  I82  R1U32  [RES_0402-5.11K,1%,1/16W,CHIP,GA]
    1  P12V_STBY          A  @BASEBOARD_FAB2_LIB.BASEBOARD_FAB2(SCH_1):P12V_STBY
    2  A_P12V_STBY_SCALED      B  @BASEBOARD_FAB2_LIB.BASEBOARD_FAB2(SCH_1):A_P12V_STBY_SCALED

RES  I83  R1U33  [RES_0402-1.00K,1%,1/16W,CHIP,GA]
    2  GND                B  @BASEBOARD_FAB2_LIB.BASEBOARD_FAB2(SCH_1):GND
    1  A_P12V_STBY_SCALED      A  @BASEBOARD_FAB2_LIB.BASEBOARD_FAB2(SCH_1):A_P12V_STBY_SCALED

RES  I16  R1U34  [RES_0402-33.2,1%,1/16W,CHIP,G2A]
    2  H_CPU1_MEMKLM_MEMHOT_LVT3_N      B  @BASEBOARD_FAB2_LIB.BASEBOARD_FAB2(SCH_1):H_CPU1_MEMKLM_MEMHOT_LVT3_N
    1  H_CPU1_MEMKLM_MEMHOT_LVT3_K_N      A  @BASEBOARD_FAB2_LIB.BASEBOARD_FAB2(SCH_1):H_CPU1_MEMKLM_MEMHOT_LVT3_K_N

RES  I57  R1U35  [RES_0402-150.0,1%,1/16W,CHIP,GA]
    1  PVCCIO_CPU1        A  @BASEBOARD_FAB2_LIB.BASEBOARD_FAB2(SCH_1):PVCCIO_CPU1
    2  H_CPU1_MEMKLM_MEMHOT_G_N      B  @BASEBOARD_FAB2_LIB.BASEBOARD_FAB2(SCH_1):H_CPU1_MEMKLM_MEMHOT_G_N

RES  I15  R1U36  [RES_0402-33.2,1%,1/16W,CHIP,G2A]
    2  H_CPU1_MEMGHJ_MEMHOT_LVT3_N      B  @BASEBOARD_FAB2_LIB.BASEBOARD_FAB2(SCH_1):H_CPU1_MEMGHJ_MEMHOT_LVT3_N
    1  H_CPU1_MEMGHJ_MEMHOT_LVT3_K_N      A  @BASEBOARD_FAB2_LIB.BASEBOARD_FAB2(SCH_1):H_CPU1_MEMGHJ_MEMHOT_LVT3_K_N

RES  I26  R1U37  [RES_0402-100.0,1%,1/16W,CHIP,GA]
    1  P0V7_GTL2014_2      A  @BASEBOARD_FAB2_LIB.BASEBOARD_FAB2(SCH_1):P0V7_GTL2014_2
    2  GND                B  @BASEBOARD_FAB2_LIB.BASEBOARD_FAB2(SCH_1):GND

RES  I114  R1U38  [RES_0402-8.2K,1%,1/16W,CHIP,G2A]
    2  GND                B  @BASEBOARD_FAB2_LIB.BASEBOARD_FAB2(SCH_1):GND
    1  A_P3V3_STBY_SCALED      A  @BASEBOARD_FAB2_LIB.BASEBOARD_FAB2(SCH_1):A_P3V3_STBY_SCALED

RES  I88  R1U39  [RES_0402-5.11K,1%,1/16W,CHIP,GA]
    1  P3V3_STBY          A  @BASEBOARD_FAB2_LIB.BASEBOARD_FAB2(SCH_1):P3V3_STBY
    2  A_P3V3_STBY_SCALED      B  @BASEBOARD_FAB2_LIB.BASEBOARD_FAB2(SCH_1):A_P3V3_STBY_SCALED

RES  I81  R1U40  [RES_0402-33.2,1%,1/16W,CHIP,G2A]
    1  IRQ_VM_INT_R_N      A  @BASEBOARD_FAB2_LIB.BASEBOARD_FAB2(SCH_1):IRQ_VM_INT_R_N
    2  IRQ_VM_INT_N       B  @BASEBOARD_FAB2_LIB.BASEBOARD_FAB2(SCH_1):IRQ_VM_INT_N

RES  I56  R1U41  [RES_0402-150.0,1%,1/16W,CHIP,GA]
    1  PVCCIO_CPU1        A  @BASEBOARD_FAB2_LIB.BASEBOARD_FAB2(SCH_1):PVCCIO_CPU1
    2  H_CPU1_MEMGHJ_MEMHOT_G_N      B  @BASEBOARD_FAB2_LIB.BASEBOARD_FAB2(SCH_1):H_CPU1_MEMGHJ_MEMHOT_G_N

RES  I25  R1U43  [RES_0402-49.9,1%,1/16W,CHIP,G2A]
    1  PVCCIO_CPU0        A  @BASEBOARD_FAB2_LIB.BASEBOARD_FAB2(SCH_1):PVCCIO_CPU0
    2  P0V7_GTL2014_2      B  @BASEBOARD_FAB2_LIB.BASEBOARD_FAB2(SCH_1):P0V7_GTL2014_2

RES  I116  R1U44  [RES_0402-3.48K,1.0%,1/16W,CHIPA]
    2  GND                B  @BASEBOARD_FAB2_LIB.BASEBOARD_FAB2(SCH_1):GND
    1  A_P5V_STBY_SCALED      A  @BASEBOARD_FAB2_LIB.BASEBOARD_FAB2(SCH_1):A_P5V_STBY_SCALED

RES  I55  R1U45  [RES_0402-4.75K,1%,1/16W,CHIP,GA]
    2  GND                B  @BASEBOARD_FAB2_LIB.BASEBOARD_FAB2(SCH_1):GND
    1  FM_ADC128_A0       A  @BASEBOARD_FAB2_LIB.BASEBOARD_FAB2(SCH_1):FM_ADC128_A0

RES  I6   R1U46  [RES_0402-33.2,1%,1/16W,CHIP,G2A]
    2  H_CPU0_MEMABC_MEMHOT_LVT3_N      B  @BASEBOARD_FAB2_LIB.BASEBOARD_FAB2(SCH_1):H_CPU0_MEMABC_MEMHOT_LVT3_N
    1  H_CPU0_MEMABC_MEMHOT_LVT3_K_N      A  @BASEBOARD_FAB2_LIB.BASEBOARD_FAB2(SCH_1):H_CPU0_MEMABC_MEMHOT_LVT3_K_N

RES  I115  R1U47  [RES_0402-5.11K,1%,1/16W,CHIP,GA]
    1  P5V_STBY           A  @BASEBOARD_FAB2_LIB.BASEBOARD_FAB2(SCH_1):P5V_STBY
    2  A_P5V_STBY_SCALED      B  @BASEBOARD_FAB2_LIB.BASEBOARD_FAB2(SCH_1):A_P5V_STBY_SCALED

RES  I56  R1U48  [RES_0402-4.75K,1%,1/16W,CHIP,GA]
    2  GND                B  @BASEBOARD_FAB2_LIB.BASEBOARD_FAB2(SCH_1):GND
    1  FM_ADC128_A1       A  @BASEBOARD_FAB2_LIB.BASEBOARD_FAB2(SCH_1):FM_ADC128_A1

RES  I163  R1U49  [RES_0402-2.7K,1%,1/16W,CHIP,G2A]
    1  P3V3_STBY          A  @BASEBOARD_FAB2_LIB.BASEBOARD_FAB2(SCH_1):P3V3_STBY
    2  FM_BATTERY_SENSE_EN      B  @BASEBOARD_FAB2_LIB.BASEBOARD_FAB2(SCH_1):FM_BATTERY_SENSE_EN

RES  I126  R1U50  [RES_0402-200.0K,1%,1/16W,CHIP,A]
    2  P3V_BAT_SOURCE_R      B  @BASEBOARD_FAB2_LIB.BASEBOARD_FAB2(SCH_1):P3V_BAT_SOURCE_R
    1  A_P3V_BAT_R        A  @BASEBOARD_FAB2_LIB.BASEBOARD_FAB2(SCH_1):A_P3V_BAT_R

RES  I112  R1U51  [RES_0402-0.0,5%,1/16W,CHIP,G21A]
    2  GND_NIC            B  @BASEBOARD_FAB2_LIB.BASEBOARD_FAB2(SCH_1):GND_NIC
    1  GND                A  @BASEBOARD_FAB2_LIB.BASEBOARD_FAB2(SCH_1):GND

RES  I557  R1U52  [RES_0402-1.5K,1%,1/16W,CHIP,G2A]
    2  USB_PCH_BMC_P4_DN      B  @BASEBOARD_FAB2_LIB.BASEBOARD_FAB2(SCH_1):USB_PCH_BMC_P4_DN
    1  P3V3_STBY          A  @BASEBOARD_FAB2_LIB.BASEBOARD_FAB2(SCH_1):P3V3_STBY

RES  I64  R1U53  [RES_0402-0.0,5%,1/16W,CHIP,G21A]
    2  H_CPU1_MEMGHJ_MEMHOT_G_R_N      B  @BASEBOARD_FAB2_LIB.BASEBOARD_FAB2(SCH_1):H_CPU1_MEMGHJ_MEMHOT_G_R_N
    1  H_CPU1_MEMGHJ_MEMHOT_G_N      A  @BASEBOARD_FAB2_LIB.BASEBOARD_FAB2(SCH_1):H_CPU1_MEMGHJ_MEMHOT_G_N

RES  I93  R1U54  [RES_0402-0.0,5%,1/16W,CHIP,G21A]
    1  H_CPU1_MEMGHJ_MEMHOT_LVT3_N      A  @BASEBOARD_FAB2_LIB.BASEBOARD_FAB2(SCH_1):H_CPU1_MEMGHJ_MEMHOT_LVT3_N
    2  H_CPU1_MEMGHJ_MEMHOT_LVT3_BMC_N      B  @BASEBOARD_FAB2_LIB.BASEBOARD_FAB2(SCH_1):H_CPU1_MEMGHJ_MEMHOT_LVT3_BMC_N

RES  I67  R1U55  [RES_0402-0.0,5%,1/16W,EMPTY,G2A]
    2  H_CPU1_MEMGHJ_MEMHOT_G_PCH_N      B  @BASEBOARD_FAB2_LIB.BASEBOARD_FAB2(SCH_1):H_CPU1_MEMGHJ_MEMHOT_G_PCH_N
    1  H_CPU1_MEMGHJ_MEMHOT_G_N      A  @BASEBOARD_FAB2_LIB.BASEBOARD_FAB2(SCH_1):H_CPU1_MEMGHJ_MEMHOT_G_N

RES  I50  R1U56  [RES_0402-0.0,5%,1/16W,EMPTY,G2A]
    1  H_CPU0_MEMDEF_MEMHOT_G_PCH_N      A  @BASEBOARD_FAB2_LIB.BASEBOARD_FAB2(SCH_1):H_CPU0_MEMDEF_MEMHOT_G_PCH_N
    2  H_CPU0_MEMDEF_MEMHOT_G_N      B  @BASEBOARD_FAB2_LIB.BASEBOARD_FAB2(SCH_1):H_CPU0_MEMDEF_MEMHOT_G_N

RES  I69  R1U57  [RES_0402-0.0,5%,1/16W,EMPTY,G2A]
    1  H_CPU1_MEMGHJ_MEMHOT_LVT3_K_N      A  @BASEBOARD_FAB2_LIB.BASEBOARD_FAB2(SCH_1):H_CPU1_MEMGHJ_MEMHOT_LVT3_K_N
    2  H_CPU1_MEMGHJ_MEMHOT_G_PCH_N      B  @BASEBOARD_FAB2_LIB.BASEBOARD_FAB2(SCH_1):H_CPU1_MEMGHJ_MEMHOT_G_PCH_N

RES  I49  R1U58  [RES_0402-0.0,5%,1/16W,CHIP,G21A]
    2  H_CPU0_MEMDEF_MEMHOT_G_R_N      B  @BASEBOARD_FAB2_LIB.BASEBOARD_FAB2(SCH_1):H_CPU0_MEMDEF_MEMHOT_G_R_N
    1  H_CPU0_MEMDEF_MEMHOT_G_N      A  @BASEBOARD_FAB2_LIB.BASEBOARD_FAB2(SCH_1):H_CPU0_MEMDEF_MEMHOT_G_N

RES  I74  R1U59  [RES_0402-0.0,5%,1/16W,CHIP,G21A]
    2  H_CPU0_MEMABC_MEMHOT_LVT3_K_N      B  @BASEBOARD_FAB2_LIB.BASEBOARD_FAB2(SCH_1):H_CPU0_MEMABC_MEMHOT_LVT3_K_N
    1  H_CPU0_ABC_MEMHOT_LVT3_R_N      A  @BASEBOARD_FAB2_LIB.BASEBOARD_FAB2(SCH_1):H_CPU0_ABC_MEMHOT_LVT3_R_N

RES  I65  R1U60  [RES_0402-0.0,5%,1/16W,CHIP,G21A]
    2  H_CPU1_MEMKLM_MEMHOT_G_R_N      B  @BASEBOARD_FAB2_LIB.BASEBOARD_FAB2(SCH_1):H_CPU1_MEMKLM_MEMHOT_G_R_N
    1  H_CPU1_MEMKLM_MEMHOT_G_N      A  @BASEBOARD_FAB2_LIB.BASEBOARD_FAB2(SCH_1):H_CPU1_MEMKLM_MEMHOT_G_N

RES  I70  R1U61  [RES_0402-0.0,5%,1/16W,EMPTY,G2A]
    1  H_CPU1_MEMKLM_MEMHOT_LVT3_K_N      A  @BASEBOARD_FAB2_LIB.BASEBOARD_FAB2(SCH_1):H_CPU1_MEMKLM_MEMHOT_LVT3_K_N
    2  H_CPU1_MEMKLM_MEMHOT_G_PCH_N      B  @BASEBOARD_FAB2_LIB.BASEBOARD_FAB2(SCH_1):H_CPU1_MEMKLM_MEMHOT_G_PCH_N

RES  I68  R1U62  [RES_0402-0.0,5%,1/16W,EMPTY,G2A]
    2  H_CPU1_MEMKLM_MEMHOT_G_PCH_N      B  @BASEBOARD_FAB2_LIB.BASEBOARD_FAB2(SCH_1):H_CPU1_MEMKLM_MEMHOT_G_PCH_N
    1  H_CPU1_MEMKLM_MEMHOT_G_N      A  @BASEBOARD_FAB2_LIB.BASEBOARD_FAB2(SCH_1):H_CPU1_MEMKLM_MEMHOT_G_N

RES  I15  R1U63  [RES_0402-1.00K,1%,1/16W,CHIP,GA]
    1  PD_RST_RTCRST_N      A  @BASEBOARD_FAB2_LIB.BASEBOARD_FAB2(SCH_1):PD_RST_RTCRST_N
    2  GND                B  @BASEBOARD_FAB2_LIB.BASEBOARD_FAB2(SCH_1):GND

RES  I69  R1U64  [RES_0402-1.00K,1%,1/16W,CHIP,GA]
    1  PD_IE_DEBUG_MODE      A  @BASEBOARD_FAB2_LIB.BASEBOARD_FAB2(SCH_1):PD_IE_DEBUG_MODE
    2  GND                B  @BASEBOARD_FAB2_LIB.BASEBOARD_FAB2(SCH_1):GND

RES  I224  R2L1   [RES_0402-0.0,5%,1/16W,CHIP,G21A]
    2  VR_PVNN_PCH_AIREF1      B  @BASEBOARD_FAB2_LIB.BASEBOARD_FAB2(SCH_1):VR_PVNN_PCH_AIREF1
    1  VR_PVNN_P1V05_PCH_VD12      A  @BASEBOARD_FAB2_LIB.BASEBOARD_FAB2(SCH_1):VR_PVNN_P1V05_PCH_VD12

RES  I18  R2L4   [RES_0402-2.0K,1%,1/16W,CHIP,G2A]
    2  SGPIO_PCH_SSATA_DOUT0_R      B  @BASEBOARD_FAB2_LIB.BASEBOARD_FAB2(SCH_1):SGPIO_PCH_SSATA_DOUT0_R
    1  P3V3_STBY          A  @BASEBOARD_FAB2_LIB.BASEBOARD_FAB2(SCH_1):P3V3_STBY

RES  I20  R2L5   [RES_0402-2.0K,1%,1/16W,CHIP,G2A]
    2  SGPIO_PCH_SSATA_LOAD_R      B  @BASEBOARD_FAB2_LIB.BASEBOARD_FAB2(SCH_1):SGPIO_PCH_SSATA_LOAD_R
    1  P3V3_STBY          A  @BASEBOARD_FAB2_LIB.BASEBOARD_FAB2(SCH_1):P3V3_STBY

RES  I17  R2L6   [RES_0402-2.0K,1%,1/16W,CHIP,G2A]
    2  SGPIO_PCH_SSATA_CLOCK_R      B  @BASEBOARD_FAB2_LIB.BASEBOARD_FAB2(SCH_1):SGPIO_PCH_SSATA_CLOCK_R
    1  P3V3_STBY          A  @BASEBOARD_FAB2_LIB.BASEBOARD_FAB2(SCH_1):P3V3_STBY

RES  I225  R2L7   [RES_0402-0.0,5%,1/16W,CHIP,G21A]
    1  VR_PVNN_P1V05_PCH_VD12      A  @BASEBOARD_FAB2_LIB.BASEBOARD_FAB2(SCH_1):VR_PVNN_P1V05_PCH_VD12
    2  VR_P1V05_PCH_BIREF1      B  @BASEBOARD_FAB2_LIB.BASEBOARD_FAB2(SCH_1):VR_P1V05_PCH_BIREF1

RES  I154  R2L8   [RES_0603-10.0,1%,1/10W,CHIP,G2A]
    1  VSENSE_P1V05_PCH_STBY_AVSP      A  @BASEBOARD_FAB2_LIB.BASEBOARD_FAB2(SCH_1):VSENSE_P1V05_PCH_STBY_AVSP
    2  VR_P1V05_PCH_STBY_AVSP      B  @BASEBOARD_FAB2_LIB.BASEBOARD_FAB2(SCH_1):VR_P1V05_PCH_STBY_AVSP

RES  I176  R2L9   [RES_0402-4.02K,1%,1/16W,CHIP,GA]
    1  VR_PVNN_PCH_XADDR1      A  @BASEBOARD_FAB2_LIB.BASEBOARD_FAB2(SCH_1):VR_PVNN_PCH_XADDR1
    2  GND                B  @BASEBOARD_FAB2_LIB.BASEBOARD_FAB2(SCH_1):GND

RES  I166  R2L10  [RES_0402-1.5K,1%,1/16W,CHIP,G2A]
    1  VR_PVNN_PCH_VINSEN      A  @BASEBOARD_FAB2_LIB.BASEBOARD_FAB2(SCH_1):VR_PVNN_PCH_VINSEN
    2  GND                B  @BASEBOARD_FAB2_LIB.BASEBOARD_FAB2(SCH_1):GND

RES  I13  R2L11  [RES_0402-2.0K,1%,1/16W,CHIP,G2A]
    2  SGPIO_PCH_SATA_CLOCK_R      B  @BASEBOARD_FAB2_LIB.BASEBOARD_FAB2(SCH_1):SGPIO_PCH_SATA_CLOCK_R
    1  P3V3_STBY          A  @BASEBOARD_FAB2_LIB.BASEBOARD_FAB2(SCH_1):P3V3_STBY

RES  I2   R2L12  [RES_0402-2.0K,1%,1/16W,CHIP,G2A]
    2  SGPIO_PCH_SATA_LOAD_R      B  @BASEBOARD_FAB2_LIB.BASEBOARD_FAB2(SCH_1):SGPIO_PCH_SATA_LOAD_R
    1  P3V3_STBY          A  @BASEBOARD_FAB2_LIB.BASEBOARD_FAB2(SCH_1):P3V3_STBY

RES  I159  R2L14  [RES_0402-0.0,5%,1/16W,CHIP,G21A]
    2  VR_PVNN_PCH_VDD      B  @BASEBOARD_FAB2_LIB.BASEBOARD_FAB2(SCH_1):VR_PVNN_PCH_VDD
    1  P3V3_STBY          A  @BASEBOARD_FAB2_LIB.BASEBOARD_FAB2(SCH_1):P3V3_STBY

RES  I12  R2L15  [RES_0402-2.0K,1%,1/16W,CHIP,G2A]
    2  SGPIO_PCH_SATA_DOUT0_R      B  @BASEBOARD_FAB2_LIB.BASEBOARD_FAB2(SCH_1):SGPIO_PCH_SATA_DOUT0_R
    1  P3V3_STBY          A  @BASEBOARD_FAB2_LIB.BASEBOARD_FAB2(SCH_1):P3V3_STBY

RES  I147  R2L16  [RES_0402-22.1,1.0%,1/16W,CHIP,A]
    1  PWRGD_PVNN_PCH_R      A  @BASEBOARD_FAB2_LIB.BASEBOARD_FAB2(SCH_1):PWRGD_PVNN_PCH_R
    2  PWRGD_PVNN_P1V05_PCH      B  @BASEBOARD_FAB2_LIB.BASEBOARD_FAB2(SCH_1):PWRGD_PVNN_P1V05_PCH

RES  I221  R2L17  [RES_0402-0.0,5%,1/16W,CHIP,G21A]
    2  VR_PVNN_PCH_VREN      B  @BASEBOARD_FAB2_LIB.BASEBOARD_FAB2(SCH_1):VR_PVNN_PCH_VREN
    1  PWRGD_P1V8_PCH_STBY      A  @BASEBOARD_FAB2_LIB.BASEBOARD_FAB2(SCH_1):PWRGD_P1V8_PCH_STBY

RES  I266  R2L18  [RES_0402-1.00K,1%,1/16W,CHIP,GA]
    1  PD_SATA0_CONTROLLER_TYPE_R      A  @BASEBOARD_FAB2_LIB.BASEBOARD_FAB2(SCH_1):PD_SATA0_CONTROLLER_TYPE_R
    2  GND                B  @BASEBOARD_FAB2_LIB.BASEBOARD_FAB2(SCH_1):GND

RES  I80  R2L19  [RES_0402-49.9K,1%,1/16W,CHIP,GA]
    1  VR_P1V8_PCH_STBY_FB      A  @BASEBOARD_FAB2_LIB.BASEBOARD_FAB2(SCH_1):VR_P1V8_PCH_STBY_FB
    2  GND                B  @BASEBOARD_FAB2_LIB.BASEBOARD_FAB2(SCH_1):GND

RES  I81  R2L20  [RES_0402-63.4K,1.0%,1/16W,CHIPA]
    2  VR_P1V8_PCH_STBY_FB      B  @BASEBOARD_FAB2_LIB.BASEBOARD_FAB2(SCH_1):VR_P1V8_PCH_STBY_FB
    1  P1V8_PCH_STBY      A  @BASEBOARD_FAB2_LIB.BASEBOARD_FAB2(SCH_1):P1V8_PCH_STBY

RES  I263  R2L21  [RES_0402-2.0K,1%,1/16W,CHIP,G2A]
    2  PU_DATAIN1_SATA_0_R      B  @BASEBOARD_FAB2_LIB.BASEBOARD_FAB2(SCH_1):PU_DATAIN1_SATA_0_R
    1  P3V3               A  @BASEBOARD_FAB2_LIB.BASEBOARD_FAB2(SCH_1):P3V3

RES  I264  R2L22  [RES_0402-1.00K,1%,1/16W,CHIP,GA]
    1  PD_SATA1_CONTROLLER_TYPE_R      A  @BASEBOARD_FAB2_LIB.BASEBOARD_FAB2(SCH_1):PD_SATA1_CONTROLLER_TYPE_R
    2  GND                B  @BASEBOARD_FAB2_LIB.BASEBOARD_FAB2(SCH_1):GND

RES  I261  R2L23  [RES_0402-2.0K,1%,1/16W,CHIP,G2A]
    2  PU_DATAIN1_SATA_1_R      B  @BASEBOARD_FAB2_LIB.BASEBOARD_FAB2(SCH_1):PU_DATAIN1_SATA_1_R
    1  P3V3               A  @BASEBOARD_FAB2_LIB.BASEBOARD_FAB2(SCH_1):P3V3

RES  I148  R2L24  [RES_0402-2.26K,1.0%,1/16W,EMPTA]
    2  PU_VR_PVNN_PCH_FAULT1      B  @BASEBOARD_FAB2_LIB.BASEBOARD_FAB2(SCH_1):PU_VR_PVNN_PCH_FAULT1
    1  P3V3_STBY          A  @BASEBOARD_FAB2_LIB.BASEBOARD_FAB2(SCH_1):P3V3_STBY

RES  I235  R2L25  [RES_0402-100.0K,1%,1/16W,EMPTYA]
    2  VID_PCH_CORE_PVNN_AUX_VID_1      B  @BASEBOARD_FAB2_LIB.BASEBOARD_FAB2(SCH_1):VID_PCH_CORE_PVNN_AUX_VID_1
    1  P3V3_STBY          A  @BASEBOARD_FAB2_LIB.BASEBOARD_FAB2(SCH_1):P3V3_STBY

RES  I236  R2L26  [RES_0402-100.0K,1%,1/16W,EMPTYA]
    2  VID_PCH_CORE_PVNN_AUX_VID_0      B  @BASEBOARD_FAB2_LIB.BASEBOARD_FAB2(SCH_1):VID_PCH_CORE_PVNN_AUX_VID_0
    1  P3V3_STBY          A  @BASEBOARD_FAB2_LIB.BASEBOARD_FAB2(SCH_1):P3V3_STBY

RES  I218  R2M1   [RES_0402-33.2,1%,1/16W,CHIP,G2A]
    2  FM_CPLD_ADR_TRIGGER_R_N      B  @BASEBOARD_FAB2_LIB.BASEBOARD_FAB2(SCH_1):FM_CPLD_ADR_TRIGGER_R_N
    1  FM_CPLD_ADR_TRIGGER_N      A  @BASEBOARD_FAB2_LIB.BASEBOARD_FAB2(SCH_1):FM_CPLD_ADR_TRIGGER_N

RES  I346  R2M2   [RES_0402-4.75K,1%,1/16W,CHIP,GA]
    1  P3V3_STBY          A  @BASEBOARD_FAB2_LIB.BASEBOARD_FAB2(SCH_1):P3V3_STBY
    2  FM_ADR_SMI_GPIO_N      B  @BASEBOARD_FAB2_LIB.BASEBOARD_FAB2(SCH_1):FM_ADR_SMI_GPIO_N

RES  I172  R2M3   [RES_0402-33.2,1%,1/16W,CHIP,G2A]
    1  FM_PCH_PLD_DATA_R      A  @BASEBOARD_FAB2_LIB.BASEBOARD_FAB2(SCH_1):FM_PCH_PLD_DATA_R
    2  FM_PCH_PLD_DATA      B  @BASEBOARD_FAB2_LIB.BASEBOARD_FAB2(SCH_1):FM_PCH_PLD_DATA

RES  I284  R2M4   [RES_0402-1.00K,1%,1/16W,CHIP,GA]
    1  P3V3_STBY          A  @BASEBOARD_FAB2_LIB.BASEBOARD_FAB2(SCH_1):P3V3_STBY
    2  IRQ_HSC_FAULT_N      B  @BASEBOARD_FAB2_LIB.BASEBOARD_FAB2(SCH_1):IRQ_HSC_FAULT_N

RES  I348  R2M5   [RES_0402-4.75K,1%,1/16W,CHIP,GA]
    1  P3V3_STBY          A  @BASEBOARD_FAB2_LIB.BASEBOARD_FAB2(SCH_1):P3V3_STBY
    2  FM_BMC_CPLD_GPO      B  @BASEBOARD_FAB2_LIB.BASEBOARD_FAB2(SCH_1):FM_BMC_CPLD_GPO

RES  I99  R2M6   [RES_0402-1.0K,0.1%,1/16W,CHIP,A]
    2  P1V05_PCH_STBY_KR_PLL      B  @BASEBOARD_FAB2_LIB.BASEBOARD_FAB2(SCH_1):P1V05_PCH_STBY_KR_PLL
    1  A_KR1_RBIAS        A  @BASEBOARD_FAB2_LIB.BASEBOARD_FAB2(SCH_1):A_KR1_RBIAS

RES  I174  R2M7   [RES_0402-33.2,1%,1/16W,CHIP,G2A]
    1  FM_ADR_MODE_SEL_R      A  @BASEBOARD_FAB2_LIB.BASEBOARD_FAB2(SCH_1):FM_ADR_MODE_SEL_R
    2  FM_ADR_MODE_SEL      B  @BASEBOARD_FAB2_LIB.BASEBOARD_FAB2(SCH_1):FM_ADR_MODE_SEL

RES  I349  R2M8   [RES_0402-1.5K,1%,1/16W,CHIP,G2A]
    1  P3V3_STBY          A  @BASEBOARD_FAB2_LIB.BASEBOARD_FAB2(SCH_1):P3V3_STBY
    2  FM_CPU0_RC_ERROR_N      B  @BASEBOARD_FAB2_LIB.BASEBOARD_FAB2(SCH_1):FM_CPU0_RC_ERROR_N

RES  I173  R2N1   [RES_0402-33.2,1%,1/16W,CHIP,G2A]
    1  FM_CPU_CATERR_DLY_LVT3_R_N      A  @BASEBOARD_FAB2_LIB.BASEBOARD_FAB2(SCH_1):FM_CPU_CATERR_DLY_LVT3_R_N
    2  FM_CPU_CATERR_DLY_LVT3_N      B  @BASEBOARD_FAB2_LIB.BASEBOARD_FAB2(SCH_1):FM_CPU_CATERR_DLY_LVT3_N

RES  I96  R2N4   [RES_0402-1.0K,0.1%,1/16W,CHIP,A]
    1  P1V05_PCH_STBY_KR_PLL      A  @BASEBOARD_FAB2_LIB.BASEBOARD_FAB2(SCH_1):P1V05_PCH_STBY_KR_PLL
    2  A_KR0_RBIAS        B  @BASEBOARD_FAB2_LIB.BASEBOARD_FAB2(SCH_1):A_KR0_RBIAS

RES  I90  R2N5   [RES_0402-665,1.0%,1/16W,CHIP,GA]
    2  SMB_SMLINK0_STBY_LVC3_SCL      B  @BASEBOARD_FAB2_LIB.BASEBOARD_FAB2(SCH_1):SMB_SMLINK0_STBY_LVC3_SCL
    1  P3V3_STBY          A  @BASEBOARD_FAB2_LIB.BASEBOARD_FAB2(SCH_1):P3V3_STBY

RES  I128  R2N6   [RES_0402-10.0K,1%,1/16W,CHIP,GA]
    1  P3V3_STBY          A  @BASEBOARD_FAB2_LIB.BASEBOARD_FAB2(SCH_1):P3V3_STBY
    2  FM_GBE_LOM_DISABLE_N      B  @BASEBOARD_FAB2_LIB.BASEBOARD_FAB2(SCH_1):FM_GBE_LOM_DISABLE_N

RES  I309  R2N7   [RES_0402-4.75K,1%,1/16W,CHIP,GA]
    1  P3V3_STBY          A  @BASEBOARD_FAB2_LIB.BASEBOARD_FAB2(SCH_1):P3V3_STBY
    2  IRQ_BOARD_BMC_ALERT_N      B  @BASEBOARD_FAB2_LIB.BASEBOARD_FAB2(SCH_1):IRQ_BOARD_BMC_ALERT_N

RES  I89  R2N8   [RES_0402-665,1.0%,1/16W,CHIP,GA]
    2  SMB_SMLINK0_STBY_LVC3_SDA      B  @BASEBOARD_FAB2_LIB.BASEBOARD_FAB2(SCH_1):SMB_SMLINK0_STBY_LVC3_SDA
    1  P3V3_STBY          A  @BASEBOARD_FAB2_LIB.BASEBOARD_FAB2(SCH_1):P3V3_STBY

RES  I267  R2N9   [RES_0402-10.0K,1%,1/16W,CHIP,GA]
    2  PU_10GBE_LOM_PCI_DISABLE_N      B  @BASEBOARD_FAB2_LIB.BASEBOARD_FAB2(SCH_1):PU_10GBE_LOM_PCI_DISABLE_N
    1  P3V3_STBY          A  @BASEBOARD_FAB2_LIB.BASEBOARD_FAB2(SCH_1):P3V3_STBY

RES  I10  R2N10  [RES_0402-4.75K,1%,1/16W,CHIP,GA]
    1  P3V3_STBY          A  @BASEBOARD_FAB2_LIB.BASEBOARD_FAB2(SCH_1):P3V3_STBY
    2  FM_PCH_BMC_THERMTRIP_EXI_STRAP_      B  @BASEBOARD_FAB2_LIB.BASEBOARD_FAB2(SCH_1):FM_PCH_BMC_THERMTRIP_EXI_STRAP_N

RES  I122  R2N12  [RES_0402-10.0K,1%,1/16W,EMPTY,A]
    2  PWRGD_SYS_PWROK      B  @BASEBOARD_FAB2_LIB.BASEBOARD_FAB2(SCH_1):PWRGD_SYS_PWROK
    1  GND                A  @BASEBOARD_FAB2_LIB.BASEBOARD_FAB2(SCH_1):GND

RES  I142  R2N13  [RES_0402-10.0K,1%,1/16W,CHIP,GA]
    2  GND                B  @BASEBOARD_FAB2_LIB.BASEBOARD_FAB2(SCH_1):GND
    1  FM_BIOS_PREFRB2_GOOD      A  @BASEBOARD_FAB2_LIB.BASEBOARD_FAB2(SCH_1):FM_BIOS_PREFRB2_GOOD

RES  I83  R2N14  [RES_0402-1.00K,1%,1/16W,EMPTY,A]
    1  P3V3_STBY          A  @BASEBOARD_FAB2_LIB.BASEBOARD_FAB2(SCH_1):P3V3_STBY
    2  FM_USB_P0_EN_BOOT_BIOS_STRAP_N      B  @BASEBOARD_FAB2_LIB.BASEBOARD_FAB2(SCH_1):FM_USB_P0_EN_BOOT_BIOS_STRAP_N

RES  I247  R2N16  [RES_0402-10.0K,1%,1/16W,CHIP,GA]
    2  PU_IRQ_VRALERT_N      B  @BASEBOARD_FAB2_LIB.BASEBOARD_FAB2(SCH_1):PU_IRQ_VRALERT_N
    1  P3V3_STBY          A  @BASEBOARD_FAB2_LIB.BASEBOARD_FAB2(SCH_1):P3V3_STBY

RES  I29  R2N17  [RES_0402-2.7K,1%,1/16W,EMPTY,GA]
    1  P3V3_STBY          A  @BASEBOARD_FAB2_LIB.BASEBOARD_FAB2(SCH_1):P3V3_STBY
    2  FM_BOARD_SKU_ID4      B  @BASEBOARD_FAB2_LIB.BASEBOARD_FAB2(SCH_1):FM_BOARD_SKU_ID4

RES  I32  R2N18  [RES_0402-1.00K,1%,1/16W,CHIP,GA]
    2  GND                B  @BASEBOARD_FAB2_LIB.BASEBOARD_FAB2(SCH_1):GND
    1  FM_BOARD_SKU_ID4      A  @BASEBOARD_FAB2_LIB.BASEBOARD_FAB2(SCH_1):FM_BOARD_SKU_ID4

RES  I22  R2N19  [RES_0402-49.9,1%,1/16W,CHIP,G2A]
    2  SGPIO_PCH_SSATA_LOAD_R      B  @BASEBOARD_FAB2_LIB.BASEBOARD_FAB2(SCH_1):SGPIO_PCH_SSATA_LOAD_R
    1  SGPIO_PCH_SSATA_LOAD      A  @BASEBOARD_FAB2_LIB.BASEBOARD_FAB2(SCH_1):SGPIO_PCH_SSATA_LOAD

RES  I171  R2N20  [RES_0402-0.0,5%,1/16W,CHIP,G21A]
    1  SMB_LAN_STBY_LVC3_SDA_R2      A  @BASEBOARD_FAB2_LIB.BASEBOARD_FAB2(SCH_1):SMB_LAN_STBY_LVC3_SDA_R2
    2  SMB_LAN_STBY_LVC3_SDA      B  @BASEBOARD_FAB2_LIB.BASEBOARD_FAB2(SCH_1):SMB_LAN_STBY_LVC3_SDA

RES  I175  R2N21  [RES_0402-0.0,5%,1/16W,CHIP,G21A]
    1  SMB_LAN_STBY_LVC3_SCL_R2      A  @BASEBOARD_FAB2_LIB.BASEBOARD_FAB2(SCH_1):SMB_LAN_STBY_LVC3_SCL_R2
    2  SMB_LAN_STBY_LVC3_SCL      B  @BASEBOARD_FAB2_LIB.BASEBOARD_FAB2(SCH_1):SMB_LAN_STBY_LVC3_SCL

RES  I23  R2N22  [RES_0402-49.9,1%,1/16W,CHIP,G2A]
    2  SGPIO_PCH_SSATA_CLOCK_R      B  @BASEBOARD_FAB2_LIB.BASEBOARD_FAB2(SCH_1):SGPIO_PCH_SSATA_CLOCK_R
    1  SGPIO_PCH_SSATA_CLOCK      A  @BASEBOARD_FAB2_LIB.BASEBOARD_FAB2(SCH_1):SGPIO_PCH_SSATA_CLOCK

RES  I112  R2N23  [RES_0402-10.0K,1%,1/16W,CHIP,GA]
    1  P3V3_STBY          A  @BASEBOARD_FAB2_LIB.BASEBOARD_FAB2(SCH_1):P3V3_STBY
    2  FM_QAT_EN_N        B  @BASEBOARD_FAB2_LIB.BASEBOARD_FAB2(SCH_1):FM_QAT_EN_N

RES  I113  R2N24  [RES_0402-1.00K,1%,1/16W,EMPTY,A]
    2  GND                B  @BASEBOARD_FAB2_LIB.BASEBOARD_FAB2(SCH_1):GND
    1  FM_QAT_EN_N        A  @BASEBOARD_FAB2_LIB.BASEBOARD_FAB2(SCH_1):FM_QAT_EN_N

RES  I302  R2N25  [RES_0402-51.1,1.0%,1/16W,CHIP,A]
    1  FM_NMI_EVENT_N      A  @BASEBOARD_FAB2_LIB.BASEBOARD_FAB2(SCH_1):FM_NMI_EVENT_N
    2  FM_BMC_NMI_N       B  @BASEBOARD_FAB2_LIB.BASEBOARD_FAB2(SCH_1):FM_BMC_NMI_N

RES  I219  R2N26  [RES_0402-33.2,1%,1/16W,CHIP,G2A]
    2  FM_ADR_COMPLETE_R1      B  @BASEBOARD_FAB2_LIB.BASEBOARD_FAB2(SCH_1):FM_ADR_COMPLETE_R1
    1  FM_ADR_COMPLETE      A  @BASEBOARD_FAB2_LIB.BASEBOARD_FAB2(SCH_1):FM_ADR_COMPLETE

RES  I97  R2N27  [RES_0402-4.75K,1%,1/16W,CHIP,GA]
    1  P3V3               A  @BASEBOARD_FAB2_LIB.BASEBOARD_FAB2(SCH_1):P3V3
    2  FM_BMC_NMI_N       B  @BASEBOARD_FAB2_LIB.BASEBOARD_FAB2(SCH_1):FM_BMC_NMI_N

RES  I147  R2N28  [RES_0402-10.0K,1%,1/16W,CHIP,GA]
    1  P3V3_STBY          A  @BASEBOARD_FAB2_LIB.BASEBOARD_FAB2(SCH_1):P3V3_STBY
    2  FM_PASSWORD_CLEAR_N      B  @BASEBOARD_FAB2_LIB.BASEBOARD_FAB2(SCH_1):FM_PASSWORD_CLEAR_N

RES  I352  R2N29  [RES_0402-1.5K,1%,1/16W,CHIP,G2A]
    1  P3V3_STBY          A  @BASEBOARD_FAB2_LIB.BASEBOARD_FAB2(SCH_1):P3V3_STBY
    2  FM_CPU1_RC_ERROR_N      B  @BASEBOARD_FAB2_LIB.BASEBOARD_FAB2(SCH_1):FM_CPU1_RC_ERROR_N

RES  I11  R2N31  [RES_0402-49.9,1%,1/16W,CHIP,G2A]
    2  SGPIO_PCH_SATA_CLOCK_R      B  @BASEBOARD_FAB2_LIB.BASEBOARD_FAB2(SCH_1):SGPIO_PCH_SATA_CLOCK_R
    1  SGPIO_PCH_SATA_CLOCK      A  @BASEBOARD_FAB2_LIB.BASEBOARD_FAB2(SCH_1):SGPIO_PCH_SATA_CLOCK

RES  I341  R2N32  [RES_0402-4.75K,1%,1/16W,CHIP,GA]
    1  P3V3_STBY          A  @BASEBOARD_FAB2_LIB.BASEBOARD_FAB2(SCH_1):P3V3_STBY
    2  FM_BIOS_SMI_ACTIVE_N      B  @BASEBOARD_FAB2_LIB.BASEBOARD_FAB2(SCH_1):FM_BIOS_SMI_ACTIVE_N

RES  I91  R2P1   [RES_0402-0.0,5%,1/16W,CHIP,G21A]
    2  RMII_SPRNGVLLE_BMC_PCH_RXD1_R1      B  @BASEBOARD_FAB2_LIB.BASEBOARD_FAB2(SCH_1):RMII_SPRNGVLLE_BMC_PCH_RXD1_R1
    1  RMII_SPRNGVLLE_BMC_PCH_RXD1      A  @BASEBOARD_FAB2_LIB.BASEBOARD_FAB2(SCH_1):RMII_SPRNGVLLE_BMC_PCH_RXD1

RES  I37  R2P2   [RES_0402-1.00K,1%,1/16W,CHIP,GA]
    2  XDP_DEBUG_CONSENT_N      B  @BASEBOARD_FAB2_LIB.BASEBOARD_FAB2(SCH_1):XDP_DEBUG_CONSENT_N
    1  SPI_PCH_IO2        A  @BASEBOARD_FAB2_LIB.BASEBOARD_FAB2(SCH_1):SPI_PCH_IO2

RES  I2   R2P3   [RES_0402-4.75K,1%,1/16W,CHIP,GA]
    1  P3V3_STBY          A  @BASEBOARD_FAB2_LIB.BASEBOARD_FAB2(SCH_1):P3V3_STBY
    2  IRQ_FORCE_NM_THROTTLE_R_N      B  @BASEBOARD_FAB2_LIB.BASEBOARD_FAB2(SCH_1):IRQ_FORCE_NM_THROTTLE_R_N

RES  I74  R2P4   [RES_0402-33.2,1%,1/16W,CHIP,G2A]
    1  IRQ_FORCE_NM_THROTTLE_R_N      A  @BASEBOARD_FAB2_LIB.BASEBOARD_FAB2(SCH_1):IRQ_FORCE_NM_THROTTLE_R_N
    2  IRQ_FORCE_NM_THROTTLE_N      B  @BASEBOARD_FAB2_LIB.BASEBOARD_FAB2(SCH_1):IRQ_FORCE_NM_THROTTLE_N

RES  I56  R2P5   [RES_0402-4.75K,1%,1/16W,CHIP,GA]
    1  P3V3_STBY          A  @BASEBOARD_FAB2_LIB.BASEBOARD_FAB2(SCH_1):P3V3_STBY
    2  FM_PMBUS_ALERT_BUF_EN      B  @BASEBOARD_FAB2_LIB.BASEBOARD_FAB2(SCH_1):FM_PMBUS_ALERT_BUF_EN

RES  I52  R2P8   [RES_0402-560,5%,1/16W,CHIP,G21A]
    1  P3V3_STBY          A  @BASEBOARD_FAB2_LIB.BASEBOARD_FAB2(SCH_1):P3V3_STBY
    2  IRQ_SML1_PMBUS_ALERT_N      B  @BASEBOARD_FAB2_LIB.BASEBOARD_FAB2(SCH_1):IRQ_SML1_PMBUS_ALERT_N

RES  I63  R2P11  [RES_0402-1.00K,1%,1/16W,EMPTY,A]
    2  GND                B  @BASEBOARD_FAB2_LIB.BASEBOARD_FAB2(SCH_1):GND
    1  FM_PMBUS_ALERT_BUF_EN_N      A  @BASEBOARD_FAB2_LIB.BASEBOARD_FAB2(SCH_1):FM_PMBUS_ALERT_BUF_EN_N

RES  I23  R2P12  [RES_0402-0.0,5%,1/16W,EMPTY,G2A]
    1  IRQ_DIMM_SAVE_LVT3_N      A  @BASEBOARD_FAB2_LIB.BASEBOARD_FAB2(SCH_1):IRQ_DIMM_SAVE_LVT3_N
    2  FM_ADR_SMI_GPIO_N      B  @BASEBOARD_FAB2_LIB.BASEBOARD_FAB2(SCH_1):FM_ADR_SMI_GPIO_N

RES  I61  R2P13  [RES_0402-4.75K,1%,1/16W,CHIP,GA]
    1  P3V3_STBY          A  @BASEBOARD_FAB2_LIB.BASEBOARD_FAB2(SCH_1):P3V3_STBY
    2  FM_PMBUS_ALERT_BUF_EN_N      B  @BASEBOARD_FAB2_LIB.BASEBOARD_FAB2(SCH_1):FM_PMBUS_ALERT_BUF_EN_N

RES  I115  R2P14  [RES_0402-0.0,5%,1/16W,CHIP,G21A]
    2  FM_SSATA_PCIE_M2_SEL      B  @BASEBOARD_FAB2_LIB.BASEBOARD_FAB2(SCH_1):FM_SSATA_PCIE_M2_SEL
    1  FM_M2_DET_LVC3      A  @BASEBOARD_FAB2_LIB.BASEBOARD_FAB2(SCH_1):FM_M2_DET_LVC3

RES  I111  R2P15  [RES_0402-10.0K,1%,1/16W,CHIP,GA]
    1  P3V3               A  @BASEBOARD_FAB2_LIB.BASEBOARD_FAB2(SCH_1):P3V3
    2  FM_M2_SSD_PEDET      B  @BASEBOARD_FAB2_LIB.BASEBOARD_FAB2(SCH_1):FM_M2_SSD_PEDET

RES  I113  R2P16  [RES_0402-10.0K,1%,1/16W,CHIP,GA]
    1  P3V3_STBY          A  @BASEBOARD_FAB2_LIB.BASEBOARD_FAB2(SCH_1):P3V3_STBY
    2  FM_M2_DET_LVC3      B  @BASEBOARD_FAB2_LIB.BASEBOARD_FAB2(SCH_1):FM_M2_DET_LVC3

RES  I3   R2P17  [RES_0402-4.75K,1%,1/16W,CHIP,GA]
    1  P3V3_STBY          A  @BASEBOARD_FAB2_LIB.BASEBOARD_FAB2(SCH_1):P3V3_STBY
    2  FM_PCH_BMC_THERMTRIP_N      B  @BASEBOARD_FAB2_LIB.BASEBOARD_FAB2(SCH_1):FM_PCH_BMC_THERMTRIP_N

RES  I121  R2P18  [RES_0402-10.0K,1%,1/16W,CHIP,GA]
    2  PWRGD_P5V_N        B  @BASEBOARD_FAB2_LIB.BASEBOARD_FAB2(SCH_1):PWRGD_P5V_N
    1  P3V3_STBY          A  @BASEBOARD_FAB2_LIB.BASEBOARD_FAB2(SCH_1):P3V3_STBY

RES  I107  R2P19  [RES_0402-10.0K,1%,1/16W,CHIP,GA]
    1  P3V3_STBY          A  @BASEBOARD_FAB2_LIB.BASEBOARD_FAB2(SCH_1):P3V3_STBY
    2  FM_DIS_ADR_DLY      B  @BASEBOARD_FAB2_LIB.BASEBOARD_FAB2(SCH_1):FM_DIS_ADR_DLY

RES  I65  R2P20  [RES_0402-100.0,1%,1/16W,CHIP,GA]
    1  PWRGD_P5V_R        A  @BASEBOARD_FAB2_LIB.BASEBOARD_FAB2(SCH_1):PWRGD_P5V_R
    2  PWRGD_P5V          B  @BASEBOARD_FAB2_LIB.BASEBOARD_FAB2(SCH_1):PWRGD_P5V

RES  I122  R2P21  [RES_0402-10.0K,1%,1/16W,CHIP,GA]
    2  PWRGD_P5V_R        B  @BASEBOARD_FAB2_LIB.BASEBOARD_FAB2(SCH_1):PWRGD_P5V_R
    1  P3V3_STBY          A  @BASEBOARD_FAB2_LIB.BASEBOARD_FAB2(SCH_1):P3V3_STBY

RES  I360  R2P22  [RES_0402-10.0K,1%,1/16W,CHIP,GA]
    1  P3V3_STBY          A  @BASEBOARD_FAB2_LIB.BASEBOARD_FAB2(SCH_1):P3V3_STBY
    2  FM_CPU1_RC_EN      B  @BASEBOARD_FAB2_LIB.BASEBOARD_FAB2(SCH_1):FM_CPU1_RC_EN

RES  I34  R2R1   [RES_0402-10.0K,1%,1/16W,CHIP,GA]
    2  PU_RST_PERST_BIT0      B  @BASEBOARD_FAB2_LIB.BASEBOARD_FAB2(SCH_1):PU_RST_PERST_BIT0
    1  P3V3_STBY          A  @BASEBOARD_FAB2_LIB.BASEBOARD_FAB2(SCH_1):P3V3_STBY

RES  I338  R2R2   [RES_0402-33.2,1%,1/16W,CHIP,G2A]
    1  RST_RSMRST_R_N      A  @BASEBOARD_FAB2_LIB.BASEBOARD_FAB2(SCH_1):RST_RSMRST_R_N
    2  RST_RSMRST_N       B  @BASEBOARD_FAB2_LIB.BASEBOARD_FAB2(SCH_1):RST_RSMRST_N

RES  I41  R2R3   [RES_0402-10.0K,1%,1/16W,CHIP,GA]
    1  P3V3_STBY          A  @BASEBOARD_FAB2_LIB.BASEBOARD_FAB2(SCH_1):P3V3_STBY
    2  FM_PLD_DEBUG_MODE_N      B  @BASEBOARD_FAB2_LIB.BASEBOARD_FAB2(SCH_1):FM_PLD_DEBUG_MODE_N

RES  I184  R2R4   [RES_0402-0.0,5%,1/16W,CHIP,G21A]
    1  FM_ADR_SMI_GPIO_R_N      A  @BASEBOARD_FAB2_LIB.BASEBOARD_FAB2(SCH_1):FM_ADR_SMI_GPIO_R_N
    2  FM_ADR_SMI_GPIO_N      B  @BASEBOARD_FAB2_LIB.BASEBOARD_FAB2(SCH_1):FM_ADR_SMI_GPIO_N

RES  I258  R2R5   [RES_0402-1.00K,1%,1/16W,CHIP,GA]
    1  P3V3_STBY          A  @BASEBOARD_FAB2_LIB.BASEBOARD_FAB2(SCH_1):P3V3_STBY
    2  FM_PCH_PLD_DATA      B  @BASEBOARD_FAB2_LIB.BASEBOARD_FAB2(SCH_1):FM_PCH_PLD_DATA

RES  I166  R2R6   [RES_0402-51,5.0%,1/16W,CHIP,G2A]
    1  SGPIO_BMC_DIN_R      A  @BASEBOARD_FAB2_LIB.BASEBOARD_FAB2(SCH_1):SGPIO_BMC_DIN_R
    2  SGPIO_BMC_DIN      B  @BASEBOARD_FAB2_LIB.BASEBOARD_FAB2(SCH_1):SGPIO_BMC_DIN

RES  I172  R2R7   [RES_0402-4.75K,1%,1/16W,CHIP,GA]
    1  P3V3_STBY          A  @BASEBOARD_FAB2_LIB.BASEBOARD_FAB2(SCH_1):P3V3_STBY
    2  FM_FORCE_ADR_N      B  @BASEBOARD_FAB2_LIB.BASEBOARD_FAB2(SCH_1):FM_FORCE_ADR_N

RES  I18  R2R8   [RES_0402-100.0,1%,1/16W,CHIP,GA]
    2  GND                B  @BASEBOARD_FAB2_LIB.BASEBOARD_FAB2(SCH_1):GND
    1  FM_MEZZ_PRSNTB1_N      A  @BASEBOARD_FAB2_LIB.BASEBOARD_FAB2(SCH_1):FM_MEZZ_PRSNTB1_N

RES  I352  R2R9   [RES_0402-200.0,1%,1/16W,CHIP,GA]
    1  FP_NMI_BTN_OUT_R_N      A  @BASEBOARD_FAB2_LIB.BASEBOARD_FAB2(SCH_1):FP_NMI_BTN_OUT_R_N
    2  FP_NMI_BTN_OUT_N      B  @BASEBOARD_FAB2_LIB.BASEBOARD_FAB2(SCH_1):FP_NMI_BTN_OUT_N

RES  I358  R2R10  [RES_0402-33.2,1%,1/16W,CHIP,G2A]
    1  FP_NMI_BTN_R_N      A  @BASEBOARD_FAB2_LIB.BASEBOARD_FAB2(SCH_1):FP_NMI_BTN_R_N
    2  FP_NMI_BTN_N       B  @BASEBOARD_FAB2_LIB.BASEBOARD_FAB2(SCH_1):FP_NMI_BTN_N

RES  I11  R2R11  [RES_0402-1.00K,1%,1/16W,EMPTY,A]
    1  SPI_PCH_IO2        A  @BASEBOARD_FAB2_LIB.BASEBOARD_FAB2(SCH_1):SPI_PCH_IO2
    2  GND                B  @BASEBOARD_FAB2_LIB.BASEBOARD_FAB2(SCH_1):GND

RES  I93  R2R12  [RES_0402-0.0,5%,1/16W,CHIP,G21A]
    2  SPI_PCH_IO2_R1      B  @BASEBOARD_FAB2_LIB.BASEBOARD_FAB2(SCH_1):SPI_PCH_IO2_R1
    1  SPI_PCH_IO2        A  @BASEBOARD_FAB2_LIB.BASEBOARD_FAB2(SCH_1):SPI_PCH_IO2

RES  I15  R2T1   [RES_0402-1.00K,1%,1/16W,CHIP,GA]
    1  SPI_PCH_IO3        A  @BASEBOARD_FAB2_LIB.BASEBOARD_FAB2(SCH_1):SPI_PCH_IO3
    2  GND                B  @BASEBOARD_FAB2_LIB.BASEBOARD_FAB2(SCH_1):GND

RES  I92  R2T2   [RES_0402-0.0,5%,1/16W,CHIP,G21A]
    2  SPI_PCH_IO3_R1      B  @BASEBOARD_FAB2_LIB.BASEBOARD_FAB2(SCH_1):SPI_PCH_IO3_R1
    1  SPI_PCH_IO3        A  @BASEBOARD_FAB2_LIB.BASEBOARD_FAB2(SCH_1):SPI_PCH_IO3

RES  I54  R2T3   [RES_0402-4.75K,1%,1/16W,CHIP,GA]
    1  P3V3_STBY          A  @BASEBOARD_FAB2_LIB.BASEBOARD_FAB2(SCH_1):P3V3_STBY
    2  FM_FAST_PROCHOT_EN_N      B  @BASEBOARD_FAB2_LIB.BASEBOARD_FAB2(SCH_1):FM_FAST_PROCHOT_EN_N

RES  I152  R2T4   [RES_0402-1.0K,0.1%,1/16W,CHIP,A]
    1  P3V3_STBY          A  @BASEBOARD_FAB2_LIB.BASEBOARD_FAB2(SCH_1):P3V3_STBY
    2  GND                B  @BASEBOARD_FAB2_LIB.BASEBOARD_FAB2(SCH_1):GND

RES  I326  R2T5   [RES_0402-1.00K,1%,1/16W,CHIP,GA]
    1  P3V3_STBY          A  @BASEBOARD_FAB2_LIB.BASEBOARD_FAB2(SCH_1):P3V3_STBY
    2  H_CPU0_FAST_WAKE      B  @BASEBOARD_FAB2_LIB.BASEBOARD_FAB2(SCH_1):H_CPU0_FAST_WAKE

RES  I127  R2T6   [RES_0402-4.75K,1%,1/16W,CHIP,GA]
    1  P3V3_STBY          A  @BASEBOARD_FAB2_LIB.BASEBOARD_FAB2(SCH_1):P3V3_STBY
    2  FM_BACKUP_BIOS_SEL_N      B  @BASEBOARD_FAB2_LIB.BASEBOARD_FAB2(SCH_1):FM_BACKUP_BIOS_SEL_N

RES  I327  R2T7   [RES_0402-1.00K,1%,1/16W,CHIP,GA]
    1  P3V3_STBY          A  @BASEBOARD_FAB2_LIB.BASEBOARD_FAB2(SCH_1):P3V3_STBY
    2  H_CPU0_FAST_WAKE_LVT3_N      B  @BASEBOARD_FAB2_LIB.BASEBOARD_FAB2(SCH_1):H_CPU0_FAST_WAKE_LVT3_N

RES  I106  R2T8   [RES_0402-10.0K,1%,1/16W,CHIP,GA]
    2  SPI_SWITCH_CS0_N      B  @BASEBOARD_FAB2_LIB.BASEBOARD_FAB2(SCH_1):SPI_SWITCH_CS0_N
    1  P3V3_STBY          A  @BASEBOARD_FAB2_LIB.BASEBOARD_FAB2(SCH_1):P3V3_STBY

RES  I62  R2T9   [RES_0402-75,1.0%,1/16W,CHIP,G2A]
    2  SPI_CS0_SECONDARY_R_N      B  @BASEBOARD_FAB2_LIB.BASEBOARD_FAB2(SCH_1):SPI_CS0_SECONDARY_R_N
    1  SPI_CS0_SECONDARY_N      A  @BASEBOARD_FAB2_LIB.BASEBOARD_FAB2(SCH_1):SPI_CS0_SECONDARY_N

RES  I105  R2T11  [RES_0402-4.75K,1%,1/16W,CHIP,GA]
    1  P3V3_STBY          A  @BASEBOARD_FAB2_LIB.BASEBOARD_FAB2(SCH_1):P3V3_STBY
    2  FM_DUAL_BIOS_SEL_N      B  @BASEBOARD_FAB2_LIB.BASEBOARD_FAB2(SCH_1):FM_DUAL_BIOS_SEL_N

RES  I205  R2T12  [RES_0402-10.0K,1%,1/16W,EMPTY,A]
    1  PD_PEREXT          A  @BASEBOARD_FAB2_LIB.BASEBOARD_FAB2(SCH_1):PD_PEREXT
    2  GND                B  @BASEBOARD_FAB2_LIB.BASEBOARD_FAB2(SCH_1):GND

RES  I101  R2T13  [RES_0402-200.0,1%,1/16W,CHIP,GA]
    2  SPI_CS0_PRIMARY_R_N      B  @BASEBOARD_FAB2_LIB.BASEBOARD_FAB2(SCH_1):SPI_CS0_PRIMARY_R_N
    1  SPI_CS0_PRIMARY_N      A  @BASEBOARD_FAB2_LIB.BASEBOARD_FAB2(SCH_1):SPI_CS0_PRIMARY_N

RES  I532  R2T15  [RES_0402-100.0K,1%,1/16W,CHIP,A]
    2  GND                B  @BASEBOARD_FAB2_LIB.BASEBOARD_FAB2(SCH_1):GND
    1  CLK_24M_BMC_LPC      A  @BASEBOARD_FAB2_LIB.BASEBOARD_FAB2(SCH_1):CLK_24M_BMC_LPC

RES  I67  R2T16  [RES_0402-75,1.0%,1/16W,CHIP,G2A]
    1  H_CPU_ERR0_GTL_R_N      A  @BASEBOARD_FAB2_LIB.BASEBOARD_FAB2(SCH_1):H_CPU_ERR0_GTL_R_N
    2  H_CPU_ERR0_GTL_N      B  @BASEBOARD_FAB2_LIB.BASEBOARD_FAB2(SCH_1):H_CPU_ERR0_GTL_N

RES  I23  R2T17  [RES_0402-0.0,5%,1/16W,CHIP,G21A]
    2  H_CPU_ERR0_GTL_R_N      B  @BASEBOARD_FAB2_LIB.BASEBOARD_FAB2(SCH_1):H_CPU_ERR0_GTL_R_N
    1  H_CPU0_ERR0_G_N      A  @BASEBOARD_FAB2_LIB.BASEBOARD_FAB2(SCH_1):H_CPU0_ERR0_G_N

RES  I288  R2T18  [RES_0402-49.9,1%,1/16W,CHIP,G2A]
    1  RST_BMC_SYSRST_BTN_OUT_B_R_N      A  @BASEBOARD_FAB2_LIB.BASEBOARD_FAB2(SCH_1):RST_BMC_SYSRST_BTN_OUT_B_R_N
    2  RST_BMC_SYSRST_BTN_OUT_B_N      B  @BASEBOARD_FAB2_LIB.BASEBOARD_FAB2(SCH_1):RST_BMC_SYSRST_BTN_OUT_B_N

RES  I63  R2T19  [RES_0402-200.0,1%,1/16W,CHIP,GA]
    1  PVCCIO_CPU0        A  @BASEBOARD_FAB2_LIB.BASEBOARD_FAB2(SCH_1):PVCCIO_CPU0
    2  H_CPU_ERR0_GTL_R_N      B  @BASEBOARD_FAB2_LIB.BASEBOARD_FAB2(SCH_1):H_CPU_ERR0_GTL_R_N

RES  I16  R2T20  [RES_0402-0.0,5%,1/16W,CHIP,G21A]
    2  H_CPU_ERR0_GTL_R_N      B  @BASEBOARD_FAB2_LIB.BASEBOARD_FAB2(SCH_1):H_CPU_ERR0_GTL_R_N
    1  H_CPU1_ERR0_G_N      A  @BASEBOARD_FAB2_LIB.BASEBOARD_FAB2(SCH_1):H_CPU1_ERR0_G_N

RES  I105  R2T21  [RES_0603-2.2,1.0%,1/10W,CHIP,GA]
    2  P3V3_STBY_MNG_CPU      B  @BASEBOARD_FAB2_LIB.BASEBOARD_FAB2(SCH_1):P3V3_STBY_MNG_CPU
    1  P3V3_STBY_MNG      A  @BASEBOARD_FAB2_LIB.BASEBOARD_FAB2(SCH_1):P3V3_STBY_MNG

RES  I210  R2T22  [RES_0402-10.0K,1%,1/16W,CHIP,GA]
    2  RST_BMC_SYSRST_BTN_OUT_B_R_N      B  @BASEBOARD_FAB2_LIB.BASEBOARD_FAB2(SCH_1):RST_BMC_SYSRST_BTN_OUT_B_R_N
    1  P3V3_STBY          A  @BASEBOARD_FAB2_LIB.BASEBOARD_FAB2(SCH_1):P3V3_STBY

RES  I94  R2T23  [RES_0603-2.2,1.0%,1/10W,CHIP,GA]
    2  P3V3_STBY_MNG_RGMII      B  @BASEBOARD_FAB2_LIB.BASEBOARD_FAB2(SCH_1):P3V3_STBY_MNG_RGMII
    1  P3V3_STBY_MNG      A  @BASEBOARD_FAB2_LIB.BASEBOARD_FAB2(SCH_1):P3V3_STBY_MNG

RES  I520  R2T24  [RES_0402-33.2,1%,1/16W,CHIP,G2A]
    2  IRQ_LPC_SERIRQ_R      B  @BASEBOARD_FAB2_LIB.BASEBOARD_FAB2(SCH_1):IRQ_LPC_SERIRQ_R
    1  IRQ_LPC_SERIRQ_N      A  @BASEBOARD_FAB2_LIB.BASEBOARD_FAB2(SCH_1):IRQ_LPC_SERIRQ_N

RES  I48  R2T25  [RES_0402-1.00K,1%,1/16W,CHIP,GA]
    1  PD_CKMNG_OE        A  @BASEBOARD_FAB2_LIB.BASEBOARD_FAB2(SCH_1):PD_CKMNG_OE
    2  GND                B  @BASEBOARD_FAB2_LIB.BASEBOARD_FAB2(SCH_1):GND

RES  I87  R2T26  [RES_0402-200.0,1%,1/16W,CHIP,GA]
    1  PVCCIO_CPU0        A  @BASEBOARD_FAB2_LIB.BASEBOARD_FAB2(SCH_1):PVCCIO_CPU0
    2  H_CPU_ERR1_GTL_R_N      B  @BASEBOARD_FAB2_LIB.BASEBOARD_FAB2(SCH_1):H_CPU_ERR1_GTL_R_N

RES  I13  R2T27  [RES_0402-0.0,5%,1/16W,CHIP,G21A]
    2  H_CPU_ERR1_GTL_R_N      B  @BASEBOARD_FAB2_LIB.BASEBOARD_FAB2(SCH_1):H_CPU_ERR1_GTL_R_N
    1  H_CPU1_ERR1_G_N      A  @BASEBOARD_FAB2_LIB.BASEBOARD_FAB2(SCH_1):H_CPU1_ERR1_G_N

RES  I289  R2T28  [RES_0402-33.2,1%,1/16W,CHIP,G2A]
    1  FM_PCH_PWRBTN_R_N      A  @BASEBOARD_FAB2_LIB.BASEBOARD_FAB2(SCH_1):FM_PCH_PWRBTN_R_N
    2  FM_PCH_PWRBTN_N      B  @BASEBOARD_FAB2_LIB.BASEBOARD_FAB2(SCH_1):FM_PCH_PWRBTN_N

RES  I298  R2T29  [RES_0402-2.21K,1%,1/16W,CHIP,GA]
    1  P3V3_STBY          A  @BASEBOARD_FAB2_LIB.BASEBOARD_FAB2(SCH_1):P3V3_STBY
    2  IRQ_OOB_MGMT_RISER_ALERT_N      B  @BASEBOARD_FAB2_LIB.BASEBOARD_FAB2(SCH_1):IRQ_OOB_MGMT_RISER_ALERT_N

RES  I42  R2T30  [RES_0402-33.2,1%,1/16W,CHIP,G2A]
    2  FM_CPU_ERR0_LVT3_N      B  @BASEBOARD_FAB2_LIB.BASEBOARD_FAB2(SCH_1):FM_CPU_ERR0_LVT3_N
    1  FM_CPU_ERR0_LVT3_K_N      A  @BASEBOARD_FAB2_LIB.BASEBOARD_FAB2(SCH_1):FM_CPU_ERR0_LVT3_K_N

RES  I68  R2T31  [RES_0402-75,1.0%,1/16W,CHIP,G2A]
    1  H_CPU_ERR1_GTL_R_N      A  @BASEBOARD_FAB2_LIB.BASEBOARD_FAB2(SCH_1):H_CPU_ERR1_GTL_R_N
    2  H_CPU_ERR1_GTL_N      B  @BASEBOARD_FAB2_LIB.BASEBOARD_FAB2(SCH_1):H_CPU_ERR1_GTL_N

RES  I15  R2T32  [RES_0402-0.0,5%,1/16W,CHIP,G21A]
    2  H_CPU_ERR1_GTL_R_N      B  @BASEBOARD_FAB2_LIB.BASEBOARD_FAB2(SCH_1):H_CPU_ERR1_GTL_R_N
    1  H_CPU0_ERR1_G_N      A  @BASEBOARD_FAB2_LIB.BASEBOARD_FAB2(SCH_1):H_CPU0_ERR1_G_N

RES  I40  R2T33  [RES_0402-33.2,1%,1/16W,CHIP,G2A]
    2  FM_CPU_ERR1_LVT3_N      B  @BASEBOARD_FAB2_LIB.BASEBOARD_FAB2(SCH_1):FM_CPU_ERR1_LVT3_N
    1  FM_CPU_ERR1_LVT3_K_N      A  @BASEBOARD_FAB2_LIB.BASEBOARD_FAB2(SCH_1):FM_CPU_ERR1_LVT3_K_N

RES  I206  R2T34  [RES_0402-4.75K,1%,1/16W,CHIP,GA]
    1  P3V3_STBY          A  @BASEBOARD_FAB2_LIB.BASEBOARD_FAB2(SCH_1):P3V3_STBY
    2  FM_BMC_PWRBTN_OUT_N      B  @BASEBOARD_FAB2_LIB.BASEBOARD_FAB2(SCH_1):FM_BMC_PWRBTN_OUT_N

RES  I207  R2T35  [RES_0402-4.75K,1%,1/16W,CHIP,GA]
    2  RST_BMC_SYSRST_BTN_OUT_N      B  @BASEBOARD_FAB2_LIB.BASEBOARD_FAB2(SCH_1):RST_BMC_SYSRST_BTN_OUT_N
    1  P3V3_STBY          A  @BASEBOARD_FAB2_LIB.BASEBOARD_FAB2(SCH_1):P3V3_STBY

RES  I97  R2T36  [RES_0402-49.9,1%,1/16W,CHIP,G2A]
    1  PVCCIO_CPU0        A  @BASEBOARD_FAB2_LIB.BASEBOARD_FAB2(SCH_1):PVCCIO_CPU0
    2  P0V7_GTL2104_5_VREF      B  @BASEBOARD_FAB2_LIB.BASEBOARD_FAB2(SCH_1):P0V7_GTL2104_5_VREF

RES  I94  R2T37  [RES_0402-200.0,1%,1/16W,CHIP,GA]
    1  PVCCIO_CPU0        A  @BASEBOARD_FAB2_LIB.BASEBOARD_FAB2(SCH_1):PVCCIO_CPU0
    2  H_CPU_ERR2_G_R_N      B  @BASEBOARD_FAB2_LIB.BASEBOARD_FAB2(SCH_1):H_CPU_ERR2_G_R_N

RES  I39  R2T38  [RES_0402-33.2,1%,1/16W,CHIP,G2A]
    2  FM_CPU0_PROCHOT_LVT3_N      B  @BASEBOARD_FAB2_LIB.BASEBOARD_FAB2(SCH_1):FM_CPU0_PROCHOT_LVT3_N
    1  FM_CPU0_PROCHOT_LVT3_K_N      A  @BASEBOARD_FAB2_LIB.BASEBOARD_FAB2(SCH_1):FM_CPU0_PROCHOT_LVT3_K_N

RES  I98  R2T39  [RES_0402-100.0,1%,1/16W,CHIP,GA]
    1  P0V7_GTL2104_5_VREF      A  @BASEBOARD_FAB2_LIB.BASEBOARD_FAB2(SCH_1):P0V7_GTL2104_5_VREF
    2  GND                B  @BASEBOARD_FAB2_LIB.BASEBOARD_FAB2(SCH_1):GND

RES  I93  R2T40  [RES_0402-0.0,5%,1/16W,CHIP,G21A]
    2  H_CPU_ERR2_G_R_N      B  @BASEBOARD_FAB2_LIB.BASEBOARD_FAB2(SCH_1):H_CPU_ERR2_G_R_N
    1  H_CPU0_ERR2_G_N      A  @BASEBOARD_FAB2_LIB.BASEBOARD_FAB2(SCH_1):H_CPU0_ERR2_G_N

RES  I203  R2T41  [RES_0402-22.1,1.0%,1/16W,CHIP,A]
    1  IRQ_FORCE_NM_THROTTLE_N      A  @BASEBOARD_FAB2_LIB.BASEBOARD_FAB2(SCH_1):IRQ_FORCE_NM_THROTTLE_N
    2  FM_BMC_SYS_THROTTLE_R_N      B  @BASEBOARD_FAB2_LIB.BASEBOARD_FAB2(SCH_1):FM_BMC_SYS_THROTTLE_R_N

RES  I124  R2T42  [RES_0402-22.1,1.0%,1/16W,CHIP,A]
    1  CLK_50M_CKMNG_OCP_R      A  @BASEBOARD_FAB2_LIB.BASEBOARD_FAB2(SCH_1):CLK_50M_CKMNG_OCP_R
    2  CLK_50M_CKMNG_OCP      B  @BASEBOARD_FAB2_LIB.BASEBOARD_FAB2(SCH_1):CLK_50M_CKMNG_OCP

RES  I96  R2T43  [RES_0402-75,1.0%,1/16W,CHIP,G2A]
    1  H_CPU_ERR2_G_R_N      A  @BASEBOARD_FAB2_LIB.BASEBOARD_FAB2(SCH_1):H_CPU_ERR2_G_R_N
    2  H_CPU_ERR2_GTL_N      B  @BASEBOARD_FAB2_LIB.BASEBOARD_FAB2(SCH_1):H_CPU_ERR2_GTL_N

RES  I92  R2T44  [RES_0402-0.0,5%,1/16W,CHIP,G21A]
    2  H_CPU_ERR2_G_R_N      B  @BASEBOARD_FAB2_LIB.BASEBOARD_FAB2(SCH_1):H_CPU_ERR2_G_R_N
    1  H_CPU1_ERR2_G_N      A  @BASEBOARD_FAB2_LIB.BASEBOARD_FAB2(SCH_1):H_CPU1_ERR2_G_N

RES  I115  R2T45  [RES_0402-22.1,1.0%,1/16W,CHIP,A]
    1  RMII_BMC_PCH_SPRNGVLLE_TXD1_R      A  @BASEBOARD_FAB2_LIB.BASEBOARD_FAB2(SCH_1):RMII_BMC_PCH_SPRNGVLLE_TXD1_R
    2  RMII_BMC_PCH_SPRNGVLLE_TXD1      B  @BASEBOARD_FAB2_LIB.BASEBOARD_FAB2(SCH_1):RMII_BMC_PCH_SPRNGVLLE_TXD1

RES  I125  R2T46  [RES_0402-22.1,1.0%,1/16W,CHIP,A]
    1  CLK_50M_CKMNG_BMC_1_R      A  @BASEBOARD_FAB2_LIB.BASEBOARD_FAB2(SCH_1):CLK_50M_CKMNG_BMC_1_R
    2  CLK_50M_CKMNG_BMC_1      B  @BASEBOARD_FAB2_LIB.BASEBOARD_FAB2(SCH_1):CLK_50M_CKMNG_BMC_1

RES  I130  R2T47  [RES_0402-33.2,1%,1/16W,CHIP,G2A]
    1  CLK_25M_CPLD_R      A  @BASEBOARD_FAB2_LIB.BASEBOARD_FAB2(SCH_1):CLK_25M_CPLD_R
    2  CLK_25M_CPLD       B  @BASEBOARD_FAB2_LIB.BASEBOARD_FAB2(SCH_1):CLK_25M_CPLD

RES  I219  R2T49  [RES_0402-20.0,1%,1/16W,CHIP,G2A]
    1  SMB_BMC_PMBUS_STBY_LVC3_SDA_R      A  @BASEBOARD_FAB2_LIB.BASEBOARD_FAB2(SCH_1):SMB_BMC_PMBUS_STBY_LVC3_SDA_R
    2  SMB_BMC_PMBUS_STBY_LVC3_SDA      B  @BASEBOARD_FAB2_LIB.BASEBOARD_FAB2(SCH_1):SMB_BMC_PMBUS_STBY_LVC3_SDA

RES  I127  R2T50  [RES_0402-1.00K,1%,1/16W,CHIP,GA]
    1  PD_GTL2104_4_DIR      A  @BASEBOARD_FAB2_LIB.BASEBOARD_FAB2(SCH_1):PD_GTL2104_4_DIR
    2  GND                B  @BASEBOARD_FAB2_LIB.BASEBOARD_FAB2(SCH_1):GND

RES  I95  R2T52  [RES_0603-2.2,1.0%,1/10W,CHIP,GA]
    2  P3V3_STBY_MNG_RMII      B  @BASEBOARD_FAB2_LIB.BASEBOARD_FAB2(SCH_1):P3V3_STBY_MNG_RMII
    1  P3V3_STBY_MNG      A  @BASEBOARD_FAB2_LIB.BASEBOARD_FAB2(SCH_1):P3V3_STBY_MNG

RES  I83  R2T53  [RES_0402-665,1.0%,1/16W,CHIP,GA]
    2  SMB_BMC_PMBUS_STBY_LVC3_SDA      B  @BASEBOARD_FAB2_LIB.BASEBOARD_FAB2(SCH_1):SMB_BMC_PMBUS_STBY_LVC3_SDA
    1  P3V3_STBY          A  @BASEBOARD_FAB2_LIB.BASEBOARD_FAB2(SCH_1):P3V3_STBY

RES  I84  R2T54  [RES_0402-665,1.0%,1/16W,CHIP,GA]
    2  SMB_BMC_PMBUS_STBY_LVC3_SCL      B  @BASEBOARD_FAB2_LIB.BASEBOARD_FAB2(SCH_1):SMB_BMC_PMBUS_STBY_LVC3_SCL
    1  P3V3_STBY          A  @BASEBOARD_FAB2_LIB.BASEBOARD_FAB2(SCH_1):P3V3_STBY

RES  I116  R2T55  [RES_0402-20.0,1%,1/16W,CHIP,G2A]
    1  SMB_PMBUS_BMC_STBY_LVC3_SDA_R1      A  @BASEBOARD_FAB2_LIB.BASEBOARD_FAB2(SCH_1):SMB_PMBUS_BMC_STBY_LVC3_SDA_R1
    2  SMB_BMC_PMBUS_STBY_LVC3_SDA      B  @BASEBOARD_FAB2_LIB.BASEBOARD_FAB2(SCH_1):SMB_BMC_PMBUS_STBY_LVC3_SDA

RES  I160  R2T56  [RES_0402-20.0,1%,1/16W,CHIP,G2A]
    1  SMB_PMBUS_BMC_STBY_LVC3_SCL_R1      A  @BASEBOARD_FAB2_LIB.BASEBOARD_FAB2(SCH_1):SMB_PMBUS_BMC_STBY_LVC3_SCL_R1
    2  SMB_BMC_PMBUS_STBY_LVC3_SCL      B  @BASEBOARD_FAB2_LIB.BASEBOARD_FAB2(SCH_1):SMB_BMC_PMBUS_STBY_LVC3_SCL

RES  I88  R2T57  [RES_0402-0.0,5%,1/16W,EMPTY,G2A]
    1  H_CPU_ERR0_PCH_N      A  @BASEBOARD_FAB2_LIB.BASEBOARD_FAB2(SCH_1):H_CPU_ERR0_PCH_N
    2  H_CPU_ERR0_GTL_R_N      B  @BASEBOARD_FAB2_LIB.BASEBOARD_FAB2(SCH_1):H_CPU_ERR0_GTL_R_N

RES  I94  R2T58  [RES_0402-0.0,5%,1/16W,EMPTY,G2A]
    1  H_CPU_ERR0_PCH_N      A  @BASEBOARD_FAB2_LIB.BASEBOARD_FAB2(SCH_1):H_CPU_ERR0_PCH_N
    2  FM_CPU_ERR0_LVT3_K_N      B  @BASEBOARD_FAB2_LIB.BASEBOARD_FAB2(SCH_1):FM_CPU_ERR0_LVT3_K_N

RES  I107  R2T59  [RES_0402-0.0,5%,1/16W,EMPTY,G2A]
    2  H_CPU0_PROCHOT_G_PCH_N      B  @BASEBOARD_FAB2_LIB.BASEBOARD_FAB2(SCH_1):H_CPU0_PROCHOT_G_PCH_N
    1  H_CPU0_PROCHOT_G_N      A  @BASEBOARD_FAB2_LIB.BASEBOARD_FAB2(SCH_1):H_CPU0_PROCHOT_G_N

RES  I103  R2T60  [RES_0402-0.0,5%,1/16W,CHIP,G21A]
    2  H_CPU0_PROCHOT_G_R_N      B  @BASEBOARD_FAB2_LIB.BASEBOARD_FAB2(SCH_1):H_CPU0_PROCHOT_G_R_N
    1  H_CPU0_PROCHOT_G_N      A  @BASEBOARD_FAB2_LIB.BASEBOARD_FAB2(SCH_1):H_CPU0_PROCHOT_G_N

RES  I89  R2T61  [RES_0402-0.0,5%,1/16W,EMPTY,G2A]
    1  H_CPU_ERR1_PCH_N      A  @BASEBOARD_FAB2_LIB.BASEBOARD_FAB2(SCH_1):H_CPU_ERR1_PCH_N
    2  H_CPU_ERR1_GTL_R_N      B  @BASEBOARD_FAB2_LIB.BASEBOARD_FAB2(SCH_1):H_CPU_ERR1_GTL_R_N

RES  I93  R2T62  [RES_0402-0.0,5%,1/16W,EMPTY,G2A]
    1  H_CPU_ERR1_PCH_N      A  @BASEBOARD_FAB2_LIB.BASEBOARD_FAB2(SCH_1):H_CPU_ERR1_PCH_N
    2  FM_CPU_ERR1_LVT3_K_N      B  @BASEBOARD_FAB2_LIB.BASEBOARD_FAB2(SCH_1):FM_CPU_ERR1_LVT3_K_N

RES  I133  R2T63  [RES_0402-0.0,5%,1/16W,EMPTY,G2A]
    2  FM_CPU_ERR1_PCH_N      B  @BASEBOARD_FAB2_LIB.BASEBOARD_FAB2(SCH_1):FM_CPU_ERR1_PCH_N
    1  FM_CPU_ERR1_LVT3_N      A  @BASEBOARD_FAB2_LIB.BASEBOARD_FAB2(SCH_1):FM_CPU_ERR1_LVT3_N

RES  I121  R2T64  [RES_0402-0.0,5%,1/16W,CHIP,G21A]
    1  FM_CPU_ERR1_LVT3_N      A  @BASEBOARD_FAB2_LIB.BASEBOARD_FAB2(SCH_1):FM_CPU_ERR1_LVT3_N
    2  FM_CPU_ERR1_LVT3_BMC_N      B  @BASEBOARD_FAB2_LIB.BASEBOARD_FAB2(SCH_1):FM_CPU_ERR1_LVT3_BMC_N

RES  I111  R2T65  [RES_0402-0.0,5%,1/16W,CHIP,G21A]
    1  FM_CPU_ERR0_LVT3_R_N      A  @BASEBOARD_FAB2_LIB.BASEBOARD_FAB2(SCH_1):FM_CPU_ERR0_LVT3_R_N
    2  FM_CPU_ERR0_LVT3_K_N      B  @BASEBOARD_FAB2_LIB.BASEBOARD_FAB2(SCH_1):FM_CPU_ERR0_LVT3_K_N

RES  I112  R2T66  [RES_0402-0.0,5%,1/16W,CHIP,G21A]
    1  FM_CPU_ERR1_LVT3_R_N      A  @BASEBOARD_FAB2_LIB.BASEBOARD_FAB2(SCH_1):FM_CPU_ERR1_LVT3_R_N
    2  FM_CPU_ERR1_LVT3_K_N      B  @BASEBOARD_FAB2_LIB.BASEBOARD_FAB2(SCH_1):FM_CPU_ERR1_LVT3_K_N

RES  I113  R2T67  [RES_0402-0.0,5%,1/16W,CHIP,G21A]
    1  FM_CPU0_PROCHOT_LVT3_R_N      A  @BASEBOARD_FAB2_LIB.BASEBOARD_FAB2(SCH_1):FM_CPU0_PROCHOT_LVT3_R_N
    2  FM_CPU0_PROCHOT_LVT3_K_N      B  @BASEBOARD_FAB2_LIB.BASEBOARD_FAB2(SCH_1):FM_CPU0_PROCHOT_LVT3_K_N

RES  I102  R2T68  [RES_0402-0.0,5%,1/16W,CHIP,G21A]
    2  H_CPU1_PROCHOT_G_R_N      B  @BASEBOARD_FAB2_LIB.BASEBOARD_FAB2(SCH_1):H_CPU1_PROCHOT_G_R_N
    1  H_CPU1_PROCHOT_G_N      A  @BASEBOARD_FAB2_LIB.BASEBOARD_FAB2(SCH_1):H_CPU1_PROCHOT_G_N

RES  I108  R2T69  [RES_0402-0.0,5%,1/16W,EMPTY,G2A]
    2  H_CPU1_PROCHOT_G_PCH_N      B  @BASEBOARD_FAB2_LIB.BASEBOARD_FAB2(SCH_1):H_CPU1_PROCHOT_G_PCH_N
    1  H_CPU1_PROCHOT_G_N      A  @BASEBOARD_FAB2_LIB.BASEBOARD_FAB2(SCH_1):H_CPU1_PROCHOT_G_N

RES  I109  R2T71  [RES_0402-0.0,5%,1/16W,EMPTY,G2A]
    2  H_CPU0_PROCHOT_G_PCH_N      B  @BASEBOARD_FAB2_LIB.BASEBOARD_FAB2(SCH_1):H_CPU0_PROCHOT_G_PCH_N
    1  FM_CPU0_PROCHOT_LVT3_K_N      A  @BASEBOARD_FAB2_LIB.BASEBOARD_FAB2(SCH_1):FM_CPU0_PROCHOT_LVT3_K_N

RES  I143  R2T72  [RES_0402-150.0,1%,1/16W,CHIP,GA]
    1  PVCCIO_CPU0        A  @BASEBOARD_FAB2_LIB.BASEBOARD_FAB2(SCH_1):PVCCIO_CPU0
    2  H_CPU0_PROCHOT_G_N      B  @BASEBOARD_FAB2_LIB.BASEBOARD_FAB2(SCH_1):H_CPU0_PROCHOT_G_N

RES  I144  R2T73  [RES_0402-150.0,1%,1/16W,CHIP,GA]
    1  PVCCIO_CPU1        A  @BASEBOARD_FAB2_LIB.BASEBOARD_FAB2(SCH_1):PVCCIO_CPU1
    2  H_CPU1_PROCHOT_G_N      B  @BASEBOARD_FAB2_LIB.BASEBOARD_FAB2(SCH_1):H_CPU1_PROCHOT_G_N

RES  I218  R2U1   [RES_0402-20.0,1%,1/16W,CHIP,G2A]
    1  SMB_BMC_PMBUS_STBY_LVC3_SCL_R      A  @BASEBOARD_FAB2_LIB.BASEBOARD_FAB2(SCH_1):SMB_BMC_PMBUS_STBY_LVC3_SCL_R
    2  SMB_BMC_PMBUS_STBY_LVC3_SCL      B  @BASEBOARD_FAB2_LIB.BASEBOARD_FAB2(SCH_1):SMB_BMC_PMBUS_STBY_LVC3_SCL

RES  I265  R2U2   [RES_0402-4.75K,1%,1/16W,CHIP,GA]
    2  RST_PCH_SYSRST_BTN_OUT_N      B  @BASEBOARD_FAB2_LIB.BASEBOARD_FAB2(SCH_1):RST_PCH_SYSRST_BTN_OUT_N
    1  P3V3_STBY          A  @BASEBOARD_FAB2_LIB.BASEBOARD_FAB2(SCH_1):P3V3_STBY

RES  I98  R2U3   [RES_0402-665,1.0%,1/16W,CHIP,GA]
    2  SMB_LAN_STBY_LVC3_SCL      B  @BASEBOARD_FAB2_LIB.BASEBOARD_FAB2(SCH_1):SMB_LAN_STBY_LVC3_SCL
    1  P3V3_STBY          A  @BASEBOARD_FAB2_LIB.BASEBOARD_FAB2(SCH_1):P3V3_STBY

RES  I367  R2U4   [RES_0402-4.75K,1%,1/16W,CHIP,GA]
    1  P3V3_STBY          A  @BASEBOARD_FAB2_LIB.BASEBOARD_FAB2(SCH_1):P3V3_STBY
    2  FM_CPLD_BMC_PWRDN_N      B  @BASEBOARD_FAB2_LIB.BASEBOARD_FAB2(SCH_1):FM_CPLD_BMC_PWRDN_N

RES  I214  R2U5   [RES_0402-2.26K,1.0%,1/16W,CHIPA]
    2  SMB_OCP_FRU_STBY_LVC3_SCL_R      B  @BASEBOARD_FAB2_LIB.BASEBOARD_FAB2(SCH_1):SMB_OCP_FRU_STBY_LVC3_SCL_R
    1  P3V3_STBY          A  @BASEBOARD_FAB2_LIB.BASEBOARD_FAB2(SCH_1):P3V3_STBY

RES  I166  R2U6   [RES_0402-20.0,1%,1/16W,CHIP,G2A]
    1  SMB_LAN_STBY_LVC3_SCL_R1      A  @BASEBOARD_FAB2_LIB.BASEBOARD_FAB2(SCH_1):SMB_LAN_STBY_LVC3_SCL_R1
    2  SMB_LAN_STBY_LVC3_SCL      B  @BASEBOARD_FAB2_LIB.BASEBOARD_FAB2(SCH_1):SMB_LAN_STBY_LVC3_SCL

RES  I220  R2U7   [RES_0402-20.0,1%,1/16W,CHIP,G2A]
    1  SMB_OCP_FRU_STBY_LVC3_SCL_R      A  @BASEBOARD_FAB2_LIB.BASEBOARD_FAB2(SCH_1):SMB_OCP_FRU_STBY_LVC3_SCL_R
    2  SMB_OCP_FRU_STBY_LVC3_SCL      B  @BASEBOARD_FAB2_LIB.BASEBOARD_FAB2(SCH_1):SMB_OCP_FRU_STBY_LVC3_SCL

RES  I158  R2U8   [RES_0402-20.0,1%,1/16W,EMPTY,GA]
    2  SMB_OCP_FRU_STBY_LVC3_SCL      B  @BASEBOARD_FAB2_LIB.BASEBOARD_FAB2(SCH_1):SMB_OCP_FRU_STBY_LVC3_SCL
    1  SMB_LAN_STBY_LVC3_SCL      A  @BASEBOARD_FAB2_LIB.BASEBOARD_FAB2(SCH_1):SMB_LAN_STBY_LVC3_SCL

RES  I165  R2U9   [RES_0402-20.0,1%,1/16W,CHIP,G2A]
    1  SMB_LAN_STBY_LVC3_SDA_R1      A  @BASEBOARD_FAB2_LIB.BASEBOARD_FAB2(SCH_1):SMB_LAN_STBY_LVC3_SDA_R1
    2  SMB_LAN_STBY_LVC3_SDA      B  @BASEBOARD_FAB2_LIB.BASEBOARD_FAB2(SCH_1):SMB_LAN_STBY_LVC3_SDA

RES  I221  R2U10  [RES_0402-20.0,1%,1/16W,CHIP,G2A]
    1  SMB_OCP_FRU_STBY_LVC3_SDA_R      A  @BASEBOARD_FAB2_LIB.BASEBOARD_FAB2(SCH_1):SMB_OCP_FRU_STBY_LVC3_SDA_R
    2  SMB_OCP_FRU_STBY_LVC3_SDA      B  @BASEBOARD_FAB2_LIB.BASEBOARD_FAB2(SCH_1):SMB_OCP_FRU_STBY_LVC3_SDA

RES  I97  R2U11  [RES_0402-665,1.0%,1/16W,CHIP,GA]
    2  SMB_LAN_STBY_LVC3_SDA      B  @BASEBOARD_FAB2_LIB.BASEBOARD_FAB2(SCH_1):SMB_LAN_STBY_LVC3_SDA
    1  P3V3_STBY          A  @BASEBOARD_FAB2_LIB.BASEBOARD_FAB2(SCH_1):P3V3_STBY

RES  I159  R2U12  [RES_0402-20.0,1%,1/16W,EMPTY,GA]
    2  SMB_OCP_FRU_STBY_LVC3_SDA      B  @BASEBOARD_FAB2_LIB.BASEBOARD_FAB2(SCH_1):SMB_OCP_FRU_STBY_LVC3_SDA
    1  SMB_LAN_STBY_LVC3_SDA      A  @BASEBOARD_FAB2_LIB.BASEBOARD_FAB2(SCH_1):SMB_LAN_STBY_LVC3_SDA

RES  I216  R2U13  [RES_0402-2.26K,1.0%,1/16W,CHIPA]
    2  SMB_OCP_FRU_STBY_LVC3_SDA_R      B  @BASEBOARD_FAB2_LIB.BASEBOARD_FAB2(SCH_1):SMB_OCP_FRU_STBY_LVC3_SDA_R
    1  P3V3_STBY          A  @BASEBOARD_FAB2_LIB.BASEBOARD_FAB2(SCH_1):P3V3_STBY

RES  I466  R2U14  [RES_0402-0.0,5%,1/16W,EMPTY,G2A]
    1  P3E_CPU0_PE1_SS_R_RXP<0>      A  @BASEBOARD_FAB2_LIB.BASEBOARD_FAB2(SCH_1):P3E_CPU0_PE1_SS_R_RXP<0>
    2  P3E_CPU0_PE1_SS_RXP<0>      B  @BASEBOARD_FAB2_LIB.BASEBOARD_FAB2(SCH_1):P3E_CPU0_PE1_SS_RXP<0>

RES  I465  R2U15  [RES_0402-0.0,5%,1/16W,EMPTY,G2A]
    1  P3E_CPU0_PE1_SS_R_RXN<0>      A  @BASEBOARD_FAB2_LIB.BASEBOARD_FAB2(SCH_1):P3E_CPU0_PE1_SS_R_RXN<0>
    2  P3E_CPU0_PE1_SS_RXN<0>      B  @BASEBOARD_FAB2_LIB.BASEBOARD_FAB2(SCH_1):P3E_CPU0_PE1_SS_RXN<0>

RES  I467  R2U16  [RES_0402-0.0,5%,1/16W,EMPTY,G2A]
    1  P3E_CPU0_PE1_SS_R_RXP<1>      A  @BASEBOARD_FAB2_LIB.BASEBOARD_FAB2(SCH_1):P3E_CPU0_PE1_SS_R_RXP<1>
    2  P3E_CPU0_PE1_SS_RXP<1>      B  @BASEBOARD_FAB2_LIB.BASEBOARD_FAB2(SCH_1):P3E_CPU0_PE1_SS_RXP<1>

RES  I464  R2U17  [RES_0402-0.0,5%,1/16W,EMPTY,G2A]
    1  P3E_CPU0_PE1_SS_R_RXN<1>      A  @BASEBOARD_FAB2_LIB.BASEBOARD_FAB2(SCH_1):P3E_CPU0_PE1_SS_R_RXN<1>
    2  P3E_CPU0_PE1_SS_RXN<1>      B  @BASEBOARD_FAB2_LIB.BASEBOARD_FAB2(SCH_1):P3E_CPU0_PE1_SS_RXN<1>

RES  I468  R2U18  [RES_0402-0.0,5%,1/16W,EMPTY,G2A]
    1  P3E_CPU0_PE1_SS_R_RXP<2>      A  @BASEBOARD_FAB2_LIB.BASEBOARD_FAB2(SCH_1):P3E_CPU0_PE1_SS_R_RXP<2>
    2  P3E_CPU0_PE1_SS_RXP<2>      B  @BASEBOARD_FAB2_LIB.BASEBOARD_FAB2(SCH_1):P3E_CPU0_PE1_SS_RXP<2>

RES  I463  R2U19  [RES_0402-0.0,5%,1/16W,EMPTY,G2A]
    1  P3E_CPU0_PE1_SS_R_RXN<2>      A  @BASEBOARD_FAB2_LIB.BASEBOARD_FAB2(SCH_1):P3E_CPU0_PE1_SS_R_RXN<2>
    2  P3E_CPU0_PE1_SS_RXN<2>      B  @BASEBOARD_FAB2_LIB.BASEBOARD_FAB2(SCH_1):P3E_CPU0_PE1_SS_RXN<2>

RES  I469  R2U20  [RES_0402-0.0,5%,1/16W,EMPTY,G2A]
    1  P3E_CPU0_PE1_SS_R_RXP<3>      A  @BASEBOARD_FAB2_LIB.BASEBOARD_FAB2(SCH_1):P3E_CPU0_PE1_SS_R_RXP<3>
    2  P3E_CPU0_PE1_SS_RXP<3>      B  @BASEBOARD_FAB2_LIB.BASEBOARD_FAB2(SCH_1):P3E_CPU0_PE1_SS_RXP<3>

RES  I462  R2U21  [RES_0402-0.0,5%,1/16W,EMPTY,G2A]
    1  P3E_CPU0_PE1_SS_R_RXN<3>      A  @BASEBOARD_FAB2_LIB.BASEBOARD_FAB2(SCH_1):P3E_CPU0_PE1_SS_R_RXN<3>
    2  P3E_CPU0_PE1_SS_RXN<3>      B  @BASEBOARD_FAB2_LIB.BASEBOARD_FAB2(SCH_1):P3E_CPU0_PE1_SS_RXN<3>

RES  I470  R2U22  [RES_0402-0.0,5%,1/16W,EMPTY,G2A]
    1  P3E_CPU0_PE1_SS_R_RXP<4>      A  @BASEBOARD_FAB2_LIB.BASEBOARD_FAB2(SCH_1):P3E_CPU0_PE1_SS_R_RXP<4>
    2  P3E_CPU0_PE1_SS_RXP<4>      B  @BASEBOARD_FAB2_LIB.BASEBOARD_FAB2(SCH_1):P3E_CPU0_PE1_SS_RXP<4>

RES  I461  R2U23  [RES_0402-0.0,5%,1/16W,EMPTY,G2A]
    1  P3E_CPU0_PE1_SS_R_RXN<4>      A  @BASEBOARD_FAB2_LIB.BASEBOARD_FAB2(SCH_1):P3E_CPU0_PE1_SS_R_RXN<4>
    2  P3E_CPU0_PE1_SS_RXN<4>      B  @BASEBOARD_FAB2_LIB.BASEBOARD_FAB2(SCH_1):P3E_CPU0_PE1_SS_RXN<4>

RES  I471  R2U24  [RES_0402-0.0,5%,1/16W,EMPTY,G2A]
    1  P3E_CPU0_PE1_SS_R_RXP<5>      A  @BASEBOARD_FAB2_LIB.BASEBOARD_FAB2(SCH_1):P3E_CPU0_PE1_SS_R_RXP<5>
    2  P3E_CPU0_PE1_SS_RXP<5>      B  @BASEBOARD_FAB2_LIB.BASEBOARD_FAB2(SCH_1):P3E_CPU0_PE1_SS_RXP<5>

RES  I460  R2U25  [RES_0402-0.0,5%,1/16W,EMPTY,G2A]
    1  P3E_CPU0_PE1_SS_R_RXN<5>      A  @BASEBOARD_FAB2_LIB.BASEBOARD_FAB2(SCH_1):P3E_CPU0_PE1_SS_R_RXN<5>
    2  P3E_CPU0_PE1_SS_RXN<5>      B  @BASEBOARD_FAB2_LIB.BASEBOARD_FAB2(SCH_1):P3E_CPU0_PE1_SS_RXN<5>

RES  I472  R2U26  [RES_0402-0.0,5%,1/16W,EMPTY,G2A]
    1  P3E_CPU0_PE1_SS_R_RXP<6>      A  @BASEBOARD_FAB2_LIB.BASEBOARD_FAB2(SCH_1):P3E_CPU0_PE1_SS_R_RXP<6>
    2  P3E_CPU0_PE1_SS_RXP<6>      B  @BASEBOARD_FAB2_LIB.BASEBOARD_FAB2(SCH_1):P3E_CPU0_PE1_SS_RXP<6>

RES  I459  R2U27  [RES_0402-0.0,5%,1/16W,EMPTY,G2A]
    1  P3E_CPU0_PE1_SS_R_RXN<6>      A  @BASEBOARD_FAB2_LIB.BASEBOARD_FAB2(SCH_1):P3E_CPU0_PE1_SS_R_RXN<6>
    2  P3E_CPU0_PE1_SS_RXN<6>      B  @BASEBOARD_FAB2_LIB.BASEBOARD_FAB2(SCH_1):P3E_CPU0_PE1_SS_RXN<6>

RES  I473  R2U28  [RES_0402-0.0,5%,1/16W,EMPTY,G2A]
    1  P3E_CPU0_PE1_SS_R_RXP<7>      A  @BASEBOARD_FAB2_LIB.BASEBOARD_FAB2(SCH_1):P3E_CPU0_PE1_SS_R_RXP<7>
    2  P3E_CPU0_PE1_SS_RXP<7>      B  @BASEBOARD_FAB2_LIB.BASEBOARD_FAB2(SCH_1):P3E_CPU0_PE1_SS_RXP<7>

RES  I458  R2U29  [RES_0402-0.0,5%,1/16W,EMPTY,G2A]
    1  P3E_CPU0_PE1_SS_R_RXN<7>      A  @BASEBOARD_FAB2_LIB.BASEBOARD_FAB2(SCH_1):P3E_CPU0_PE1_SS_R_RXN<7>
    2  P3E_CPU0_PE1_SS_RXN<7>      B  @BASEBOARD_FAB2_LIB.BASEBOARD_FAB2(SCH_1):P3E_CPU0_PE1_SS_RXN<7>

RES  I76  R2U30  [RES_0402-4.75K,1%,1/16W,CHIP,GA]
    1  P3V3_STBY          A  @BASEBOARD_FAB2_LIB.BASEBOARD_FAB2(SCH_1):P3V3_STBY
    2  FM_UV_ADR_TRIGGER_EN      B  @BASEBOARD_FAB2_LIB.BASEBOARD_FAB2(SCH_1):FM_UV_ADR_TRIGGER_EN

RES  I330  R2U31  [RES_0402-20.0,1%,1/16W,CHIP,G2A]
    2  SMB_SLOTX24_STBY_LVC3_SDA_R2      B  @BASEBOARD_FAB2_LIB.BASEBOARD_FAB2(SCH_1):SMB_SLOTX24_STBY_LVC3_SDA_R2
    1  SMB_SLOTX24_BMC_STBY_LVC3_SDA      A  @BASEBOARD_FAB2_LIB.BASEBOARD_FAB2(SCH_1):SMB_SLOTX24_BMC_STBY_LVC3_SDA

RES  I339  R2U32  [RES_0402-20.0,1%,1/16W,CHIP,G2A]
    2  SMB_SLOTX24_STBY_LVC3_SCL_R2      B  @BASEBOARD_FAB2_LIB.BASEBOARD_FAB2(SCH_1):SMB_SLOTX24_STBY_LVC3_SCL_R2
    1  SMB_SLOTX24_BMC_STBY_LVC3_SCL      A  @BASEBOARD_FAB2_LIB.BASEBOARD_FAB2(SCH_1):SMB_SLOTX24_BMC_STBY_LVC3_SCL

RES  I231  R2U33  [RES_0402-20.0,1%,1/16W,CHIP,G2A]
    1  SMB_HOST_STBY_LVC3_SDA_R      A  @BASEBOARD_FAB2_LIB.BASEBOARD_FAB2(SCH_1):SMB_HOST_STBY_LVC3_SDA_R
    2  SMB_HOST_STBY_LVC3_SDA      B  @BASEBOARD_FAB2_LIB.BASEBOARD_FAB2(SCH_1):SMB_HOST_STBY_LVC3_SDA

RES  I230  R2U34  [RES_0402-20.0,1%,1/16W,CHIP,G2A]
    1  SMB_HOST_STBY_LVC3_SCL_R      A  @BASEBOARD_FAB2_LIB.BASEBOARD_FAB2(SCH_1):SMB_HOST_STBY_LVC3_SCL_R
    2  SMB_HOST_STBY_LVC3_SCL      B  @BASEBOARD_FAB2_LIB.BASEBOARD_FAB2(SCH_1):SMB_HOST_STBY_LVC3_SCL

RES  I320  R2U35  [RES_0402-20.0,1%,1/16W,EMPTY,GA]
    2  SMB_SLOTX24_STBY_LVC3_SDA_R2      B  @BASEBOARD_FAB2_LIB.BASEBOARD_FAB2(SCH_1):SMB_SLOTX24_STBY_LVC3_SDA_R2
    1  SMB_SLOTX24_PCH_STBY_LVC3_SDA      A  @BASEBOARD_FAB2_LIB.BASEBOARD_FAB2(SCH_1):SMB_SLOTX24_PCH_STBY_LVC3_SDA

RES  I340  R2U36  [RES_0402-20.0,1%,1/16W,EMPTY,GA]
    2  SMB_SLOTX24_STBY_LVC3_SCL_R2      B  @BASEBOARD_FAB2_LIB.BASEBOARD_FAB2(SCH_1):SMB_SLOTX24_STBY_LVC3_SCL_R2
    1  SMB_SLOTX24_PCH_STBY_LVC3_SCL      A  @BASEBOARD_FAB2_LIB.BASEBOARD_FAB2(SCH_1):SMB_SLOTX24_PCH_STBY_LVC3_SCL

RES  I173  R2U37  [RES_0402-0.0,5%,1/16W,CHIP,G21A]
    2  RST_PCIE_RISER1_PERST_R_N      B  @BASEBOARD_FAB2_LIB.BASEBOARD_FAB2(SCH_1):RST_PCIE_RISER1_PERST_R_N
    1  RST_PCIE_RISER1_PERST_N      A  @BASEBOARD_FAB2_LIB.BASEBOARD_FAB2(SCH_1):RST_PCIE_RISER1_PERST_N

RES  I80  R2U38  [RES_0402-665,1.0%,1/16W,CHIP,GA]
    2  SMB_SENSOR_STBY_LVC3_SCL      B  @BASEBOARD_FAB2_LIB.BASEBOARD_FAB2(SCH_1):SMB_SENSOR_STBY_LVC3_SCL
    1  P3V3_STBY          A  @BASEBOARD_FAB2_LIB.BASEBOARD_FAB2(SCH_1):P3V3_STBY

RES  I83  R2U39  [RES_0402-665,1.0%,1/16W,CHIP,GA]
    2  SMB_SENSOR_STBY_LVC3_SDA      B  @BASEBOARD_FAB2_LIB.BASEBOARD_FAB2(SCH_1):SMB_SENSOR_STBY_LVC3_SDA
    1  P3V3_STBY          A  @BASEBOARD_FAB2_LIB.BASEBOARD_FAB2(SCH_1):P3V3_STBY

RES  I53  R2U40  [RES_0402-150.0,1%,1/16W,CHIP,GA]
    1  PVCCIO_CPU0        A  @BASEBOARD_FAB2_LIB.BASEBOARD_FAB2(SCH_1):PVCCIO_CPU0
    2  H_CPU0_MEMABC_MEMHOT_G_N      B  @BASEBOARD_FAB2_LIB.BASEBOARD_FAB2(SCH_1):H_CPU0_MEMABC_MEMHOT_G_N

RES  I54  R2U41  [RES_0402-150.0,1%,1/16W,CHIP,GA]
    1  PVCCIO_CPU0        A  @BASEBOARD_FAB2_LIB.BASEBOARD_FAB2(SCH_1):PVCCIO_CPU0
    2  H_CPU0_MEMDEF_MEMHOT_G_N      B  @BASEBOARD_FAB2_LIB.BASEBOARD_FAB2(SCH_1):H_CPU0_MEMDEF_MEMHOT_G_N

RES  I99  R2U42  [RES_0402-221,1.0%,1/16W,CHIP,GA]
    2  FAN_PWM_OUT_SYS0_R      B  @BASEBOARD_FAB2_LIB.BASEBOARD_FAB2(SCH_1):FAN_PWM_OUT_SYS0_R
    1  FAN_PWM_OUT_SYS0_BUF      A  @BASEBOARD_FAB2_LIB.BASEBOARD_FAB2(SCH_1):FAN_PWM_OUT_SYS0_BUF

RES  I46  R2U43  [RES_0402-1.00K,1%,1/16W,CHIP,GA]
    1  P3V_BAT_SOURCE      A  @BASEBOARD_FAB2_LIB.BASEBOARD_FAB2(SCH_1):P3V_BAT_SOURCE
    2  A_P3V_BAT_R        B  @BASEBOARD_FAB2_LIB.BASEBOARD_FAB2(SCH_1):A_P3V_BAT_R

RES  I102  R2U44  [RES_0402-221,1.0%,1/16W,CHIP,GA]
    2  FAN_PWM_OUT_SYS1_R      B  @BASEBOARD_FAB2_LIB.BASEBOARD_FAB2(SCH_1):FAN_PWM_OUT_SYS1_R
    1  FAN_PWM_OUT_SYS1_BUF      A  @BASEBOARD_FAB2_LIB.BASEBOARD_FAB2(SCH_1):FAN_PWM_OUT_SYS1_BUF

RES  I102  R2U45  [RES_0402-0.0,5%,1/16W,EMPTY,G2A]
    2  H_CPU1_MEMKLM_MEMHOT_PCH_N      B  @BASEBOARD_FAB2_LIB.BASEBOARD_FAB2(SCH_1):H_CPU1_MEMKLM_MEMHOT_PCH_N
    1  H_CPU1_MEMKLM_MEMHOT_LVT3_N      A  @BASEBOARD_FAB2_LIB.BASEBOARD_FAB2(SCH_1):H_CPU1_MEMKLM_MEMHOT_LVT3_N

RES  I94  R2U46  [RES_0402-0.0,5%,1/16W,CHIP,G21A]
    1  H_CPU1_MEMKLM_MEMHOT_LVT3_N      A  @BASEBOARD_FAB2_LIB.BASEBOARD_FAB2(SCH_1):H_CPU1_MEMKLM_MEMHOT_LVT3_N
    2  H_CPU1_MEMKLM_MEMHOT_LVT3_BMC_N      B  @BASEBOARD_FAB2_LIB.BASEBOARD_FAB2(SCH_1):H_CPU1_MEMKLM_MEMHOT_LVT3_BMC_N

RES  I79  R2U47  [RES_0402-0.0,5%,1/16W,CHIP,G21A]
    1  H_CPU0_MEMABC_MEMHOT_LVT3_N      A  @BASEBOARD_FAB2_LIB.BASEBOARD_FAB2(SCH_1):H_CPU0_MEMABC_MEMHOT_LVT3_N
    2  H_CPU0_MEMABC_MEMHOT_LVT3_BMC_N      B  @BASEBOARD_FAB2_LIB.BASEBOARD_FAB2(SCH_1):H_CPU0_MEMABC_MEMHOT_LVT3_BMC_N

RES  I213  R2U48  [RES_0402-4.75K,1%,1/16W,CHIP,GA]
    1  P3V3_STBY          A  @BASEBOARD_FAB2_LIB.BASEBOARD_FAB2(SCH_1):P3V3_STBY
    2  FM_SLT_CFG2_R      B  @BASEBOARD_FAB2_LIB.BASEBOARD_FAB2(SCH_1):FM_SLT_CFG2_R

RES  I66  R2U49  [RES_0402-0.0,5%,1/16W,EMPTY,G2A]
    2  H_CPU0_MEMABC_MEMHOT_LVT3_K_N      B  @BASEBOARD_FAB2_LIB.BASEBOARD_FAB2(SCH_1):H_CPU0_MEMABC_MEMHOT_LVT3_K_N
    1  H_CPU0_MEMABC_MEMHOT_G_PCH_N      A  @BASEBOARD_FAB2_LIB.BASEBOARD_FAB2(SCH_1):H_CPU0_MEMABC_MEMHOT_G_PCH_N

RES  I215  R2U50  [RES_0402-0.0,5%,1/16W,EMPTY,G2A]
    1  FM_SLT_CFG2_R      A  @BASEBOARD_FAB2_LIB.BASEBOARD_FAB2(SCH_1):FM_SLT_CFG2_R
    2  FM_PWRBRK_SLOT_N      B  @BASEBOARD_FAB2_LIB.BASEBOARD_FAB2(SCH_1):FM_PWRBRK_SLOT_N

RES  I51  R2U51  [RES_0402-0.0,5%,1/16W,EMPTY,G2A]
    1  H_CPU0_MEMABC_MEMHOT_G_PCH_N      A  @BASEBOARD_FAB2_LIB.BASEBOARD_FAB2(SCH_1):H_CPU0_MEMABC_MEMHOT_G_PCH_N
    2  H_CPU0_MEMABC_MEMHOT_G_N      B  @BASEBOARD_FAB2_LIB.BASEBOARD_FAB2(SCH_1):H_CPU0_MEMABC_MEMHOT_G_N

RES  I27  R3B1   [RES_0402-221,1.0%,1/16W,CHIP,GA]
    2  SVID_ALERT0_CPU1_R_N      B  @BASEBOARD_FAB2_LIB.BASEBOARD_FAB2(SCH_1):SVID_ALERT0_CPU1_R_N
    1  SVID_ALERT0_CPU1_N      A  @BASEBOARD_FAB2_LIB.BASEBOARD_FAB2(SCH_1):SVID_ALERT0_CPU1_N

RES  I19  R3B2   [RES_0402-49.9,1%,1/16W,CHIP,G2A]
    1  SVID_ALERT0_CPU1_R_N      A  @BASEBOARD_FAB2_LIB.BASEBOARD_FAB2(SCH_1):SVID_ALERT0_CPU1_R_N
    2  PVCCIO_CPU1        B  @BASEBOARD_FAB2_LIB.BASEBOARD_FAB2(SCH_1):PVCCIO_CPU1

RES  I29  R3B3   [RES_0402-0.0,5%,1/16W,CHIP,G21A]
    2  SVID_DIO0_CPU1_R      B  @BASEBOARD_FAB2_LIB.BASEBOARD_FAB2(SCH_1):SVID_DIO0_CPU1_R
    1  SVID_DIO0_CPU1      A  @BASEBOARD_FAB2_LIB.BASEBOARD_FAB2(SCH_1):SVID_DIO0_CPU1

RES  I21  R3B4   [RES_0402-100.0,1%,1/16W,CHIP,GA]
    1  SVID_DIO0_CPU1_R      A  @BASEBOARD_FAB2_LIB.BASEBOARD_FAB2(SCH_1):SVID_DIO0_CPU1_R
    2  PVCCIO_CPU1        B  @BASEBOARD_FAB2_LIB.BASEBOARD_FAB2(SCH_1):PVCCIO_CPU1

RES  I28  R3B5   [RES_0402-0.0,5%,1/16W,CHIP,G21A]
    2  SVID_CLK0_CPU1_R      B  @BASEBOARD_FAB2_LIB.BASEBOARD_FAB2(SCH_1):SVID_CLK0_CPU1_R
    1  SVID_CLK0_CPU1      A  @BASEBOARD_FAB2_LIB.BASEBOARD_FAB2(SCH_1):SVID_CLK0_CPU1

RES  I116  R3D1   [RES_0402-90.9,1%,1/16W,CHIP,G2A]
    2  GND                B  @BASEBOARD_FAB2_LIB.BASEBOARD_FAB2(SCH_1):GND
    1  A_CPU1_KLM_RCOMP0      A  @BASEBOARD_FAB2_LIB.BASEBOARD_FAB2(SCH_1):A_CPU1_KLM_RCOMP0

RES  I117  R3D2   [RES_0402-90.9,1%,1/16W,CHIP,G2A]
    2  GND                B  @BASEBOARD_FAB2_LIB.BASEBOARD_FAB2(SCH_1):GND
    1  A_CPU1_KLM_RCOMP1      A  @BASEBOARD_FAB2_LIB.BASEBOARD_FAB2(SCH_1):A_CPU1_KLM_RCOMP1

RES  I118  R3D3   [RES_0402-100.0,1%,1/16W,CHIP,GA]
    2  GND                B  @BASEBOARD_FAB2_LIB.BASEBOARD_FAB2(SCH_1):GND
    1  A_CPU1_KLM_RCOMP2      A  @BASEBOARD_FAB2_LIB.BASEBOARD_FAB2(SCH_1):A_CPU1_KLM_RCOMP2

RES  I155  R3D4   [RES_0402-49.9,1%,1/16W,CHIP,G2A]
    2  GND                B  @BASEBOARD_FAB2_LIB.BASEBOARD_FAB2(SCH_1):GND
    1  A_CPU1_MCP01_RBIAS      A  @BASEBOARD_FAB2_LIB.BASEBOARD_FAB2(SCH_1):A_CPU1_MCP01_RBIAS

RES  I88  R3D9   [RES_0402-49.9,1%,1/16W,CHIP,G2A]
    1  PD_CPU1_TEST12      A  @BASEBOARD_FAB2_LIB.BASEBOARD_FAB2(SCH_1):PD_CPU1_TEST12
    2  GND                B  @BASEBOARD_FAB2_LIB.BASEBOARD_FAB2(SCH_1):GND

RES  I11  R3D12  [RES_0402-240,1.0%,1/16W,CHIP,GA]
    2  PD_CPU1_TXT_PLTEN      B  @BASEBOARD_FAB2_LIB.BASEBOARD_FAB2(SCH_1):PD_CPU1_TXT_PLTEN
    1  GND                A  @BASEBOARD_FAB2_LIB.BASEBOARD_FAB2(SCH_1):GND

RES  I12  R3D13  [RES_0402-240,1.0%,1/16W,EMPTY,A]
    2  PD_CPU1_BIST_ENABLE      B  @BASEBOARD_FAB2_LIB.BASEBOARD_FAB2(SCH_1):PD_CPU1_BIST_ENABLE
    1  GND                A  @BASEBOARD_FAB2_LIB.BASEBOARD_FAB2(SCH_1):GND

RES  I21  R3D14  [RES_0603-2.2,1.0%,1/10W,CHIP,GA]
    2  P3V3_DB1200_A      B  @BASEBOARD_FAB2_LIB.BASEBOARD_FAB2(SCH_1):P3V3_DB1200_A
    1  P3V3_DB1200        A  @BASEBOARD_FAB2_LIB.BASEBOARD_FAB2(SCH_1):P3V3_DB1200

RES  I26  R3D15  [RES_0402-49.9,1%,1/16W,CHIP,G2A]
    2  PWRGD_CPU1_G       B  @BASEBOARD_FAB2_LIB.BASEBOARD_FAB2(SCH_1):PWRGD_CPU1_G
    1  PVCCIO_CPU1        A  @BASEBOARD_FAB2_LIB.BASEBOARD_FAB2(SCH_1):PVCCIO_CPU1

RES  I24  R3D16  [RES_0402-240,1.0%,1/16W,EMPTY,A]
    1  PVCCIO_CPU1        A  @BASEBOARD_FAB2_LIB.BASEBOARD_FAB2(SCH_1):PVCCIO_CPU1
    2  H_CPU1_BMCINIT      B  @BASEBOARD_FAB2_LIB.BASEBOARD_FAB2(SCH_1):H_CPU1_BMCINIT

RES  I60  R3D17  [RES_0402-240,1.0%,1/16W,EMPTY,A]
    1  PVCCIO_CPU1        A  @BASEBOARD_FAB2_LIB.BASEBOARD_FAB2(SCH_1):PVCCIO_CPU1
    2  PU_CPU1_SOCKET_ID_1      B  @BASEBOARD_FAB2_LIB.BASEBOARD_FAB2(SCH_1):PU_CPU1_SOCKET_ID_1

RES  I33  R3D18  [RES_0402-0.0,5%,1/16W,CHIP,G21A]
    2  H_CPU1_FAST_WAKE_N      B  @BASEBOARD_FAB2_LIB.BASEBOARD_FAB2(SCH_1):H_CPU1_FAST_WAKE_N
    1  H_CPU0_FAST_WAKE_N      A  @BASEBOARD_FAB2_LIB.BASEBOARD_FAB2(SCH_1):H_CPU0_FAST_WAKE_N

RES  I125  R3D19  [RES_0402-49.9,1%,1/16W,CHIP,G2A]
    2  GND                B  @BASEBOARD_FAB2_LIB.BASEBOARD_FAB2(SCH_1):GND
    1  A_CPU1_UPI01_RBIAS      A  @BASEBOARD_FAB2_LIB.BASEBOARD_FAB2(SCH_1):A_CPU1_UPI01_RBIAS

RES  I25  R3D20  [RES_0402-49.9,1%,1/16W,CHIP,G2A]
    2  RST_CPU1_G_N       B  @BASEBOARD_FAB2_LIB.BASEBOARD_FAB2(SCH_1):RST_CPU1_G_N
    1  PVCCIO_CPU1        A  @BASEBOARD_FAB2_LIB.BASEBOARD_FAB2(SCH_1):PVCCIO_CPU1

RES  I30  R3D21  [RES_0402-64.9,1.0%,1/16W,CHIP,A]
    2  PWRGD_CPU1_DRAMPWROK_GHJ_G      B  @BASEBOARD_FAB2_LIB.BASEBOARD_FAB2(SCH_1):PWRGD_CPU1_DRAMPWROK_GHJ_G
    1  PVDDQ_GHJ          A  @BASEBOARD_FAB2_LIB.BASEBOARD_FAB2(SCH_1):PVDDQ_GHJ

RES  I17  R3D22  [RES_0402-240,1.0%,1/16W,EMPTY,A]
    1  PVCCIO_CPU1        A  @BASEBOARD_FAB2_LIB.BASEBOARD_FAB2(SCH_1):PVCCIO_CPU1
    2  PU_CPU1_FRMAGENT      B  @BASEBOARD_FAB2_LIB.BASEBOARD_FAB2(SCH_1):PU_CPU1_FRMAGENT

RES  I25  R3D23  [RES_0402-240,1.0%,1/16W,EMPTY,A]
    1  PVCCIO_CPU1        A  @BASEBOARD_FAB2_LIB.BASEBOARD_FAB2(SCH_1):PVCCIO_CPU1
    2  PU_CPU1_TXT_AGENT      B  @BASEBOARD_FAB2_LIB.BASEBOARD_FAB2(SCH_1):PU_CPU1_TXT_AGENT

RES  I59  R3D24  [RES_0402-240,1.0%,1/16W,CHIP,GA]
    1  PVCCIO_CPU1        A  @BASEBOARD_FAB2_LIB.BASEBOARD_FAB2(SCH_1):PVCCIO_CPU1
    2  PU_CPU1_SOCKET_ID_0      B  @BASEBOARD_FAB2_LIB.BASEBOARD_FAB2(SCH_1):PU_CPU1_SOCKET_ID_0

RES  I66  R3D25  [RES_0402-240,1.0%,1/16W,EMPTY,A]
    1  PVCCIO_CPU1        A  @BASEBOARD_FAB2_LIB.BASEBOARD_FAB2(SCH_1):PVCCIO_CPU1
    2  PU_CPU1_EAR_N      B  @BASEBOARD_FAB2_LIB.BASEBOARD_FAB2(SCH_1):PU_CPU1_EAR_N

RES  I28  R3D26  [RES_0402-240,1.0%,1/16W,EMPTY,A]
    1  PVCCIO_CPU1        A  @BASEBOARD_FAB2_LIB.BASEBOARD_FAB2(SCH_1):PVCCIO_CPU1
    2  PU_CPU1_SAFE_MODE_BOOT      B  @BASEBOARD_FAB2_LIB.BASEBOARD_FAB2(SCH_1):PU_CPU1_SAFE_MODE_BOOT

RES  I43  R3D27  [RES_0402-249,0.1%,1/16W,CHIP,GA]
    1  VSENSE_PMAX_CPU1      A  @BASEBOARD_FAB2_LIB.BASEBOARD_FAB2(SCH_1):VSENSE_PMAX_CPU1
    2  GND                B  @BASEBOARD_FAB2_LIB.BASEBOARD_FAB2(SCH_1):GND

RES  I101  R3D28  [RES_0402-100.0,1%,1/16W,CHIP,GA]
    1  VSENSE_PVCCIO_CPU1_AVSN      A  @BASEBOARD_FAB2_LIB.BASEBOARD_FAB2(SCH_1):VSENSE_PVCCIO_CPU1_AVSN
    2  GND                B  @BASEBOARD_FAB2_LIB.BASEBOARD_FAB2(SCH_1):GND

RES  I300  R3D31  [RES_0402-0.0,5%,1/16W,EMPTY,G2A]
    2  H_CPU1_BMCINIT      B  @BASEBOARD_FAB2_LIB.BASEBOARD_FAB2(SCH_1):H_CPU1_BMCINIT
    1  FM_CPU_BMC_INIT      A  @BASEBOARD_FAB2_LIB.BASEBOARD_FAB2(SCH_1):FM_CPU_BMC_INIT

RES  I53  R3D32  [RES_0402-10.0,1%,1/16W,EMPTY,GA]
    2  VSENSE_PMAX_CPU1      B  @BASEBOARD_FAB2_LIB.BASEBOARD_FAB2(SCH_1):VSENSE_PMAX_CPU1
    1  PVCCIO_CPU1        A  @BASEBOARD_FAB2_LIB.BASEBOARD_FAB2(SCH_1):PVCCIO_CPU1

RES  I105  R3E1   [RES_0402-100.0,1%,1/16W,CHIP,GA]
    1  VSENSE_PVCCIO_CPU1_AVSP      A  @BASEBOARD_FAB2_LIB.BASEBOARD_FAB2(SCH_1):VSENSE_PVCCIO_CPU1_AVSP
    2  PVCCIO_CPU1        B  @BASEBOARD_FAB2_LIB.BASEBOARD_FAB2(SCH_1):PVCCIO_CPU1

RES  I51  R3F1   [RES_0402-0.0,5%,1/16W,EMPTY,G2A]
    1  CLK_322M_156M_CPU1_OSC_VRM_DN      A  @BASEBOARD_FAB2_LIB.BASEBOARD_FAB2(SCH_1):CLK_322M_156M_CPU1_OSC_VRM_DN
    2  CLK_156M_OSC_CPU1_HFI_DN      B  @BASEBOARD_FAB2_LIB.BASEBOARD_FAB2(SCH_1):CLK_156M_OSC_CPU1_HFI_DN

RES  I69  R3F2   [RES_0402-0.0,5%,1/16W,CHIP,G21A]
    2  CLK_156M_OSC_CPU1_HFI_DN      B  @BASEBOARD_FAB2_LIB.BASEBOARD_FAB2(SCH_1):CLK_156M_OSC_CPU1_HFI_DN
    1  CLK_156M_OSC_BRD_CPU1_DN      A  @BASEBOARD_FAB2_LIB.BASEBOARD_FAB2(SCH_1):CLK_156M_OSC_BRD_CPU1_DN

RES  I53  R3F3   [RES_0402-0.0,5%,1/16W,EMPTY,G2A]
    1  CLK_322M_156M_CPU1_OSC_VRM_DP      A  @BASEBOARD_FAB2_LIB.BASEBOARD_FAB2(SCH_1):CLK_322M_156M_CPU1_OSC_VRM_DP
    2  CLK_156M_OSC_CPU1_HFI_DP      B  @BASEBOARD_FAB2_LIB.BASEBOARD_FAB2(SCH_1):CLK_156M_OSC_CPU1_HFI_DP

RES  I70  R3F4   [RES_0402-0.0,5%,1/16W,CHIP,G21A]
    2  CLK_156M_OSC_CPU1_HFI_DP      B  @BASEBOARD_FAB2_LIB.BASEBOARD_FAB2(SCH_1):CLK_156M_OSC_CPU1_HFI_DP
    1  CLK_156M_OSC_BRD_CPU1_DP      A  @BASEBOARD_FAB2_LIB.BASEBOARD_FAB2(SCH_1):CLK_156M_OSC_BRD_CPU1_DP

RES  I84  R3F5   [RES_0402-0.0,5%,1/16W,EMPTY,G2A]
    2  CLK_322M_OSC_CPU1_RC_DN      B  @BASEBOARD_FAB2_LIB.BASEBOARD_FAB2(SCH_1):CLK_322M_OSC_CPU1_RC_DN
    1  CLK_322M_156M_CPU1_OSC_VRM_DN      A  @BASEBOARD_FAB2_LIB.BASEBOARD_FAB2(SCH_1):CLK_322M_156M_CPU1_OSC_VRM_DN

RES  I88  R3F6   [RES_0402-0.0,5%,1/16W,EMPTY,G2A]
    2  CLK_322M_OSC_CPU1_RC_DP      B  @BASEBOARD_FAB2_LIB.BASEBOARD_FAB2(SCH_1):CLK_322M_OSC_CPU1_RC_DP
    1  CLK_322M_156M_CPU1_OSC_VRM_DP      A  @BASEBOARD_FAB2_LIB.BASEBOARD_FAB2(SCH_1):CLK_322M_156M_CPU1_OSC_VRM_DP

RES  I14  R3L1   [RES_0402-1.0,1%,1/16W,CHIP,G21A]
    1  VR_PVNN_PCH_PH1_VCIN      A  @BASEBOARD_FAB2_LIB.BASEBOARD_FAB2(SCH_1):VR_PVNN_PCH_PH1_VCIN
    2  P5V_STBY           B  @BASEBOARD_FAB2_LIB.BASEBOARD_FAB2(SCH_1):P5V_STBY

RES  I41  R3L4   [RES_0402-1.0,1%,1/16W,CHIP,G21A]
    1  VR_P1V05_PCH_STBY_PH1_VCIN      A  @BASEBOARD_FAB2_LIB.BASEBOARD_FAB2(SCH_1):VR_P1V05_PCH_STBY_PH1_VCIN
    2  P5V_STBY           B  @BASEBOARD_FAB2_LIB.BASEBOARD_FAB2(SCH_1):P5V_STBY

RES  I52  R3L6   [RES_0402-1.0,1%,1/16W,CHIP,G21A]
    1  VR_PVDDQ_DEF_PH1_VCIN      A  @BASEBOARD_FAB2_LIB.BASEBOARD_FAB2(SCH_1):VR_PVDDQ_DEF_PH1_VCIN
    2  P5V_STBY           B  @BASEBOARD_FAB2_LIB.BASEBOARD_FAB2(SCH_1):P5V_STBY

RES  I76  R3L8   [RES_0402-1.0,1%,1/16W,CHIP,G21A]
    1  VR_PVDDQ_DEF_PH2_VCIN      A  @BASEBOARD_FAB2_LIB.BASEBOARD_FAB2(SCH_1):VR_PVDDQ_DEF_PH2_VCIN
    2  P5V_STBY           B  @BASEBOARD_FAB2_LIB.BASEBOARD_FAB2(SCH_1):P5V_STBY

RES  I57  R3L9   [RES_0402-0.0,5%,1/16W,CHIP,G21A]
    1  VR_PVDDQ_DEF_VD12      A  @BASEBOARD_FAB2_LIB.BASEBOARD_FAB2(SCH_1):VR_PVDDQ_DEF_VD12
    2  VR_PVDDQ_DEF_AIREF1      B  @BASEBOARD_FAB2_LIB.BASEBOARD_FAB2(SCH_1):VR_PVDDQ_DEF_AIREF1

RES  I50  R3L10  [RES_0402-0.0,5%,1/16W,CHIP,G21A]
    1  VR_PVDDQ_DEF_VD12      A  @BASEBOARD_FAB2_LIB.BASEBOARD_FAB2(SCH_1):VR_PVDDQ_DEF_VD12
    2  VR_PVDDQ_DEF_AIREF2      B  @BASEBOARD_FAB2_LIB.BASEBOARD_FAB2(SCH_1):VR_PVDDQ_DEF_AIREF2

RES  I7   R3L11  [RES_0402-100.0,1%,1/16W,EMPTY,A]
    2  SVID_DIO1_CPU0_R      B  @BASEBOARD_FAB2_LIB.BASEBOARD_FAB2(SCH_1):SVID_DIO1_CPU0_R
    1  PVCCIO_CPU0        A  @BASEBOARD_FAB2_LIB.BASEBOARD_FAB2(SCH_1):PVCCIO_CPU0

RES  I53  R3L12  [RES_0402-100.0K,1%,1/16W,CHIP,B]
    2  VR_PVDDQ_DEF_VINSEN      B  @BASEBOARD_FAB2_LIB.BASEBOARD_FAB2(SCH_1):VR_PVDDQ_DEF_VINSEN
    1  VR_FET_SW_P12V_STBY_PVDDQ_DEF      A  @BASEBOARD_FAB2_LIB.BASEBOARD_FAB2(SCH_1):VR_FET_SW_P12V_STBY_PVDDQ_DEF

RES  I47  R3L13  [RES_0402-49.9,1%,1/16W,CHIP,G2A]
    2  SVID_CLK1_CPU0_R      B  @BASEBOARD_FAB2_LIB.BASEBOARD_FAB2(SCH_1):SVID_CLK1_CPU0_R
    1  PVCCIO_CPU0        A  @BASEBOARD_FAB2_LIB.BASEBOARD_FAB2(SCH_1):PVCCIO_CPU0

RES  I120  R3L14  [RES_0402-68.1K,1%,1/16W,EMPTY,A]
    1  VR_P1V05_PCH_STBY_OCSET      A  @BASEBOARD_FAB2_LIB.BASEBOARD_FAB2(SCH_1):VR_P1V05_PCH_STBY_OCSET
    2  GND                B  @BASEBOARD_FAB2_LIB.BASEBOARD_FAB2(SCH_1):GND

RES  I118  R3L15  [RES_0402-68.1K,1%,1/16W,EMPTY,A]
    1  VR_PVNN_PCH_STBY_OCSET      A  @BASEBOARD_FAB2_LIB.BASEBOARD_FAB2(SCH_1):VR_PVNN_PCH_STBY_OCSET
    2  GND                B  @BASEBOARD_FAB2_LIB.BASEBOARD_FAB2(SCH_1):GND

RES  I34  R3M1   [RES_0402-0.0,5%,1/16W,CHIP,G21A]
    2  VR_PVDDQ_DEF_VDD      B  @BASEBOARD_FAB2_LIB.BASEBOARD_FAB2(SCH_1):VR_PVDDQ_DEF_VDD
    1  P3V3_STBY          A  @BASEBOARD_FAB2_LIB.BASEBOARD_FAB2(SCH_1):P3V3_STBY

RES  I11  R3M3   [RES_0402-22.1,1.0%,1/16W,CHIP,A]
    1  PWRGD_PVDDQ_DEF_R      A  @BASEBOARD_FAB2_LIB.BASEBOARD_FAB2(SCH_1):PWRGD_PVDDQ_DEF_R
    2  PWRGD_PVDDQ_DEF      B  @BASEBOARD_FAB2_LIB.BASEBOARD_FAB2(SCH_1):PWRGD_PVDDQ_DEF

RES  I35  R3M5   [RES_0402-100.0K,1%,1/16W,EMPTYA]
    2  VR_PVDDQ_DEF_VREN      B  @BASEBOARD_FAB2_LIB.BASEBOARD_FAB2(SCH_1):VR_PVDDQ_DEF_VREN
    1  P3V3_STBY          A  @BASEBOARD_FAB2_LIB.BASEBOARD_FAB2(SCH_1):P3V3_STBY

RES  I59  R3M6   [RES_0402-0.0,5%,1/16W,CHIP,G21A]
    2  VR_PVDDQ_DEF_VREN      B  @BASEBOARD_FAB2_LIB.BASEBOARD_FAB2(SCH_1):VR_PVDDQ_DEF_VREN
    1  FM_PVDDQ_DEF_EN      A  @BASEBOARD_FAB2_LIB.BASEBOARD_FAB2(SCH_1):FM_PVDDQ_DEF_EN

RES  I235  R3M8   [RES_0402-100.0K,1%,1/16W,CHIP,A]
    1  P2E_SSB_BMC_RX_C_DP      A  @BASEBOARD_FAB2_LIB.BASEBOARD_FAB2(SCH_1):P2E_SSB_BMC_RX_C_DP
    2  GND                B  @BASEBOARD_FAB2_LIB.BASEBOARD_FAB2(SCH_1):GND

RES  I234  R3M9   [RES_0402-100.0K,1%,1/16W,CHIP,A]
    1  P2E_SSB_BMC_RX_C_DN      A  @BASEBOARD_FAB2_LIB.BASEBOARD_FAB2(SCH_1):P2E_SSB_BMC_RX_C_DN
    2  GND                B  @BASEBOARD_FAB2_LIB.BASEBOARD_FAB2(SCH_1):GND

RES  I85  R3M10  [RES_0402-1.00K,1%,1/16W,CHIP,GA]
    1  XDP_PCH_CPU_TCK0      A  @BASEBOARD_FAB2_LIB.BASEBOARD_FAB2(SCH_1):XDP_PCH_CPU_TCK0
    2  GND                B  @BASEBOARD_FAB2_LIB.BASEBOARD_FAB2(SCH_1):GND

RES  I108  R3M11  [RES_0402-100.0,1%,1/16W,CHIP,GA]
    1  A_PCIE_RCOMP_P      A  @BASEBOARD_FAB2_LIB.BASEBOARD_FAB2(SCH_1):A_PCIE_RCOMP_P
    2  A_PCIE_RCOMP_N      B  @BASEBOARD_FAB2_LIB.BASEBOARD_FAB2(SCH_1):A_PCIE_RCOMP_N

RES  I181  R3M12  [RES_0402-100.0,1%,1/16W,CHIP,GA]
    1  A_PCIEUP_RCOMP_P      A  @BASEBOARD_FAB2_LIB.BASEBOARD_FAB2(SCH_1):A_PCIEUP_RCOMP_P
    2  A_PCIEUP_RCOMP_N      B  @BASEBOARD_FAB2_LIB.BASEBOARD_FAB2(SCH_1):A_PCIEUP_RCOMP_N

RES  I149  R3N1   [RES_0402-169,1.0%,1/16W,CHIP,GA]
    2  GND                B  @BASEBOARD_FAB2_LIB.BASEBOARD_FAB2(SCH_1):GND
    1  A_PCH_XCLK_BIASREF      A  @BASEBOARD_FAB2_LIB.BASEBOARD_FAB2(SCH_1):A_PCH_XCLK_BIASREF

RES  I72  R3N2   [RES_0402-4.75K,1%,1/16W,EMPTY,A]
    1  P3V3_STBY          A  @BASEBOARD_FAB2_LIB.BASEBOARD_FAB2(SCH_1):P3V3_STBY
    2  FM_FLASH_DESC_OVERRIDE      B  @BASEBOARD_FAB2_LIB.BASEBOARD_FAB2(SCH_1):FM_FLASH_DESC_OVERRIDE

RES  I120  R3N3   [RES_0402-2.0K,1%,1/16W,CHIP,G2A]
    2  PWRGD_PCH_PWROK      B  @BASEBOARD_FAB2_LIB.BASEBOARD_FAB2(SCH_1):PWRGD_PCH_PWROK
    1  GND                A  @BASEBOARD_FAB2_LIB.BASEBOARD_FAB2(SCH_1):GND

RES  I19  R3N4   [RES_0402-20.0K,1%,1/16W,CHIP,GA]
    2  RST_SRTCRST_N      B  @BASEBOARD_FAB2_LIB.BASEBOARD_FAB2(SCH_1):RST_SRTCRST_N
    1  P3V3_RTC_STBY      A  @BASEBOARD_FAB2_LIB.BASEBOARD_FAB2(SCH_1):P3V3_RTC_STBY

RES  I32  R3N7   [RES_0402-1.0,1%,1/16W,CHIP,G21A]
    1  VR_PVCCIO_CPU0_PH1_VCIN      A  @BASEBOARD_FAB2_LIB.BASEBOARD_FAB2(SCH_1):VR_PVCCIO_CPU0_PH1_VCIN
    2  P5V_STBY           B  @BASEBOARD_FAB2_LIB.BASEBOARD_FAB2(SCH_1):P5V_STBY

RES  I66  R3N9   [RES_0402-10.0,1%,1/16W,CHIP,G2A]
    2  H_PM_SYNC_GTL      B  @BASEBOARD_FAB2_LIB.BASEBOARD_FAB2(SCH_1):H_PM_SYNC_GTL
    1  H_PM_SYNC1_GTL_R      A  @BASEBOARD_FAB2_LIB.BASEBOARD_FAB2(SCH_1):H_PM_SYNC1_GTL_R

RES  I37  R3N10  [RES_0402-10.0K,1%,1/16W,CHIP,GA]
    1  P3V3_STBY          A  @BASEBOARD_FAB2_LIB.BASEBOARD_FAB2(SCH_1):P3V3_STBY
    2  FM_INTRUDER_HDR_PCH_N      B  @BASEBOARD_FAB2_LIB.BASEBOARD_FAB2(SCH_1):FM_INTRUDER_HDR_PCH_N

RES  I344  R3N11  [RES_0402-4.75K,1%,1/16W,CHIP,GA]
    1  P3V3_STBY          A  @BASEBOARD_FAB2_LIB.BASEBOARD_FAB2(SCH_1):P3V3_STBY
    2  FM_MP_PS_REDUNDANT_LOST_N      B  @BASEBOARD_FAB2_LIB.BASEBOARD_FAB2(SCH_1):FM_MP_PS_REDUNDANT_LOST_N

RES  I342  R3N12  [RES_0402-4.75K,1%,1/16W,CHIP,GA]
    1  P3V3_STBY          A  @BASEBOARD_FAB2_LIB.BASEBOARD_FAB2(SCH_1):P3V3_STBY
    2  FM_MP_PS_FAIL_N      B  @BASEBOARD_FAB2_LIB.BASEBOARD_FAB2(SCH_1):FM_MP_PS_FAIL_N

RES  I71  R3N13  [RES_0402-4.75K,1%,1/16W,CHIP,GA]
    1  P3V3_STBY          A  @BASEBOARD_FAB2_LIB.BASEBOARD_FAB2(SCH_1):P3V3_STBY
    2  IRQ_LVC3_WAKE_N      B  @BASEBOARD_FAB2_LIB.BASEBOARD_FAB2(SCH_1):IRQ_LVC3_WAKE_N

RES  I67  R3N14  [RES_0402-49.9,1%,1/16W,EMPTY,GA]
    1  H_PM_SYNC_GTL      A  @BASEBOARD_FAB2_LIB.BASEBOARD_FAB2(SCH_1):H_PM_SYNC_GTL
    2  GND                B  @BASEBOARD_FAB2_LIB.BASEBOARD_FAB2(SCH_1):GND

RES  I318  R3N15  [RES_0402-1.00K,1%,1/16W,CHIP,GA]
    1  P1V05_PCH_STBY      A  @BASEBOARD_FAB2_LIB.BASEBOARD_FAB2(SCH_1):P1V05_PCH_STBY
    2  FM_PRSNT_2_4_N      B  @BASEBOARD_FAB2_LIB.BASEBOARD_FAB2(SCH_1):FM_PRSNT_2_4_N

RES  I321  R3N16  [RES_0402-1.00K,1%,1/16W,CHIP,GA]
    1  P1V05_PCH_STBY      A  @BASEBOARD_FAB2_LIB.BASEBOARD_FAB2(SCH_1):P1V05_PCH_STBY
    2  FM_PRSNT_2_5_N      B  @BASEBOARD_FAB2_LIB.BASEBOARD_FAB2(SCH_1):FM_PRSNT_2_5_N

RES  I78  R3N17  [RES_0402-1.00K,1%,1/16W,EMPTY,A]
    2  SPI_PCH_IO3        B  @BASEBOARD_FAB2_LIB.BASEBOARD_FAB2(SCH_1):SPI_PCH_IO3
    1  P3V3_STBY          A  @BASEBOARD_FAB2_LIB.BASEBOARD_FAB2(SCH_1):P3V3_STBY

RES  I81  R3N19  [RES_0402-10.0,1%,1/16W,CHIP,G2A]
    1  VSENSE_PVCCIO_CPU0_AVSP      A  @BASEBOARD_FAB2_LIB.BASEBOARD_FAB2(SCH_1):VSENSE_PVCCIO_CPU0_AVSP
    2  VR_PVCCIO_CPU0_AVSP      B  @BASEBOARD_FAB2_LIB.BASEBOARD_FAB2(SCH_1):VR_PVCCIO_CPU0_AVSP

RES  I68  R3N20  [RES_0402-100.0,1%,1/16W,CHIP,GA]
    1  VSENSE_PVCCIO_CPU0_AVSN      A  @BASEBOARD_FAB2_LIB.BASEBOARD_FAB2(SCH_1):VSENSE_PVCCIO_CPU0_AVSN
    2  GND                B  @BASEBOARD_FAB2_LIB.BASEBOARD_FAB2(SCH_1):GND

RES  I74  R3N21  [RES_0402-100.0,1%,1/16W,CHIP,GA]
    1  VSENSE_PVCCIO_CPU0_AVSP      A  @BASEBOARD_FAB2_LIB.BASEBOARD_FAB2(SCH_1):VSENSE_PVCCIO_CPU0_AVSP
    2  PVCCIO_CPU0        B  @BASEBOARD_FAB2_LIB.BASEBOARD_FAB2(SCH_1):PVCCIO_CPU0

RES  I65  R3N22  [RES_0402-4.02K,1%,1/16W,CHIP,GA]
    1  VR_PVCCIO_CPU0_XADDR2      A  @BASEBOARD_FAB2_LIB.BASEBOARD_FAB2(SCH_1):VR_PVCCIO_CPU0_XADDR2
    2  GND                B  @BASEBOARD_FAB2_LIB.BASEBOARD_FAB2(SCH_1):GND

RES  I60  R3N23  [RES_0402-2.26K,1.0%,1/16W,EMPTA]
    2  PU_VR_PVCCIO_CPU0_FAULT1      B  @BASEBOARD_FAB2_LIB.BASEBOARD_FAB2(SCH_1):PU_VR_PVCCIO_CPU0_FAULT1
    1  P3V3_STBY          A  @BASEBOARD_FAB2_LIB.BASEBOARD_FAB2(SCH_1):P3V3_STBY

RES  I553  R3N24  [RES_0402-33.2,1%,1/16W,CHIP,G2A]
    2  LPC_LAD2_IO2_R      B  @BASEBOARD_FAB2_LIB.BASEBOARD_FAB2(SCH_1):LPC_LAD2_IO2_R
    1  LPC_LAD2_IO2       A  @BASEBOARD_FAB2_LIB.BASEBOARD_FAB2(SCH_1):LPC_LAD2_IO2

RES  I527  R3N25  [RES_0402-33.2,1%,1/16W,CHIP,G2A]
    2  LPC_LAD3_IO3_R      B  @BASEBOARD_FAB2_LIB.BASEBOARD_FAB2(SCH_1):LPC_LAD3_IO3_R
    1  LPC_LAD3_IO3       A  @BASEBOARD_FAB2_LIB.BASEBOARD_FAB2(SCH_1):LPC_LAD3_IO3

RES  I555  R3N26  [RES_0402-33.2,1%,1/16W,CHIP,G2A]
    2  LPC_LAD0_IO0_R      B  @BASEBOARD_FAB2_LIB.BASEBOARD_FAB2(SCH_1):LPC_LAD0_IO0_R
    1  LPC_LAD0_IO0       A  @BASEBOARD_FAB2_LIB.BASEBOARD_FAB2(SCH_1):LPC_LAD0_IO0

RES  I521  R3N27  [RES_0402-33.2,1%,1/16W,CHIP,G2A]
    2  LPC_LFRAME_N_CS0_R_N      B  @BASEBOARD_FAB2_LIB.BASEBOARD_FAB2(SCH_1):LPC_LFRAME_N_CS0_R_N
    1  LPC_LFRAME_N_CS0_N      A  @BASEBOARD_FAB2_LIB.BASEBOARD_FAB2(SCH_1):LPC_LFRAME_N_CS0_N

RES  I554  R3N28  [RES_0402-33.2,1%,1/16W,CHIP,G2A]
    2  LPC_LAD1_IO1_R      B  @BASEBOARD_FAB2_LIB.BASEBOARD_FAB2(SCH_1):LPC_LAD1_IO1_R
    1  LPC_LAD1_IO1       A  @BASEBOARD_FAB2_LIB.BASEBOARD_FAB2(SCH_1):LPC_LAD1_IO1

RES  I156  R3N29  [RES_0402-16K,1.0%,1/16W,CHIP,GA]
    1  VR_PVCCIOMCP_CPU0_XADDR1      A  @BASEBOARD_FAB2_LIB.BASEBOARD_FAB2(SCH_1):VR_PVCCIOMCP_CPU0_XADDR1
    2  GND                B  @BASEBOARD_FAB2_LIB.BASEBOARD_FAB2(SCH_1):GND

RES  I95  R3N30  [RES_0402-0.0,5%,1/16W,EMPTY,G2A]
    2  H_CPU0_MEMABC_MEMHOT_PCH_N      B  @BASEBOARD_FAB2_LIB.BASEBOARD_FAB2(SCH_1):H_CPU0_MEMABC_MEMHOT_PCH_N
    1  H_CPU0_MEMABC_MEMHOT_LVT3_N      A  @BASEBOARD_FAB2_LIB.BASEBOARD_FAB2(SCH_1):H_CPU0_MEMABC_MEMHOT_LVT3_N

RES  I52  R3N31  [RES_0402-3.16K,1%,1/16W,CHIP,GA]
    1  VR_PVCCIO_CPU0_XADDR1      A  @BASEBOARD_FAB2_LIB.BASEBOARD_FAB2(SCH_1):VR_PVCCIO_CPU0_XADDR1
    2  GND                B  @BASEBOARD_FAB2_LIB.BASEBOARD_FAB2(SCH_1):GND

RES  I61  R3P1   [RES_0402-0.0,5%,1/16W,CHIP,G21A]
    1  SVID_ALERT_PVCCIO_CPU0      A  @BASEBOARD_FAB2_LIB.BASEBOARD_FAB2(SCH_1):SVID_ALERT_PVCCIO_CPU0
    2  SVID_ALERT0_CPU0_R_N      B  @BASEBOARD_FAB2_LIB.BASEBOARD_FAB2(SCH_1):SVID_ALERT0_CPU0_R_N

RES  I90  R3P2   [RES_0402-0.0,5%,1/16W,CHIP,G21A]
    2  RMII_BMC_PCH_SPRNGVLLE_CRSDV_R1      B  @BASEBOARD_FAB2_LIB.BASEBOARD_FAB2(SCH_1):RMII_BMC_PCH_SPRNGVLLE_CRSDV_R1
    1  RMII_BMC_PCH_SPRNGVLLE_CRSDV      A  @BASEBOARD_FAB2_LIB.BASEBOARD_FAB2(SCH_1):RMII_BMC_PCH_SPRNGVLLE_CRSDV

RES  I89  R3P3   [RES_0402-0.0,5%,1/16W,CHIP,G21A]
    2  RMII_SPRNGVLLE_BMC_PCH_RXD0_R1      B  @BASEBOARD_FAB2_LIB.BASEBOARD_FAB2(SCH_1):RMII_SPRNGVLLE_BMC_PCH_RXD0_R1
    1  RMII_SPRNGVLLE_BMC_PCH_RXD0      A  @BASEBOARD_FAB2_LIB.BASEBOARD_FAB2(SCH_1):RMII_SPRNGVLLE_BMC_PCH_RXD0

RES  I316  R3P5   [RES_0402-1.00K,1%,1/16W,CHIP,GA]
    1  P1V05_PCH_STBY      A  @BASEBOARD_FAB2_LIB.BASEBOARD_FAB2(SCH_1):P1V05_PCH_STBY
    2  FM_PRSNT_2_2_N      B  @BASEBOARD_FAB2_LIB.BASEBOARD_FAB2(SCH_1):FM_PRSNT_2_2_N

RES  I317  R3P6   [RES_0402-1.00K,1%,1/16W,CHIP,GA]
    1  P1V05_PCH_STBY      A  @BASEBOARD_FAB2_LIB.BASEBOARD_FAB2(SCH_1):P1V05_PCH_STBY
    2  FM_PRSNT_2_3_N      B  @BASEBOARD_FAB2_LIB.BASEBOARD_FAB2(SCH_1):FM_PRSNT_2_3_N

RES  I315  R3P7   [RES_0402-1.00K,1%,1/16W,CHIP,GA]
    1  P1V05_PCH_STBY      A  @BASEBOARD_FAB2_LIB.BASEBOARD_FAB2(SCH_1):P1V05_PCH_STBY
    2  FM_PRSNT_2_1_N      B  @BASEBOARD_FAB2_LIB.BASEBOARD_FAB2(SCH_1):FM_PRSNT_2_1_N

RES  I322  R3P8   [RES_0402-1.00K,1%,1/16W,CHIP,GA]
    1  P1V05_PCH_STBY      A  @BASEBOARD_FAB2_LIB.BASEBOARD_FAB2(SCH_1):P1V05_PCH_STBY
    2  FM_PRSNT_2_6_N      B  @BASEBOARD_FAB2_LIB.BASEBOARD_FAB2(SCH_1):FM_PRSNT_2_6_N

RES  I16  R3P11  [RES_0402-0.0,5%,1/16W,CHIP,G21A]
    2  SVID_VDIO_PVCCIO_CPU0      B  @BASEBOARD_FAB2_LIB.BASEBOARD_FAB2(SCH_1):SVID_VDIO_PVCCIO_CPU0
    1  SVID_DIO0_CPU0_R      A  @BASEBOARD_FAB2_LIB.BASEBOARD_FAB2(SCH_1):SVID_DIO0_CPU0_R

RES  I31  R3P12  [RES_0402-100.0K,1%,1/16W,CHIP,B]
    2  VR_PVCCIO_CPU0_VINSEN      B  @BASEBOARD_FAB2_LIB.BASEBOARD_FAB2(SCH_1):VR_PVCCIO_CPU0_VINSEN
    1  VR_FET_SW_P12V_STBY_PVCCIO_CPU0      A  @BASEBOARD_FAB2_LIB.BASEBOARD_FAB2(SCH_1):VR_FET_SW_P12V_STBY_PVCCIO_CPU0

RES  I17  R3P13  [RES_0402-100.0,1%,1/16W,EMPTY,A]
    2  SVID_DIO0_CPU0_R      B  @BASEBOARD_FAB2_LIB.BASEBOARD_FAB2(SCH_1):SVID_DIO0_CPU0_R
    1  PVCCIO_CPU0        A  @BASEBOARD_FAB2_LIB.BASEBOARD_FAB2(SCH_1):PVCCIO_CPU0

RES  I29  R3P15  [RES_0402-150.0,1%,1/16W,CHIP,GA]
    2  SVID_CLK_PVCCIO_CPU0      B  @BASEBOARD_FAB2_LIB.BASEBOARD_FAB2(SCH_1):SVID_CLK_PVCCIO_CPU0
    1  SVID_CLK0_CPU0_R      A  @BASEBOARD_FAB2_LIB.BASEBOARD_FAB2(SCH_1):SVID_CLK0_CPU0_R

RES  I32  R3P16  [RES_0402-1.5K,1%,1/16W,CHIP,G2A]
    1  VR_PVCCIO_CPU0_VINSEN      A  @BASEBOARD_FAB2_LIB.BASEBOARD_FAB2(SCH_1):VR_PVCCIO_CPU0_VINSEN
    2  GND                B  @BASEBOARD_FAB2_LIB.BASEBOARD_FAB2(SCH_1):GND

RES  I28  R3P17  [RES_0402-49.9,1%,1/16W,EMPTY,GA]
    2  SVID_CLK0_CPU0_R      B  @BASEBOARD_FAB2_LIB.BASEBOARD_FAB2(SCH_1):SVID_CLK0_CPU0_R
    1  PVCCIO_CPU0        A  @BASEBOARD_FAB2_LIB.BASEBOARD_FAB2(SCH_1):PVCCIO_CPU0

RES  I64  R3P18  [RES_0402-1.00K,1%,1/16W,CHIP,GA]
    1  P3V3_STBY          A  @BASEBOARD_FAB2_LIB.BASEBOARD_FAB2(SCH_1):P3V3_STBY
    2  IRQ_PVCCIO_CPU0_VRHOT_N      B  @BASEBOARD_FAB2_LIB.BASEBOARD_FAB2(SCH_1):IRQ_PVCCIO_CPU0_VRHOT_N

RES  I58  R3P20  [RES_0402-22.1,1.0%,1/16W,CHIP,A]
    1  PWRGD_PVCCIO_CPU0_R      A  @BASEBOARD_FAB2_LIB.BASEBOARD_FAB2(SCH_1):PWRGD_PVCCIO_CPU0_R
    2  PWRGD_PVCCIO_CPU0      B  @BASEBOARD_FAB2_LIB.BASEBOARD_FAB2(SCH_1):PWRGD_PVCCIO_CPU0

RES  I88  R3P21  [RES_0402-100.0K,1%,1/16W,EMPTYA]
    2  VR_PVCCIO_CPU0_EN      B  @BASEBOARD_FAB2_LIB.BASEBOARD_FAB2(SCH_1):VR_PVCCIO_CPU0_EN
    1  P3V3_STBY          A  @BASEBOARD_FAB2_LIB.BASEBOARD_FAB2(SCH_1):P3V3_STBY

RES  I24  R3P22  [RES_0402-0.0,5%,1/16W,CHIP,G21A]
    2  VR_PVCCIO_CPU0_VDD      B  @BASEBOARD_FAB2_LIB.BASEBOARD_FAB2(SCH_1):VR_PVCCIO_CPU0_VDD
    1  P3V3_STBY          A  @BASEBOARD_FAB2_LIB.BASEBOARD_FAB2(SCH_1):P3V3_STBY

RES  I47  R3P23  [RES_0402-20.0,1%,1/16W,CHIP,G2A]
    1  SMB_VR_STBY_LVC3_SDA      A  @BASEBOARD_FAB2_LIB.BASEBOARD_FAB2(SCH_1):SMB_VR_STBY_LVC3_SDA
    2  SMB_VR_SDA_PVCCIO_CPU0      B  @BASEBOARD_FAB2_LIB.BASEBOARD_FAB2(SCH_1):SMB_VR_SDA_PVCCIO_CPU0

RES  I46  R3P24  [RES_0402-20.0,1%,1/16W,CHIP,G2A]
    1  SMB_VR_STBY_LVC3_SCL      A  @BASEBOARD_FAB2_LIB.BASEBOARD_FAB2(SCH_1):SMB_VR_STBY_LVC3_SCL
    2  SMB_VR_SCL_PVCCIO_CPU0      B  @BASEBOARD_FAB2_LIB.BASEBOARD_FAB2(SCH_1):SMB_VR_SCL_PVCCIO_CPU0

RES  I56  R3P25  [RES_0402-1.00K,1%,1/16W,CHIP,GA]
    2  PWRGD_PVCCIO_CPU0_R      B  @BASEBOARD_FAB2_LIB.BASEBOARD_FAB2(SCH_1):PWRGD_PVCCIO_CPU0_R
    1  P3V3_STBY          A  @BASEBOARD_FAB2_LIB.BASEBOARD_FAB2(SCH_1):P3V3_STBY

RES  I87  R3P26  [RES_0402-0.0,5%,1/16W,CHIP,G21A]
    2  VR_PVCCIO_CPU0_EN      B  @BASEBOARD_FAB2_LIB.BASEBOARD_FAB2(SCH_1):VR_PVCCIO_CPU0_EN
    1  FM_PVCCIO_CPU0_EN      A  @BASEBOARD_FAB2_LIB.BASEBOARD_FAB2(SCH_1):FM_PVCCIO_CPU0_EN

RES  I5   R3P29  [RES_0402-64.9,1.0%,1/16W,CHIP,A]
    2  PWRGD_CPU0_DRAMPWROK_DEF_G      B  @BASEBOARD_FAB2_LIB.BASEBOARD_FAB2(SCH_1):PWRGD_CPU0_DRAMPWROK_DEF_G
    1  PVDDQ_DEF          A  @BASEBOARD_FAB2_LIB.BASEBOARD_FAB2(SCH_1):PVDDQ_DEF

RES  I71  R3P32  [RES_0402-1.00K,1%,1/16W,CHIP,GA]
    2  PD_GTL2014_1_VREF      B  @BASEBOARD_FAB2_LIB.BASEBOARD_FAB2(SCH_1):PD_GTL2014_1_VREF
    1  GND                A  @BASEBOARD_FAB2_LIB.BASEBOARD_FAB2(SCH_1):GND

RES  I116  R3P34  [RES_0402-0.0,5%,1/16W,CHIP,G21A]
    1  RST_CPU0_LVC3_R1_N      A  @BASEBOARD_FAB2_LIB.BASEBOARD_FAB2(SCH_1):RST_CPU0_LVC3_R1_N
    2  RST_CPU0_LVC3_N      B  @BASEBOARD_FAB2_LIB.BASEBOARD_FAB2(SCH_1):RST_CPU0_LVC3_N

RES  I117  R3P35  [RES_0402-0.0,5%,1/16W,CHIP,G21A]
    1  RST_CPU1_LVC3_R1_N      A  @BASEBOARD_FAB2_LIB.BASEBOARD_FAB2(SCH_1):RST_CPU1_LVC3_R1_N
    2  RST_CPU1_LVC3_N      B  @BASEBOARD_FAB2_LIB.BASEBOARD_FAB2(SCH_1):RST_CPU1_LVC3_N

RES  I36  R3P36  [RES_0402-1.00K,1%,1/16W,CHIP,GA]
    2  PU_GTL2014_1_DIR      B  @BASEBOARD_FAB2_LIB.BASEBOARD_FAB2(SCH_1):PU_GTL2014_1_DIR
    1  P3V3_STBY          A  @BASEBOARD_FAB2_LIB.BASEBOARD_FAB2(SCH_1):P3V3_STBY

RES  I7   R3P38  [RES_0402-64.9,1.0%,1/16W,CHIP,A]
    2  PWRGD_CPU0_DRAMPWROK_ABC_G      B  @BASEBOARD_FAB2_LIB.BASEBOARD_FAB2(SCH_1):PWRGD_CPU0_DRAMPWROK_ABC_G
    1  PVDDQ_ABC          A  @BASEBOARD_FAB2_LIB.BASEBOARD_FAB2(SCH_1):PVDDQ_ABC

RES  I9   R3P41  [RES_0402-75,1.0%,1/16W,CHIP,G2A]
    1  PVCCIO_CPU1        A  @BASEBOARD_FAB2_LIB.BASEBOARD_FAB2(SCH_1):PVCCIO_CPU1
    2  H_CPU1_THERMTRIP_G_N      B  @BASEBOARD_FAB2_LIB.BASEBOARD_FAB2(SCH_1):H_CPU1_THERMTRIP_G_N

RES  I14  R3P42  [RES_0402-33.2,1%,1/16W,CHIP,G2A]
    1  FM_CPU1_THERMTRIP_LVT3_R_N      A  @BASEBOARD_FAB2_LIB.BASEBOARD_FAB2(SCH_1):FM_CPU1_THERMTRIP_LVT3_R_N
    2  FM_CPU1_THERMTRIP_LVT3_N      B  @BASEBOARD_FAB2_LIB.BASEBOARD_FAB2(SCH_1):FM_CPU1_THERMTRIP_LVT3_N

RES  I13  R3P43  [RES_0402-33.2,1%,1/16W,CHIP,G2A]
    1  FM_CPU_CATERR_LVT3_R2_N      A  @BASEBOARD_FAB2_LIB.BASEBOARD_FAB2(SCH_1):FM_CPU_CATERR_LVT3_R2_N
    2  FM_CPU_CATERR_LVT3_N      B  @BASEBOARD_FAB2_LIB.BASEBOARD_FAB2(SCH_1):FM_CPU_CATERR_LVT3_N

RES  I59  R3P44  [RES_0402-4.75K,1%,1/16W,CHIP,GA]
    2  PWRGD_DSW_PWROK      B  @BASEBOARD_FAB2_LIB.BASEBOARD_FAB2(SCH_1):PWRGD_DSW_PWROK
    1  P3V3_STBY          A  @BASEBOARD_FAB2_LIB.BASEBOARD_FAB2(SCH_1):P3V3_STBY

RES  I39  R3P45  [RES_0402-49.9,1%,1/16W,CHIP,G2A]
    1  PVCCIO_CPU0        A  @BASEBOARD_FAB2_LIB.BASEBOARD_FAB2(SCH_1):PVCCIO_CPU0
    2  P0V7_GTL2104_VREF_1      B  @BASEBOARD_FAB2_LIB.BASEBOARD_FAB2(SCH_1):P0V7_GTL2104_VREF_1

RES  I12  R3P46  [RES_0402-33.2,1%,1/16W,CHIP,G2A]
    1  FM_CPU1_FIVR_FAULT_R_LVT3      A  @BASEBOARD_FAB2_LIB.BASEBOARD_FAB2(SCH_1):FM_CPU1_FIVR_FAULT_R_LVT3
    2  FM_CPU1_FIVR_FAULT_LVT3      B  @BASEBOARD_FAB2_LIB.BASEBOARD_FAB2(SCH_1):FM_CPU1_FIVR_FAULT_LVT3

RES  I74  R3P48  [RES_0402-90.9K,1%,1/16W,CHIP,GA]
    2  VSENSE_P12V_ADM1085      B  @BASEBOARD_FAB2_LIB.BASEBOARD_FAB2(SCH_1):VSENSE_P12V_ADM1085
    1  P12V_STBY          A  @BASEBOARD_FAB2_LIB.BASEBOARD_FAB2(SCH_1):P12V_STBY

RES  I38  R3P49  [RES_0402-100.0,1%,1/16W,CHIP,GA]
    1  P0V7_GTL2104_VREF_1      A  @BASEBOARD_FAB2_LIB.BASEBOARD_FAB2(SCH_1):P0V7_GTL2104_VREF_1
    2  GND                B  @BASEBOARD_FAB2_LIB.BASEBOARD_FAB2(SCH_1):GND

RES  I71  R3P50  [RES_0402-10.0K,1%,1/16W,EMPTY,A]
    2  PWRGD_P3V3_STBY      B  @BASEBOARD_FAB2_LIB.BASEBOARD_FAB2(SCH_1):PWRGD_P3V3_STBY
    1  P3V3_STBY          A  @BASEBOARD_FAB2_LIB.BASEBOARD_FAB2(SCH_1):P3V3_STBY

RES  I75  R3P51  [RES_0402-6.34K,1%,1/16W,CHIP,GA]
    1  VSENSE_P12V_ADM1085      A  @BASEBOARD_FAB2_LIB.BASEBOARD_FAB2(SCH_1):VSENSE_P12V_ADM1085
    2  GND                B  @BASEBOARD_FAB2_LIB.BASEBOARD_FAB2(SCH_1):GND

RES  I357  R3P53  [RES_0402-4.75K,1%,1/16W,CHIP,GA]
    1  P1V05_PCH_STBY      A  @BASEBOARD_FAB2_LIB.BASEBOARD_FAB2(SCH_1):P1V05_PCH_STBY
    2  FM_OCP_MEZZC_PRES_N      B  @BASEBOARD_FAB2_LIB.BASEBOARD_FAB2(SCH_1):FM_OCP_MEZZC_PRES_N

RES  I331  R3P54  [RES_0402-3.32K,1%,1/16W,EMPTY,A]
    1  P3V3_STBY          A  @BASEBOARD_FAB2_LIB.BASEBOARD_FAB2(SCH_1):P3V3_STBY
    2  FM_CPU0_SM_WP      B  @BASEBOARD_FAB2_LIB.BASEBOARD_FAB2(SCH_1):FM_CPU0_SM_WP

RES  I333  R3P56  [RES_0402-1.00K,1%,1/16W,CHIP,GA]
    2  GND                B  @BASEBOARD_FAB2_LIB.BASEBOARD_FAB2(SCH_1):GND
    1  FM_CPU0_SM_WP      A  @BASEBOARD_FAB2_LIB.BASEBOARD_FAB2(SCH_1):FM_CPU0_SM_WP

RES  I91  R3P57  [RES_0402-0.0,5%,1/16W,CHIP,G21A]
    1  VR_PVCCIO_CPU0_VD12      A  @BASEBOARD_FAB2_LIB.BASEBOARD_FAB2(SCH_1):VR_PVCCIO_CPU0_VD12
    2  VR_PVCCIO_CPU0_AIREF1      B  @BASEBOARD_FAB2_LIB.BASEBOARD_FAB2(SCH_1):VR_PVCCIO_CPU0_AIREF1

RES  I98  R3P58  [RES_0402-0.0,5%,1/16W,CHIP,G21A]
    2  H_CPU_CATERR_G_N      B  @BASEBOARD_FAB2_LIB.BASEBOARD_FAB2(SCH_1):H_CPU_CATERR_G_N
    1  H_CPU1_CATERR_G_N      A  @BASEBOARD_FAB2_LIB.BASEBOARD_FAB2(SCH_1):H_CPU1_CATERR_G_N

RES  I97  R3P59  [RES_0402-0.0,5%,1/16W,CHIP,G21A]
    2  H_CPU_CATERR_G_N      B  @BASEBOARD_FAB2_LIB.BASEBOARD_FAB2(SCH_1):H_CPU_CATERR_G_N
    1  H_CPU0_CATERR_G_N      A  @BASEBOARD_FAB2_LIB.BASEBOARD_FAB2(SCH_1):H_CPU0_CATERR_G_N

RES  I67  R3P60  [RES_0402-240,1.0%,1/16W,CHIP,GA]
    2  SMB_DDR_DEF_SCL_G      B  @BASEBOARD_FAB2_LIB.BASEBOARD_FAB2(SCH_1):SMB_DDR_DEF_SCL_G
    1  PVCCIO_CPU0        A  @BASEBOARD_FAB2_LIB.BASEBOARD_FAB2(SCH_1):PVCCIO_CPU0

RES  I201  R3P61  [RES_0402-2.26K,1.0%,1/16W,CHIPA]
    1  P3V3_STBY          A  @BASEBOARD_FAB2_LIB.BASEBOARD_FAB2(SCH_1):P3V3_STBY
    2  FM_MB_SLOT_ID2      B  @BASEBOARD_FAB2_LIB.BASEBOARD_FAB2(SCH_1):FM_MB_SLOT_ID2

RES  I22  R3P62  [RES_0402-4.75K,1%,1/16W,EMPTY,A]
    1  P3V3_STBY          A  @BASEBOARD_FAB2_LIB.BASEBOARD_FAB2(SCH_1):P3V3_STBY
    2  FM_FLASH_ATTACH_CFG_STRAP      B  @BASEBOARD_FAB2_LIB.BASEBOARD_FAB2(SCH_1):FM_FLASH_ATTACH_CFG_STRAP

RES  I100  R3P63  [RES_0402-0.0,5%,1/16W,EMPTY,G2A]
    2  H_CPU1_MEMGHJ_MEMHOT_PCH_N      B  @BASEBOARD_FAB2_LIB.BASEBOARD_FAB2(SCH_1):H_CPU1_MEMGHJ_MEMHOT_PCH_N
    1  H_CPU1_MEMGHJ_MEMHOT_LVT3_N      A  @BASEBOARD_FAB2_LIB.BASEBOARD_FAB2(SCH_1):H_CPU1_MEMGHJ_MEMHOT_LVT3_N

RES  I23  R3P64  [RES_0402-1.00K,1%,1/16W,EMPTY,A]
    2  GND                B  @BASEBOARD_FAB2_LIB.BASEBOARD_FAB2(SCH_1):GND
    1  FM_FLASH_ATTACH_CFG_STRAP      A  @BASEBOARD_FAB2_LIB.BASEBOARD_FAB2(SCH_1):FM_FLASH_ATTACH_CFG_STRAP

RES  I46  R3R1   [RES_0402-1.00K,1%,1/16W,CHIP,GA]
    1  PD_GTL2104_DIR_1      A  @BASEBOARD_FAB2_LIB.BASEBOARD_FAB2(SCH_1):PD_GTL2104_DIR_1
    2  GND                B  @BASEBOARD_FAB2_LIB.BASEBOARD_FAB2(SCH_1):GND

RES  I75  R3R2   [RES_0402-1.00K,1%,1/16W,CHIP,GA]
    1  H_CPU1_FIVR_FAULT_G      A  @BASEBOARD_FAB2_LIB.BASEBOARD_FAB2(SCH_1):H_CPU1_FIVR_FAULT_G
    2  GND                B  @BASEBOARD_FAB2_LIB.BASEBOARD_FAB2(SCH_1):GND

RES  I61  R3R3   [RES_0402-33.2,1%,1/16W,CHIP,G2A]
    1  PWRGD_CPUPWRGD_R1      A  @BASEBOARD_FAB2_LIB.BASEBOARD_FAB2(SCH_1):PWRGD_CPUPWRGD_R1
    2  PWRGD_CPUPWRGD      B  @BASEBOARD_FAB2_LIB.BASEBOARD_FAB2(SCH_1):PWRGD_CPUPWRGD

RES  I66  R3R4   [RES_0402-4.75K,1%,1/16W,CHIP,GA]
    1  P3V3               A  @BASEBOARD_FAB2_LIB.BASEBOARD_FAB2(SCH_1):P3V3
    2  H_CPU0_MEMDEF_MEMHOT      B  @BASEBOARD_FAB2_LIB.BASEBOARD_FAB2(SCH_1):H_CPU0_MEMDEF_MEMHOT

RES  I103  R3R5   [RES_0402-665,1.0%,1/16W,CHIP,GA]
    2  SMB_DDR_DEF_VPP_SCL_R      B  @BASEBOARD_FAB2_LIB.BASEBOARD_FAB2(SCH_1):SMB_DDR_DEF_VPP_SCL_R
    1  PVPP_DEF           A  @BASEBOARD_FAB2_LIB.BASEBOARD_FAB2(SCH_1):PVPP_DEF

RES  I88  R3R7   [RES_0402-10.0,1%,1/16W,CHIP,G2A]
    1  SMB_DDR_DEF_SCL_G_R      A  @BASEBOARD_FAB2_LIB.BASEBOARD_FAB2(SCH_1):SMB_DDR_DEF_SCL_G_R
    2  SMB_DDR_DEF_SCL_G      B  @BASEBOARD_FAB2_LIB.BASEBOARD_FAB2(SCH_1):SMB_DDR_DEF_SCL_G

RES  I35  R3R8   [RES_0402-20.0,1%,1/16W,CHIP,G2A]
    1  SMB_DDR_DEF_VPP_SCL_R      A  @BASEBOARD_FAB2_LIB.BASEBOARD_FAB2(SCH_1):SMB_DDR_DEF_VPP_SCL_R
    2  SMB_DDR_DEF_VPP_SCL      B  @BASEBOARD_FAB2_LIB.BASEBOARD_FAB2(SCH_1):SMB_DDR_DEF_VPP_SCL

RES  I34  R3R9   [RES_0402-20.0,1%,1/16W,CHIP,G2A]
    1  SMB_DDR_DEF_VPP_SDA_R      A  @BASEBOARD_FAB2_LIB.BASEBOARD_FAB2(SCH_1):SMB_DDR_DEF_VPP_SDA_R
    2  SMB_DDR_DEF_VPP_SDA      B  @BASEBOARD_FAB2_LIB.BASEBOARD_FAB2(SCH_1):SMB_DDR_DEF_VPP_SDA

RES  I79  R3R10  [RES_0402-4.75K,1%,1/16W,CHIP,GA]
    1  P3V3               A  @BASEBOARD_FAB2_LIB.BASEBOARD_FAB2(SCH_1):P3V3
    2  H_CPU1_MEMGHJ_MEMHOT      B  @BASEBOARD_FAB2_LIB.BASEBOARD_FAB2(SCH_1):H_CPU1_MEMGHJ_MEMHOT

RES  I45  R3R11  [RES_0402-10.0K,1%,1/16W,EMPTY,A]
    2  GND                B  @BASEBOARD_FAB2_LIB.BASEBOARD_FAB2(SCH_1):GND
    1  FM_JTAG_PLD_EN_DEBUG      A  @BASEBOARD_FAB2_LIB.BASEBOARD_FAB2(SCH_1):FM_JTAG_PLD_EN_DEBUG

RES  I101  R3R12  [RES_0402-665,1.0%,1/16W,CHIP,GA]
    2  SMB_DDR_DEF_VPP_SDA_R      B  @BASEBOARD_FAB2_LIB.BASEBOARD_FAB2(SCH_1):SMB_DDR_DEF_VPP_SDA_R
    1  PVPP_DEF           A  @BASEBOARD_FAB2_LIB.BASEBOARD_FAB2(SCH_1):PVPP_DEF

RES  I65  R3R13  [RES_0402-240,1.0%,1/16W,CHIP,GA]
    2  SMB_DDR_DEF_SDA_G      B  @BASEBOARD_FAB2_LIB.BASEBOARD_FAB2(SCH_1):SMB_DDR_DEF_SDA_G
    1  PVCCIO_CPU0        A  @BASEBOARD_FAB2_LIB.BASEBOARD_FAB2(SCH_1):PVCCIO_CPU0

RES  I110  R3R14  [RES_0402-10.0,1%,1/16W,CHIP,G2A]
    1  SMB_DDR_DEF_SDA_G_R      A  @BASEBOARD_FAB2_LIB.BASEBOARD_FAB2(SCH_1):SMB_DDR_DEF_SDA_G_R
    2  SMB_DDR_DEF_SDA_G      B  @BASEBOARD_FAB2_LIB.BASEBOARD_FAB2(SCH_1):SMB_DDR_DEF_SDA_G

RES  I44  R3R15  [RES_0402-1.00K,1%,1/16W,CHIP,GA]
    1  P3V3_STBY          A  @BASEBOARD_FAB2_LIB.BASEBOARD_FAB2(SCH_1):P3V3_STBY
    2  FM_JTAG_PLD_EN_DEBUG      B  @BASEBOARD_FAB2_LIB.BASEBOARD_FAB2(SCH_1):FM_JTAG_PLD_EN_DEBUG

RES  I48  R3R16  [RES_0402-4.75K,1%,1/16W,CHIP,GA]
    2  RST_CD_CPU0_POR_N      B  @BASEBOARD_FAB2_LIB.BASEBOARD_FAB2(SCH_1):RST_CD_CPU0_POR_N
    1  PVPP_ABC           A  @BASEBOARD_FAB2_LIB.BASEBOARD_FAB2(SCH_1):PVPP_ABC

RES  I157  R3T1   [RES_0402-33.2,1%,1/16W,CHIP,G2A]
    1  SPI_BIOS_SOCKET_IO3      A  @BASEBOARD_FAB2_LIB.BASEBOARD_FAB2(SCH_1):SPI_BIOS_SOCKET_IO3
    2  PU_BIOS_SPI_HOLD1_N      B  @BASEBOARD_FAB2_LIB.BASEBOARD_FAB2(SCH_1):PU_BIOS_SPI_HOLD1_N

RES  I155  R3T2   [RES_0402-33.2,1%,1/16W,CHIP,G2A]
    1  SPI_SWITCH_MISO      A  @BASEBOARD_FAB2_LIB.BASEBOARD_FAB2(SCH_1):SPI_SWITCH_MISO
    2  SPI_MISO_R1        B  @BASEBOARD_FAB2_LIB.BASEBOARD_FAB2(SCH_1):SPI_MISO_R1

RES  I150  R3T3   [RES_0402-4.75K,1%,1/16W,EMPTY,A]
    2  PU_SPI1_RST        B  @BASEBOARD_FAB2_LIB.BASEBOARD_FAB2(SCH_1):PU_SPI1_RST
    1  P3V3_STBY          A  @BASEBOARD_FAB2_LIB.BASEBOARD_FAB2(SCH_1):P3V3_STBY

RES  I174  R3T4   [RES_0402-10.0K,1%,1/16W,CHIP,GA]
    2  PU_BIOS_SPI_HOLD1_N      B  @BASEBOARD_FAB2_LIB.BASEBOARD_FAB2(SCH_1):PU_BIOS_SPI_HOLD1_N
    1  P3V3_STBY          A  @BASEBOARD_FAB2_LIB.BASEBOARD_FAB2(SCH_1):P3V3_STBY

RES  I152  R3T5   [RES_0402-4.75K,1%,1/16W,CHIP,GA]
    2  SPI_CS0_SECONDARY_R_N      B  @BASEBOARD_FAB2_LIB.BASEBOARD_FAB2(SCH_1):SPI_CS0_SECONDARY_R_N
    1  P3V3_STBY          A  @BASEBOARD_FAB2_LIB.BASEBOARD_FAB2(SCH_1):P3V3_STBY

RES  I179  R3T9   [RES_0402-10.0K,1%,1/16W,EMPTY,A]
    1  PU_BIOS_SPI_WP1_N      A  @BASEBOARD_FAB2_LIB.BASEBOARD_FAB2(SCH_1):PU_BIOS_SPI_WP1_N
    2  GND                B  @BASEBOARD_FAB2_LIB.BASEBOARD_FAB2(SCH_1):GND

RES  I184  R3T10  [RES_0402-33.2,1%,1/16W,CHIP,G2A]
    2  SPI_SWITCH_MOSI_R1      B  @BASEBOARD_FAB2_LIB.BASEBOARD_FAB2(SCH_1):SPI_SWITCH_MOSI_R1
    1  SPI_SWITCH_MOSI      A  @BASEBOARD_FAB2_LIB.BASEBOARD_FAB2(SCH_1):SPI_SWITCH_MOSI

RES  I330  R3T11  [RES_0402-49.9,1%,1/16W,EMPTY,GA]
    2  SVID_CLK1_CPU0_R      B  @BASEBOARD_FAB2_LIB.BASEBOARD_FAB2(SCH_1):SVID_CLK1_CPU0_R
    1  PVCCIO_CPU0        A  @BASEBOARD_FAB2_LIB.BASEBOARD_FAB2(SCH_1):PVCCIO_CPU0

RES  I178  R3T12  [RES_0402-10.0K,1%,1/16W,CHIP,GA]
    2  PU_BIOS_SPI_WP1_N      B  @BASEBOARD_FAB2_LIB.BASEBOARD_FAB2(SCH_1):PU_BIOS_SPI_WP1_N
    1  P3V3_STBY          A  @BASEBOARD_FAB2_LIB.BASEBOARD_FAB2(SCH_1):P3V3_STBY

RES  I313  R3T13  [RES_0402-0.0,5%,1/16W,CHIP,G21A]
    2  VR_PVDDQ_ABC_VDD      B  @BASEBOARD_FAB2_LIB.BASEBOARD_FAB2(SCH_1):VR_PVDDQ_ABC_VDD
    1  P3V3_STBY          A  @BASEBOARD_FAB2_LIB.BASEBOARD_FAB2(SCH_1):P3V3_STBY

RES  I156  R3T14  [RES_0402-10.0K,1%,1/16W,CHIP,GA]
    2  GND                B  @BASEBOARD_FAB2_LIB.BASEBOARD_FAB2(SCH_1):GND
    1  FM_BIOS_USB_RECOVERY      A  @BASEBOARD_FAB2_LIB.BASEBOARD_FAB2(SCH_1):FM_BIOS_USB_RECOVERY

RES  I156  R3U1   [RES_0402-33.2,1%,1/16W,CHIP,G2A]
    1  SPI_BIOS_SOCKET_IO2      A  @BASEBOARD_FAB2_LIB.BASEBOARD_FAB2(SCH_1):SPI_BIOS_SOCKET_IO2
    2  PU_BIOS_SPI_WP1_N      B  @BASEBOARD_FAB2_LIB.BASEBOARD_FAB2(SCH_1):PU_BIOS_SPI_WP1_N

RES  I295  R3U2   [RES_0402-100.0,1%,1/16W,CHIP,GA]
    2  SVID_DIO1_CPU0_R      B  @BASEBOARD_FAB2_LIB.BASEBOARD_FAB2(SCH_1):SVID_DIO1_CPU0_R
    1  PVCCIO_CPU0        A  @BASEBOARD_FAB2_LIB.BASEBOARD_FAB2(SCH_1):PVCCIO_CPU0

RES  I332  R3U3   [RES_0402-0.0,5%,1/16W,CHIP,G21A]
    1  VR_PVDDQ_ABC_VD12      A  @BASEBOARD_FAB2_LIB.BASEBOARD_FAB2(SCH_1):VR_PVDDQ_ABC_VD12
    2  VR_PVDDQ_ABC_AIREF2      B  @BASEBOARD_FAB2_LIB.BASEBOARD_FAB2(SCH_1):VR_PVDDQ_ABC_AIREF2

RES  I58  R3U4   [RES_0603-120.0,1%,1/10W,CHIP,GA]
    1  PVDDQ_ABC          A  @BASEBOARD_FAB2_LIB.BASEBOARD_FAB2(SCH_1):PVDDQ_ABC
    2  GND                B  @BASEBOARD_FAB2_LIB.BASEBOARD_FAB2(SCH_1):GND

RES  I52  R3U6   [RES_0402-1.0,1%,1/16W,CHIP,G21A]
    1  VR_PVDDQ_ABC_PH1_VCIN      A  @BASEBOARD_FAB2_LIB.BASEBOARD_FAB2(SCH_1):VR_PVDDQ_ABC_PH1_VCIN
    2  P5V_STBY           B  @BASEBOARD_FAB2_LIB.BASEBOARD_FAB2(SCH_1):P5V_STBY

RES  I76  R3U9   [RES_0402-1.0,1%,1/16W,CHIP,G21A]
    1  VR_PVDDQ_ABC_PH2_VCIN      A  @BASEBOARD_FAB2_LIB.BASEBOARD_FAB2(SCH_1):VR_PVDDQ_ABC_PH2_VCIN
    2  P5V_STBY           B  @BASEBOARD_FAB2_LIB.BASEBOARD_FAB2(SCH_1):P5V_STBY

RES  I341  R3U10  [RES_0402-0.0,5%,1/16W,CHIP,G21A]
    1  VR_PVDDQ_ABC_VD12      A  @BASEBOARD_FAB2_LIB.BASEBOARD_FAB2(SCH_1):VR_PVDDQ_ABC_VD12
    2  VR_PVDDQ_ABC_AIREF1      B  @BASEBOARD_FAB2_LIB.BASEBOARD_FAB2(SCH_1):VR_PVDDQ_ABC_AIREF1

RES  I52  R4A1   [RES_0402-51.1,1.0%,1/16W,CHIP,A]
    2  PVTT_DEF           B  @BASEBOARD_FAB2_LIB.BASEBOARD_FAB2(SCH_1):PVTT_DEF
    1  GND                A  @BASEBOARD_FAB2_LIB.BASEBOARD_FAB2(SCH_1):GND

RES  I38  R4A2   [RES_0402-0.0,5%,1/16W,CHIP,G21A]
    1  PWRGD_PVDDQ_DEF      A  @BASEBOARD_FAB2_LIB.BASEBOARD_FAB2(SCH_1):PWRGD_PVDDQ_DEF
    2  FM_PVTT_DEF_EN_R      B  @BASEBOARD_FAB2_LIB.BASEBOARD_FAB2(SCH_1):FM_PVTT_DEF_EN_R

RES  I38  R4A3   [RES_0402-0.0,5%,1/16W,CHIP,G21A]
    1  PWRGD_PVDDQ_KLM      A  @BASEBOARD_FAB2_LIB.BASEBOARD_FAB2(SCH_1):PWRGD_PVDDQ_KLM
    2  FM_PVTT_KLM_EN_R      B  @BASEBOARD_FAB2_LIB.BASEBOARD_FAB2(SCH_1):FM_PVTT_KLM_EN_R

RES  I51  R4A4   [RES_0402-33.2,1%,1/16W,CHIP,G2A]
    1  PWRGD_PVTT_KLM_CPU1_R      A  @BASEBOARD_FAB2_LIB.BASEBOARD_FAB2(SCH_1):PWRGD_PVTT_KLM_CPU1_R
    2  PWRGD_PVTT_CPU1      B  @BASEBOARD_FAB2_LIB.BASEBOARD_FAB2(SCH_1):PWRGD_PVTT_CPU1

RES  I17  R4A5   [RES_0402-10.0K,1%,1/16W,CHIP,GA]
    2  PWRGD_PVTT_KLM_CPU1_R      B  @BASEBOARD_FAB2_LIB.BASEBOARD_FAB2(SCH_1):PWRGD_PVTT_KLM_CPU1_R
    1  P3V3               A  @BASEBOARD_FAB2_LIB.BASEBOARD_FAB2(SCH_1):P3V3

RES  I51  R4A6   [RES_0402-33.2,1%,1/16W,CHIP,G2A]
    1  PWRGD_PVTT_DEF_CPU0_R      A  @BASEBOARD_FAB2_LIB.BASEBOARD_FAB2(SCH_1):PWRGD_PVTT_DEF_CPU0_R
    2  PWRGD_PVTT_CPU0      B  @BASEBOARD_FAB2_LIB.BASEBOARD_FAB2(SCH_1):PWRGD_PVTT_CPU0

RES  I162  R4A7   [RES_0402-2.2,5%,1/16W,EMPTY,G2A]
    1  VR_PVPP_KLM_SNUB      A  @BASEBOARD_FAB2_LIB.BASEBOARD_FAB2(SCH_1):VR_PVPP_KLM_SNUB
    2  GND                B  @BASEBOARD_FAB2_LIB.BASEBOARD_FAB2(SCH_1):GND

RES  I322  R4A8   [RES_0402-0.0,5%,1/16W,CHIP,G21A]
    2  SMB_PIROM_CPU0_SDA      B  @BASEBOARD_FAB2_LIB.BASEBOARD_FAB2(SCH_1):SMB_PIROM_CPU0_SDA
    1  SMB_LAN_STBY_LVC3_SDA      A  @BASEBOARD_FAB2_LIB.BASEBOARD_FAB2(SCH_1):SMB_LAN_STBY_LVC3_SDA

RES  I324  R4A9   [RES_0402-0.0,5%,1/16W,CHIP,G21A]
    2  SMB_PIROM_CPU0_SCL      B  @BASEBOARD_FAB2_LIB.BASEBOARD_FAB2(SCH_1):SMB_PIROM_CPU0_SCL
    1  SMB_LAN_STBY_LVC3_SCL      A  @BASEBOARD_FAB2_LIB.BASEBOARD_FAB2(SCH_1):SMB_LAN_STBY_LVC3_SCL

RES  I220  R4B1   [RES_0402-0.0,5%,1/16W,CHIP,G21A]
    2  FM_PVPP_PVDDQ_CPU1_EN_KLM      B  @BASEBOARD_FAB2_LIB.BASEBOARD_FAB2(SCH_1):FM_PVPP_PVDDQ_CPU1_EN_KLM
    1  FM_PVPP_CPU1_EN      A  @BASEBOARD_FAB2_LIB.BASEBOARD_FAB2(SCH_1):FM_PVPP_CPU1_EN

RES  I183  R4B2   [RES_0603-120.0,1%,1/10W,CHIP,GA]
    1  PVPP_KLM           A  @BASEBOARD_FAB2_LIB.BASEBOARD_FAB2(SCH_1):PVPP_KLM
    2  GND                B  @BASEBOARD_FAB2_LIB.BASEBOARD_FAB2(SCH_1):GND

RES  I214  R4B3   [RES_0402-0.0,5%,1/16W,CHIP,G21A]
    2  VSENSE_PVPP_KLM      B  @BASEBOARD_FAB2_LIB.BASEBOARD_FAB2(SCH_1):VSENSE_PVPP_KLM
    1  PVPP_KLM           A  @BASEBOARD_FAB2_LIB.BASEBOARD_FAB2(SCH_1):PVPP_KLM

RES  I216  R4B4   [RES_0402-6.34K,1%,1/16W,CHIP,GA]
    1  VR_FB_PVPP_KLM      A  @BASEBOARD_FAB2_LIB.BASEBOARD_FAB2(SCH_1):VR_FB_PVPP_KLM
    2  AGND_PVPP_KLM      B  @BASEBOARD_FAB2_LIB.BASEBOARD_FAB2(SCH_1):AGND_PVPP_KLM

RES  I215  R4B5   [RES_0402-20.0K,1%,1/16W,CHIP,GA]
    1  VSENSE_PVPP_KLM      A  @BASEBOARD_FAB2_LIB.BASEBOARD_FAB2(SCH_1):VSENSE_PVPP_KLM
    2  VR_FB_PVPP_KLM      B  @BASEBOARD_FAB2_LIB.BASEBOARD_FAB2(SCH_1):VR_FB_PVPP_KLM

RES  I140  R4B6   [RES_0402-7.87K,1.0%,1/16W,CHIPA]
    1  VR_PVPP_KLM_ISET      A  @BASEBOARD_FAB2_LIB.BASEBOARD_FAB2(SCH_1):VR_PVPP_KLM_ISET
    2  AGND_PVPP_KLM      B  @BASEBOARD_FAB2_LIB.BASEBOARD_FAB2(SCH_1):AGND_PVPP_KLM

RES  I201  R4B7   [RES_0402-22.1,1.0%,1/16W,CHIP,A]
    1  PWRGD_PVPP_KLM_R      A  @BASEBOARD_FAB2_LIB.BASEBOARD_FAB2(SCH_1):PWRGD_PVPP_KLM_R
    2  PWRGD_PVPP_KLM      B  @BASEBOARD_FAB2_LIB.BASEBOARD_FAB2(SCH_1):PWRGD_PVPP_KLM

RES  I213  R4B8   [RES_0402-7.87K,1.0%,1/16W,CHIPA]
    2  VR_FB_PVPP_KLM      B  @BASEBOARD_FAB2_LIB.BASEBOARD_FAB2(SCH_1):VR_FB_PVPP_KLM
    1  VR_COMP_RC_PVPP_KLM      A  @BASEBOARD_FAB2_LIB.BASEBOARD_FAB2(SCH_1):VR_COMP_RC_PVPP_KLM

RES  I219  R4B9   [RES_0402-1.0K,0.1%,1/16W,CHIP,A]
    1  VSENSE_PVPP_KLM      A  @BASEBOARD_FAB2_LIB.BASEBOARD_FAB2(SCH_1):VSENSE_PVPP_KLM
    2  VR_COMP_PVPP_KLM      B  @BASEBOARD_FAB2_LIB.BASEBOARD_FAB2(SCH_1):VR_COMP_PVPP_KLM

RES  I143  R4B10  [RES_0402-1.00K,1%,1/16W,CHIP,GA]
    2  PWRGD_PVPP_KLM_R      B  @BASEBOARD_FAB2_LIB.BASEBOARD_FAB2(SCH_1):PWRGD_PVPP_KLM_R
    1  P3V3_STBY          A  @BASEBOARD_FAB2_LIB.BASEBOARD_FAB2(SCH_1):P3V3_STBY

RES  I113  R4B11  [RES_0402-0.0,5%,1/16W,CHIP,G21A]
    1  VR_PVDDQ_DEF_AIINSEN_R      A  @BASEBOARD_FAB2_LIB.BASEBOARD_FAB2(SCH_1):VR_PVDDQ_DEF_AIINSEN_R
    2  VR_PVDDQ_DEF_AIINSEN      B  @BASEBOARD_FAB2_LIB.BASEBOARD_FAB2(SCH_1):VR_PVDDQ_DEF_AIINSEN

RES  I121  R4B12  [RES_1206-0.002,1%,1W,CHIP,G521A]
    2  P12V_STBY          B  @BASEBOARD_FAB2_LIB.BASEBOARD_FAB2(SCH_1):P12V_STBY
    1  P12V_NVDIMM_DEF      A  @BASEBOARD_FAB2_LIB.BASEBOARD_FAB2(SCH_1):P12V_NVDIMM_DEF

RES  I155  R4B13  [RES_0402-0.0,5%,1/16W,CHIP,G21A]
    2  VR_PVPP_KLM_BOOT_R      B  @BASEBOARD_FAB2_LIB.BASEBOARD_FAB2(SCH_1):VR_PVPP_KLM_BOOT_R
    1  VR_PVPP_KLM_BOOT      A  @BASEBOARD_FAB2_LIB.BASEBOARD_FAB2(SCH_1):VR_PVPP_KLM_BOOT

RES  I29  R4B14  [RES_0402-0.0,5%,1/16W,CHIP,G21A]
    1  GND                A  @BASEBOARD_FAB2_LIB.BASEBOARD_FAB2(SCH_1):GND
    2  AGND_PVPP_KLM      B  @BASEBOARD_FAB2_LIB.BASEBOARD_FAB2(SCH_1):AGND_PVPP_KLM

RES  I29  R4C1   [RES_0402-100.0,1%,1/16W,CHIP,GA]
    1  VSENSE_PVSA_CPU0_N      A  @BASEBOARD_FAB2_LIB.BASEBOARD_FAB2(SCH_1):VSENSE_PVSA_CPU0_N
    2  GND                B  @BASEBOARD_FAB2_LIB.BASEBOARD_FAB2(SCH_1):GND

RES  I30  R4C2   [RES_0402-0.0,5%,1/16W,CHIP,G21A]
    2  VSENSE_PVSA_CPU0_SKT_VRTN      B  @BASEBOARD_FAB2_LIB.BASEBOARD_FAB2(SCH_1):VSENSE_PVSA_CPU0_SKT_VRTN
    1  VSENSE_PVSA_CPU0_N      A  @BASEBOARD_FAB2_LIB.BASEBOARD_FAB2(SCH_1):VSENSE_PVSA_CPU0_N

RES  I37  R4C3   [RES_0402-1.00K,1%,1/16W,EMPTY,A]
    1  VSENSE_PVSA_CPU0_P      A  @BASEBOARD_FAB2_LIB.BASEBOARD_FAB2(SCH_1):VSENSE_PVSA_CPU0_P
    2  VSENSE_PVSA_CPU0_N      B  @BASEBOARD_FAB2_LIB.BASEBOARD_FAB2(SCH_1):VSENSE_PVSA_CPU0_N

RES  I26  R4C4   [RES_0402-0.0,5%,1/16W,CHIP,G21A]
    2  VSENSE_PVSA_CPU0_SKT_VSEN      B  @BASEBOARD_FAB2_LIB.BASEBOARD_FAB2(SCH_1):VSENSE_PVSA_CPU0_SKT_VSEN
    1  VSENSE_PVSA_CPU0_P      A  @BASEBOARD_FAB2_LIB.BASEBOARD_FAB2(SCH_1):VSENSE_PVSA_CPU0_P

RES  I24  R4C5   [RES_0402-100.0,1%,1/16W,CHIP,GA]
    1  VSENSE_PVSA_CPU0_P      A  @BASEBOARD_FAB2_LIB.BASEBOARD_FAB2(SCH_1):VSENSE_PVSA_CPU0_P
    2  PVSA_CPU0          B  @BASEBOARD_FAB2_LIB.BASEBOARD_FAB2(SCH_1):PVSA_CPU0

RES  I45  R4C6   [RES_2010-0.001,1%,1W,CHIP,E309A]
    2  VR_FET_SW_P12V_STBY_PVCCIN_CPU0      B  @BASEBOARD_FAB2_LIB.BASEBOARD_FAB2(SCH_1):VR_FET_SW_P12V_STBY_PVCCIN_CPU0
    1  VR_FET_SW_P12V_PVCCIN_CPU0_R      A  @BASEBOARD_FAB2_LIB.BASEBOARD_FAB2(SCH_1):VR_FET_SW_P12V_PVCCIN_CPU0_R

RES  I55  R4C8   [RES_0402-1.00K,1%,1/16W,CHIP,GA]
    2  PU_GTL2014_2_DIR      B  @BASEBOARD_FAB2_LIB.BASEBOARD_FAB2(SCH_1):PU_GTL2014_2_DIR
    1  P3V3_STBY          A  @BASEBOARD_FAB2_LIB.BASEBOARD_FAB2(SCH_1):P3V3_STBY

RES  I69  R4C9   [RES_0402-1.00K,1%,1/16W,CHIP,GA]
    2  PD_GTL2014_2_VREF      B  @BASEBOARD_FAB2_LIB.BASEBOARD_FAB2(SCH_1):PD_GTL2014_2_VREF
    1  GND                A  @BASEBOARD_FAB2_LIB.BASEBOARD_FAB2(SCH_1):GND

RES  I76  R4C10  [RES_0402-240,1.0%,1/16W,CHIP,GA]
    1  PVCCIO_CPU1        A  @BASEBOARD_FAB2_LIB.BASEBOARD_FAB2(SCH_1):PVCCIO_CPU1
    2  PU_CPU1_TSC_SYNC      B  @BASEBOARD_FAB2_LIB.BASEBOARD_FAB2(SCH_1):PU_CPU1_TSC_SYNC

RES  I170  R4C11  [RES_0402-3.16K,1%,1/16W,CHIP,GA]
    1  VR_PVCCMCP_CPU1_XADDR2      A  @BASEBOARD_FAB2_LIB.BASEBOARD_FAB2(SCH_1):VR_PVCCMCP_CPU1_XADDR2
    2  GND                B  @BASEBOARD_FAB2_LIB.BASEBOARD_FAB2(SCH_1):GND

RES  I169  R4C12  [RES_0402-8.06K,1%,1/16W,CHIP,GA]
    1  VR_PVCCIOMCP_CPU1_XADDR1      A  @BASEBOARD_FAB2_LIB.BASEBOARD_FAB2(SCH_1):VR_PVCCIOMCP_CPU1_XADDR1
    2  GND                B  @BASEBOARD_FAB2_LIB.BASEBOARD_FAB2(SCH_1):GND

RES  I62  R4C13  [RES_0402-68.1K,1%,1/16W,EMPTY,A]
    1  VR_PVSA_CPU0_OCSET      A  @BASEBOARD_FAB2_LIB.BASEBOARD_FAB2(SCH_1):VR_PVSA_CPU0_OCSET
    2  GND                B  @BASEBOARD_FAB2_LIB.BASEBOARD_FAB2(SCH_1):GND

RES  I54  R4D1   [RES_0402-27.4,1%,1/16W,CHIP,G2A]
    1  CLK_100M_CPU1_BCLK1_R_DN      A  @BASEBOARD_FAB2_LIB.BASEBOARD_FAB2(SCH_1):CLK_100M_CPU1_BCLK1_R_DN
    2  CLK_100M_CPU1_BCLK1_DN      B  @BASEBOARD_FAB2_LIB.BASEBOARD_FAB2(SCH_1):CLK_100M_CPU1_BCLK1_DN

RES  I49  R4D2   [RES_0402-27.4,1%,1/16W,CHIP,G2A]
    1  CLK_100M_CPU1_BCLK1_R_DP      A  @BASEBOARD_FAB2_LIB.BASEBOARD_FAB2(SCH_1):CLK_100M_CPU1_BCLK1_R_DP
    2  CLK_100M_CPU1_BCLK1_DP      B  @BASEBOARD_FAB2_LIB.BASEBOARD_FAB2(SCH_1):CLK_100M_CPU1_BCLK1_DP

RES  I64  R4D3   [RES_0402-27.4,1%,1/16W,CHIP,G2A]
    1  CLK_100M_CPU1_BCLK0_R_DN      A  @BASEBOARD_FAB2_LIB.BASEBOARD_FAB2(SCH_1):CLK_100M_CPU1_BCLK0_R_DN
    2  CLK_100M_CPU1_BCLK0_DN      B  @BASEBOARD_FAB2_LIB.BASEBOARD_FAB2(SCH_1):CLK_100M_CPU1_BCLK0_DN

RES  I59  R4D4   [RES_0402-27.4,1%,1/16W,CHIP,G2A]
    1  CLK_100M_CPU1_BCLK0_R_DP      A  @BASEBOARD_FAB2_LIB.BASEBOARD_FAB2(SCH_1):CLK_100M_CPU1_BCLK0_R_DP
    2  CLK_100M_CPU1_BCLK0_DP      B  @BASEBOARD_FAB2_LIB.BASEBOARD_FAB2(SCH_1):CLK_100M_CPU1_BCLK0_DP

RES  I79  R4D5   [RES_0402-27.4,1%,1/16W,CHIP,G2A]
    1  CLK_100M_CPU0_RC_REFCLK1_R_DN      A  @BASEBOARD_FAB2_LIB.BASEBOARD_FAB2(SCH_1):CLK_100M_CPU0_RC_REFCLK1_R_DN
    2  CLK_100M_CPU0_RC_REFCLK1_DN      B  @BASEBOARD_FAB2_LIB.BASEBOARD_FAB2(SCH_1):CLK_100M_CPU0_RC_REFCLK1_DN

RES  I74  R4D6   [RES_0402-27.4,1%,1/16W,CHIP,G2A]
    1  CLK_100M_CPU0_RC_REFCLK1_R_DP      A  @BASEBOARD_FAB2_LIB.BASEBOARD_FAB2(SCH_1):CLK_100M_CPU0_RC_REFCLK1_R_DP
    2  CLK_100M_CPU0_RC_REFCLK1_DP      B  @BASEBOARD_FAB2_LIB.BASEBOARD_FAB2(SCH_1):CLK_100M_CPU0_RC_REFCLK1_DP

RES  I89  R4D7   [RES_0402-27.4,1%,1/16W,CHIP,G2A]
    1  CLK_100M_CPU0_RC_REFCLK0_R_DN      A  @BASEBOARD_FAB2_LIB.BASEBOARD_FAB2(SCH_1):CLK_100M_CPU0_RC_REFCLK0_R_DN
    2  CLK_100M_CPU0_RC_REFCLK0_DN      B  @BASEBOARD_FAB2_LIB.BASEBOARD_FAB2(SCH_1):CLK_100M_CPU0_RC_REFCLK0_DN

RES  I84  R4D8   [RES_0402-27.4,1%,1/16W,CHIP,G2A]
    1  CLK_100M_CPU0_RC_REFCLK0_R_DP      A  @BASEBOARD_FAB2_LIB.BASEBOARD_FAB2(SCH_1):CLK_100M_CPU0_RC_REFCLK0_R_DP
    2  CLK_100M_CPU0_RC_REFCLK0_DP      B  @BASEBOARD_FAB2_LIB.BASEBOARD_FAB2(SCH_1):CLK_100M_CPU0_RC_REFCLK0_DP

RES  I39  R4D9   [RES_0402-27.4,1%,1/16W,CHIP,G2A]
    1  CLK_100M_CPU1_BCLK2_R_DP      A  @BASEBOARD_FAB2_LIB.BASEBOARD_FAB2(SCH_1):CLK_100M_CPU1_BCLK2_R_DP
    2  CLK_100M_CPU1_BCLK2_DP      B  @BASEBOARD_FAB2_LIB.BASEBOARD_FAB2(SCH_1):CLK_100M_CPU1_BCLK2_DP

RES  I99  R4D10  [RES_0402-27.4,1%,1/16W,CHIP,G2A]
    1  CLK_100M_CPU0_PE_REFCLK_R_DN      A  @BASEBOARD_FAB2_LIB.BASEBOARD_FAB2(SCH_1):CLK_100M_CPU0_PE_REFCLK_R_DN
    2  CLK_100M_CPU0_PE_REFCLK_DN      B  @BASEBOARD_FAB2_LIB.BASEBOARD_FAB2(SCH_1):CLK_100M_CPU0_PE_REFCLK_DN

RES  I44  R4D11  [RES_0402-27.4,1%,1/16W,CHIP,G2A]
    1  CLK_100M_CPU1_BCLK2_R_DN      A  @BASEBOARD_FAB2_LIB.BASEBOARD_FAB2(SCH_1):CLK_100M_CPU1_BCLK2_R_DN
    2  CLK_100M_CPU1_BCLK2_DN      B  @BASEBOARD_FAB2_LIB.BASEBOARD_FAB2(SCH_1):CLK_100M_CPU1_BCLK2_DN

RES  I94  R4D12  [RES_0402-27.4,1%,1/16W,CHIP,G2A]
    1  CLK_100M_CPU0_PE_REFCLK_R_DP      A  @BASEBOARD_FAB2_LIB.BASEBOARD_FAB2(SCH_1):CLK_100M_CPU0_PE_REFCLK_R_DP
    2  CLK_100M_CPU0_PE_REFCLK_DP      B  @BASEBOARD_FAB2_LIB.BASEBOARD_FAB2(SCH_1):CLK_100M_CPU0_PE_REFCLK_DP

RES  I29  R4D13  [RES_0402-27.4,1%,1/16W,CHIP,G2A]
    1  CLK_100M_CPU1_PE_REFCLK_R_DP      A  @BASEBOARD_FAB2_LIB.BASEBOARD_FAB2(SCH_1):CLK_100M_CPU1_PE_REFCLK_R_DP
    2  CLK_100M_CPU1_PE_REFCLK_DP      B  @BASEBOARD_FAB2_LIB.BASEBOARD_FAB2(SCH_1):CLK_100M_CPU1_PE_REFCLK_DP

RES  I109  R4D14  [RES_0402-27.4,1%,1/16W,CHIP,G2A]
    1  CLK_100M_CPU0_BCLK2_R_DN      A  @BASEBOARD_FAB2_LIB.BASEBOARD_FAB2(SCH_1):CLK_100M_CPU0_BCLK2_R_DN
    2  CLK_100M_CPU0_BCLK2_DN      B  @BASEBOARD_FAB2_LIB.BASEBOARD_FAB2(SCH_1):CLK_100M_CPU0_BCLK2_DN

RES  I34  R4D16  [RES_0402-27.4,1%,1/16W,CHIP,G2A]
    1  CLK_100M_CPU1_PE_REFCLK_R_DN      A  @BASEBOARD_FAB2_LIB.BASEBOARD_FAB2(SCH_1):CLK_100M_CPU1_PE_REFCLK_R_DN
    2  CLK_100M_CPU1_PE_REFCLK_DN      B  @BASEBOARD_FAB2_LIB.BASEBOARD_FAB2(SCH_1):CLK_100M_CPU1_PE_REFCLK_DN

RES  I104  R4D17  [RES_0402-27.4,1%,1/16W,CHIP,G2A]
    1  CLK_100M_CPU0_BCLK2_R_DP      A  @BASEBOARD_FAB2_LIB.BASEBOARD_FAB2(SCH_1):CLK_100M_CPU0_BCLK2_R_DP
    2  CLK_100M_CPU0_BCLK2_DP      B  @BASEBOARD_FAB2_LIB.BASEBOARD_FAB2(SCH_1):CLK_100M_CPU0_BCLK2_DP

RES  I163  R4D18  [RES_0402-42.2,1.0%,1/16W,EMPTYA]
    2  GND                B  @BASEBOARD_FAB2_LIB.BASEBOARD_FAB2(SCH_1):GND
    1  CLK_100M_CPU0_BCLK1_DN      A  @BASEBOARD_FAB2_LIB.BASEBOARD_FAB2(SCH_1):CLK_100M_CPU0_BCLK1_DN

RES  I19  R4D19  [RES_0402-27.4,1%,1/16W,CHIP,G2A]
    1  CLK_100M_CPU1_RC_REFCLK0_R_DP      A  @BASEBOARD_FAB2_LIB.BASEBOARD_FAB2(SCH_1):CLK_100M_CPU1_RC_REFCLK0_R_DP
    2  CLK_100M_CPU1_RC_REFCLK0_DP      B  @BASEBOARD_FAB2_LIB.BASEBOARD_FAB2(SCH_1):CLK_100M_CPU1_RC_REFCLK0_DP

RES  I119  R4D20  [RES_0402-27.4,1%,1/16W,CHIP,G2A]
    1  CLK_100M_CPU0_BCLK1_R_DN      A  @BASEBOARD_FAB2_LIB.BASEBOARD_FAB2(SCH_1):CLK_100M_CPU0_BCLK1_R_DN
    2  CLK_100M_CPU0_BCLK1_DN      B  @BASEBOARD_FAB2_LIB.BASEBOARD_FAB2(SCH_1):CLK_100M_CPU0_BCLK1_DN

RES  I24  R4D21  [RES_0402-27.4,1%,1/16W,CHIP,G2A]
    1  CLK_100M_CPU1_RC_REFCLK0_R_DN      A  @BASEBOARD_FAB2_LIB.BASEBOARD_FAB2(SCH_1):CLK_100M_CPU1_RC_REFCLK0_R_DN
    2  CLK_100M_CPU1_RC_REFCLK0_DN      B  @BASEBOARD_FAB2_LIB.BASEBOARD_FAB2(SCH_1):CLK_100M_CPU1_RC_REFCLK0_DN

RES  I114  R4D22  [RES_0402-27.4,1%,1/16W,CHIP,G2A]
    1  CLK_100M_CPU0_BCLK1_R_DP      A  @BASEBOARD_FAB2_LIB.BASEBOARD_FAB2(SCH_1):CLK_100M_CPU0_BCLK1_R_DP
    2  CLK_100M_CPU0_BCLK1_DP      B  @BASEBOARD_FAB2_LIB.BASEBOARD_FAB2(SCH_1):CLK_100M_CPU0_BCLK1_DP

RES  I9   R4D23  [RES_0402-27.4,1%,1/16W,CHIP,G2A]
    1  CLK_100M_CPU1_RC_REFCLK1_R_DP      A  @BASEBOARD_FAB2_LIB.BASEBOARD_FAB2(SCH_1):CLK_100M_CPU1_RC_REFCLK1_R_DP
    2  CLK_100M_CPU1_RC_REFCLK1_DP      B  @BASEBOARD_FAB2_LIB.BASEBOARD_FAB2(SCH_1):CLK_100M_CPU1_RC_REFCLK1_DP

RES  I161  R4D24  [RES_0402-42.2,1.0%,1/16W,EMPTYA]
    2  GND                B  @BASEBOARD_FAB2_LIB.BASEBOARD_FAB2(SCH_1):GND
    1  CLK_100M_CPU0_BCLK1_DP      A  @BASEBOARD_FAB2_LIB.BASEBOARD_FAB2(SCH_1):CLK_100M_CPU0_BCLK1_DP

RES  I1   R4D25  [RES_0402-27.4,1%,1/16W,CHIP,G2A]
    1  CLK_100M_CPU0_BCLK0_R_DN      A  @BASEBOARD_FAB2_LIB.BASEBOARD_FAB2(SCH_1):CLK_100M_CPU0_BCLK0_R_DN
    2  CLK_100M_CPU0_BCLK0_DN      B  @BASEBOARD_FAB2_LIB.BASEBOARD_FAB2(SCH_1):CLK_100M_CPU0_BCLK0_DN

RES  I40  R4D26  [RES_0402-0.0,5%,1/16W,CHIP,G21A]
    2  VR_PVCCIN_CPU0_VDD      B  @BASEBOARD_FAB2_LIB.BASEBOARD_FAB2(SCH_1):VR_PVCCIN_CPU0_VDD
    1  P3V3_STBY          A  @BASEBOARD_FAB2_LIB.BASEBOARD_FAB2(SCH_1):P3V3_STBY

RES  I54  R4D27  [RES_0402-100.0K,1%,1/16W,CHIP,B]
    2  VR_PVCCIN_CPU0_AVINSEN      B  @BASEBOARD_FAB2_LIB.BASEBOARD_FAB2(SCH_1):VR_PVCCIN_CPU0_AVINSEN
    1  VR_FET_SW_P12V_STBY_PVCCIN_CPU0      A  @BASEBOARD_FAB2_LIB.BASEBOARD_FAB2(SCH_1):VR_FET_SW_P12V_STBY_PVCCIN_CPU0

RES  I14  R4D28  [RES_0402-27.4,1%,1/16W,CHIP,G2A]
    1  CLK_100M_CPU1_RC_REFCLK1_R_DN      A  @BASEBOARD_FAB2_LIB.BASEBOARD_FAB2(SCH_1):CLK_100M_CPU1_RC_REFCLK1_R_DN
    2  CLK_100M_CPU1_RC_REFCLK1_DN      B  @BASEBOARD_FAB2_LIB.BASEBOARD_FAB2(SCH_1):CLK_100M_CPU1_RC_REFCLK1_DN

RES  I69  R4D29  [RES_0402-27.4,1%,1/16W,CHIP,G2A]
    1  CLK_100M_CPU0_BCLK0_R_DP      A  @BASEBOARD_FAB2_LIB.BASEBOARD_FAB2(SCH_1):CLK_100M_CPU0_BCLK0_R_DP
    2  CLK_100M_CPU0_BCLK0_DP      B  @BASEBOARD_FAB2_LIB.BASEBOARD_FAB2(SCH_1):CLK_100M_CPU0_BCLK0_DP

RES  I22  R4D31  [RES_0402-2.26K,1.0%,1/16W,EMPTA]
    2  PU_VR_PVCCIN_CPU0_IMON      B  @BASEBOARD_FAB2_LIB.BASEBOARD_FAB2(SCH_1):PU_VR_PVCCIN_CPU0_IMON
    1  P3V3_STBY          A  @BASEBOARD_FAB2_LIB.BASEBOARD_FAB2(SCH_1):P3V3_STBY

RES  I55  R4D32  [RES_0402-1.5K,1%,1/16W,CHIP,G2A]
    1  VR_PVCCIN_CPU0_AVINSEN      A  @BASEBOARD_FAB2_LIB.BASEBOARD_FAB2(SCH_1):VR_PVCCIN_CPU0_AVINSEN
    2  GND                B  @BASEBOARD_FAB2_LIB.BASEBOARD_FAB2(SCH_1):GND

RES  I38  R4D35  [RES_0402-10.0K,1%,1/16W,EMPTY,A]
    1  P3V3_DB1200        A  @BASEBOARD_FAB2_LIB.BASEBOARD_FAB2(SCH_1):P3V3_DB1200
    2  FM_DB1200_SMB_SA0      B  @BASEBOARD_FAB2_LIB.BASEBOARD_FAB2(SCH_1):FM_DB1200_SMB_SA0

RES  I82  R4D36  [RES_0402-33.2,1%,1/16W,CHIP,G2A]
    2  SMB_HOST_STBY_LVC3_SDA_R2      B  @BASEBOARD_FAB2_LIB.BASEBOARD_FAB2(SCH_1):SMB_HOST_STBY_LVC3_SDA_R2
    1  SMB_HOST_STBY_LVC3_SDA      A  @BASEBOARD_FAB2_LIB.BASEBOARD_FAB2(SCH_1):SMB_HOST_STBY_LVC3_SDA

RES  I87  R4D37  [RES_0402-33.2,1%,1/16W,CHIP,G2A]
    2  SMB_HOST_STBY_LVC3_SCL_R2      B  @BASEBOARD_FAB2_LIB.BASEBOARD_FAB2(SCH_1):SMB_HOST_STBY_LVC3_SCL_R2
    1  SMB_HOST_STBY_LVC3_SCL      A  @BASEBOARD_FAB2_LIB.BASEBOARD_FAB2(SCH_1):SMB_HOST_STBY_LVC3_SCL

RES  I37  R4D38  [RES_0402-10.0K,1%,1/16W,EMPTY,A]
    1  P3V3_DB1200        A  @BASEBOARD_FAB2_LIB.BASEBOARD_FAB2(SCH_1):P3V3_DB1200
    2  FM_DB1200_SMB_SA1      B  @BASEBOARD_FAB2_LIB.BASEBOARD_FAB2(SCH_1):FM_DB1200_SMB_SA1

RES  I110  R4D39  [RES_0402-10.0,1%,1/16W,CHIP,G2A]
    1  VSENSE_PVSA_CPU0_P      A  @BASEBOARD_FAB2_LIB.BASEBOARD_FAB2(SCH_1):VSENSE_PVSA_CPU0_P
    2  VSENSE_PVSA_CPU0_BVSP      B  @BASEBOARD_FAB2_LIB.BASEBOARD_FAB2(SCH_1):VSENSE_PVSA_CPU0_BVSP

RES  I45  R4D40  [RES_0402-4.75K,1%,1/16W,CHIP,GA]
    1  P3V3_DB1200        A  @BASEBOARD_FAB2_LIB.BASEBOARD_FAB2(SCH_1):P3V3_DB1200
    2  FM_100M_N          B  @BASEBOARD_FAB2_LIB.BASEBOARD_FAB2(SCH_1):FM_100M_N

RES  I53  R4D41  [RES_0402-4.75K,1%,1/16W,CHIP,GA]
    1  P3V3_DB1200        A  @BASEBOARD_FAB2_LIB.BASEBOARD_FAB2(SCH_1):P3V3_DB1200
    2  FM_HBW_BYPASS_LOWBW_N      B  @BASEBOARD_FAB2_LIB.BASEBOARD_FAB2(SCH_1):FM_HBW_BYPASS_LOWBW_N

RES  I15  R4D42  [RES_0402-1.00K,1%,1/16W,CHIP,GA]
    2  PWRGD_PVCCIO_CPU1_R      B  @BASEBOARD_FAB2_LIB.BASEBOARD_FAB2(SCH_1):PWRGD_PVCCIO_CPU1_R
    1  P3V3_STBY          A  @BASEBOARD_FAB2_LIB.BASEBOARD_FAB2(SCH_1):P3V3_STBY

RES  I39  R4D43  [RES_0402-20.0,1%,1/16W,CHIP,G2A]
    1  SMB_VR_STBY_LVC3_SCL      A  @BASEBOARD_FAB2_LIB.BASEBOARD_FAB2(SCH_1):SMB_VR_STBY_LVC3_SCL
    2  SMB_VR_SCL_PVCCIO_CPU1      B  @BASEBOARD_FAB2_LIB.BASEBOARD_FAB2(SCH_1):SMB_VR_SCL_PVCCIO_CPU1

RES  I38  R4D44  [RES_0402-20.0,1%,1/16W,CHIP,G2A]
    1  SMB_VR_STBY_LVC3_SDA      A  @BASEBOARD_FAB2_LIB.BASEBOARD_FAB2(SCH_1):SMB_VR_STBY_LVC3_SDA
    2  SMB_VR_SDA_PVCCIO_CPU1      B  @BASEBOARD_FAB2_LIB.BASEBOARD_FAB2(SCH_1):SMB_VR_SDA_PVCCIO_CPU1

RES  I94  R4D45  [RES_0402-0.0,5%,1/16W,CHIP,G21A]
    1  VR_PVCCIO_CPU1_VD12      A  @BASEBOARD_FAB2_LIB.BASEBOARD_FAB2(SCH_1):VR_PVCCIO_CPU1_VD12
    2  VR_PVCCIO_CPU1_AIREF1      B  @BASEBOARD_FAB2_LIB.BASEBOARD_FAB2(SCH_1):VR_PVCCIO_CPU1_AIREF1

RES  I13  R4D46  [RES_0402-22.1,1.0%,1/16W,CHIP,A]
    1  PWRGD_PVCCIO_CPU1_R      A  @BASEBOARD_FAB2_LIB.BASEBOARD_FAB2(SCH_1):PWRGD_PVCCIO_CPU1_R
    2  PWRGD_PVCCIO_CPU1      B  @BASEBOARD_FAB2_LIB.BASEBOARD_FAB2(SCH_1):PWRGD_PVCCIO_CPU1

RES  I25  R4D47  [RES_0402-0.0,5%,1/16W,CHIP,G21A]
    2  VR_PVCCIO_CPU1_VDD      B  @BASEBOARD_FAB2_LIB.BASEBOARD_FAB2(SCH_1):VR_PVCCIO_CPU1_VDD
    1  P3V3_STBY          A  @BASEBOARD_FAB2_LIB.BASEBOARD_FAB2(SCH_1):P3V3_STBY

RES  I63  R4D49  [RES_0402-1.00K,1%,1/16W,CHIP,GA]
    1  P3V3_STBY          A  @BASEBOARD_FAB2_LIB.BASEBOARD_FAB2(SCH_1):P3V3_STBY
    2  IRQ_PVCCIO_CPU1_VRHOT_N      B  @BASEBOARD_FAB2_LIB.BASEBOARD_FAB2(SCH_1):IRQ_PVCCIO_CPU1_VRHOT_N

RES  I28  R4D50  [RES_0402-0.0,5%,1/16W,CHIP,G21A]
    2  SMB_VR_STBY_LVC3_SDA      B  @BASEBOARD_FAB2_LIB.BASEBOARD_FAB2(SCH_1):SMB_VR_STBY_LVC3_SDA
    1  SMB_VR_SDA_R       A  @BASEBOARD_FAB2_LIB.BASEBOARD_FAB2(SCH_1):SMB_VR_SDA_R

RES  I46  R4D51  [RES_0402-150.0,1%,1/16W,CHIP,GA]
    2  SVID_CLK_PVCCIO_CPU1      B  @BASEBOARD_FAB2_LIB.BASEBOARD_FAB2(SCH_1):SVID_CLK_PVCCIO_CPU1
    1  SVID_CLK0_CPU1_R      A  @BASEBOARD_FAB2_LIB.BASEBOARD_FAB2(SCH_1):SVID_CLK0_CPU1_R

RES  I31  R4D53  [RES_0402-0.0,5%,1/16W,CHIP,G21A]
    2  SMB_VR_STBY_LVC3_SCL      B  @BASEBOARD_FAB2_LIB.BASEBOARD_FAB2(SCH_1):SMB_VR_STBY_LVC3_SCL
    1  SMB_VR_SCL_R       A  @BASEBOARD_FAB2_LIB.BASEBOARD_FAB2(SCH_1):SMB_VR_SCL_R

RES  I37  R4D54  [RES_0402-0.0,5%,1/16W,CHIP,G21A]
    2  SVID_VDIO_PVCCIO_CPU1      B  @BASEBOARD_FAB2_LIB.BASEBOARD_FAB2(SCH_1):SVID_VDIO_PVCCIO_CPU1
    1  SVID_DIO0_CPU1_R      A  @BASEBOARD_FAB2_LIB.BASEBOARD_FAB2(SCH_1):SVID_DIO0_CPU1_R

RES  I16  R4D56  [RES_0402-0.0,5%,1/16W,CHIP,G21A]
    1  SVID_ALERT_PVCCIO_CPU1      A  @BASEBOARD_FAB2_LIB.BASEBOARD_FAB2(SCH_1):SVID_ALERT_PVCCIO_CPU1
    2  SVID_ALERT0_CPU1_R_N      B  @BASEBOARD_FAB2_LIB.BASEBOARD_FAB2(SCH_1):SVID_ALERT0_CPU1_R_N

RES  I32  R4D57  [RES_0402-1.5K,1%,1/16W,CHIP,G2A]
    1  VR_PVCCIO_CPU1_VINSEN      A  @BASEBOARD_FAB2_LIB.BASEBOARD_FAB2(SCH_1):VR_PVCCIO_CPU1_VINSEN
    2  GND                B  @BASEBOARD_FAB2_LIB.BASEBOARD_FAB2(SCH_1):GND

RES  I25  R4D58  [RES_0402-1.00K,1%,1/16W,CHIP,GA]
    2  VR_VRRDY_PVCCIN_CPU0      B  @BASEBOARD_FAB2_LIB.BASEBOARD_FAB2(SCH_1):VR_VRRDY_PVCCIN_CPU0
    1  P3V3_STBY          A  @BASEBOARD_FAB2_LIB.BASEBOARD_FAB2(SCH_1):P3V3_STBY

RES  I31  R4D60  [RES_0402-100.0K,1%,1/16W,CHIP,B]
    2  VR_PVCCIO_CPU1_VINSEN      B  @BASEBOARD_FAB2_LIB.BASEBOARD_FAB2(SCH_1):VR_PVCCIO_CPU1_VINSEN
    1  VR_FET_SW_P12V_STBY_PVCCIN_CPU0      A  @BASEBOARD_FAB2_LIB.BASEBOARD_FAB2(SCH_1):VR_FET_SW_P12V_STBY_PVCCIN_CPU0

RES  I124  R4D63  [RES_0402-22.1,1.0%,1/16W,CHIP,A]
    1  VR_VRRDY_PVCCIN_CPU0      A  @BASEBOARD_FAB2_LIB.BASEBOARD_FAB2(SCH_1):VR_VRRDY_PVCCIN_CPU0
    2  PWRGD_PVCCIN_CPU0      B  @BASEBOARD_FAB2_LIB.BASEBOARD_FAB2(SCH_1):PWRGD_PVCCIN_CPU0

RES  I42  R4D64  [RES_0402-3.16K,1%,1/16W,CHIP,GA]
    1  VR_PVCCIO_CPU1_XADDR1      A  @BASEBOARD_FAB2_LIB.BASEBOARD_FAB2(SCH_1):VR_PVCCIO_CPU1_XADDR1
    2  GND                B  @BASEBOARD_FAB2_LIB.BASEBOARD_FAB2(SCH_1):GND

RES  I127  R4D65  [RES_0402-33.2,1%,1/16W,CHIP,G2A]
    1  PWRGD_PVSA_CPU0_R      A  @BASEBOARD_FAB2_LIB.BASEBOARD_FAB2(SCH_1):PWRGD_PVSA_CPU0_R
    2  PWRGD_PVSA_CPU0      B  @BASEBOARD_FAB2_LIB.BASEBOARD_FAB2(SCH_1):PWRGD_PVSA_CPU0

RES  I98  R4D66  [RES_0402-0.0,5%,1/16W,CHIP,G21A]
    1  SVID_VDIO_PVCCIN_CPU0      A  @BASEBOARD_FAB2_LIB.BASEBOARD_FAB2(SCH_1):SVID_VDIO_PVCCIN_CPU0
    2  SVID_DIO0_CPU0_R      B  @BASEBOARD_FAB2_LIB.BASEBOARD_FAB2(SCH_1):SVID_DIO0_CPU0_R

RES  I26  R4D67  [RES_0402-0.0,5%,1/16W,CHIP,G21A]
    1  SVID_VALERT_VCCIN_CPU0      A  @BASEBOARD_FAB2_LIB.BASEBOARD_FAB2(SCH_1):SVID_VALERT_VCCIN_CPU0
    2  SVID_ALERT0_CPU0_R_N      B  @BASEBOARD_FAB2_LIB.BASEBOARD_FAB2(SCH_1):SVID_ALERT0_CPU0_R_N

RES  I83  R4D68  [RES_0402-68.1K,1%,1/16W,EMPTY,A]
    1  VR_PVCCIN_CPU0_PH5_OCSET      A  @BASEBOARD_FAB2_LIB.BASEBOARD_FAB2(SCH_1):VR_PVCCIN_CPU0_PH5_OCSET
    2  GND                B  @BASEBOARD_FAB2_LIB.BASEBOARD_FAB2(SCH_1):GND

RES  I93  R4D69  [RES_0402-4.75K,1%,1/16W,CHIP,GA]
    1  P3V3               A  @BASEBOARD_FAB2_LIB.BASEBOARD_FAB2(SCH_1):P3V3
    2  FM_CPU1_MCP_CLK_EN_N      B  @BASEBOARD_FAB2_LIB.BASEBOARD_FAB2(SCH_1):FM_CPU1_MCP_CLK_EN_N

RES  I94  R4D70  [RES_0402-4.75K,1%,1/16W,CHIP,GA]
    1  P3V3               A  @BASEBOARD_FAB2_LIB.BASEBOARD_FAB2(SCH_1):P3V3
    2  FM_CPU0_MCP_CLK_EN_N      B  @BASEBOARD_FAB2_LIB.BASEBOARD_FAB2(SCH_1):FM_CPU0_MCP_CLK_EN_N

RES  I91  R4D71  [RES_0402-68.1K,1%,1/16W,EMPTY,A]
    1  VR_PVCCIN_CPU0_PH4_OCSET      A  @BASEBOARD_FAB2_LIB.BASEBOARD_FAB2(SCH_1):VR_PVCCIN_CPU0_PH4_OCSET
    2  GND                B  @BASEBOARD_FAB2_LIB.BASEBOARD_FAB2(SCH_1):GND

RES  I89  R4D72  [RES_0402-68.1K,1%,1/16W,EMPTY,A]
    1  VR_PVCCIN_CPU0_PH3_OCSET      A  @BASEBOARD_FAB2_LIB.BASEBOARD_FAB2(SCH_1):VR_PVCCIN_CPU0_PH3_OCSET
    2  GND                B  @BASEBOARD_FAB2_LIB.BASEBOARD_FAB2(SCH_1):GND

RES  I65  R4E2   [RES_0402-3.16K,1%,1/16W,CHIP,GA]
    1  VR_PVCCIO_CPU1_XADDR2      A  @BASEBOARD_FAB2_LIB.BASEBOARD_FAB2(SCH_1):VR_PVCCIO_CPU1_XADDR2
    2  GND                B  @BASEBOARD_FAB2_LIB.BASEBOARD_FAB2(SCH_1):GND

RES  I111  R4E3   [RES_0402-1.00K,1%,1/16W,CHIP,GA]
    1  P3V3_STBY          A  @BASEBOARD_FAB2_LIB.BASEBOARD_FAB2(SCH_1):P3V3_STBY
    2  IRQ_PVCCIN_CPU0_VRHOT_LVC3_R_N      B  @BASEBOARD_FAB2_LIB.BASEBOARD_FAB2(SCH_1):IRQ_PVCCIN_CPU0_VRHOT_LVC3_R_N

RES  I19  R4E4   [RES_0402-2.26K,1.0%,1/16W,CHIPA]
    1  P3V3_STBY          A  @BASEBOARD_FAB2_LIB.BASEBOARD_FAB2(SCH_1):P3V3_STBY
    2  FM_PVCCIN_CPU0_PWR_IN_ALERT_N      B  @BASEBOARD_FAB2_LIB.BASEBOARD_FAB2(SCH_1):FM_PVCCIN_CPU0_PWR_IN_ALERT_N

RES  I27  R4E5   [RES_0402-1.00K,1%,1/16W,CHIP,GA]
    2  PWRGD_PVSA_CPU0_R      B  @BASEBOARD_FAB2_LIB.BASEBOARD_FAB2(SCH_1):PWRGD_PVSA_CPU0_R
    1  P3V3_STBY          A  @BASEBOARD_FAB2_LIB.BASEBOARD_FAB2(SCH_1):P3V3_STBY

RES  I56  R4E6   [RES_0402-150.0,1%,1/16W,CHIP,GA]
    2  SVID_VCLK_PVCCIN_CPU0      B  @BASEBOARD_FAB2_LIB.BASEBOARD_FAB2(SCH_1):SVID_VCLK_PVCCIN_CPU0
    1  SVID_CLK0_CPU0_R      A  @BASEBOARD_FAB2_LIB.BASEBOARD_FAB2(SCH_1):SVID_CLK0_CPU0_R

RES  I84  R4E7   [RES_0402-10.0,1%,1/16W,CHIP,G2A]
    1  VSENSE_PVCCIO_CPU1_AVSP      A  @BASEBOARD_FAB2_LIB.BASEBOARD_FAB2(SCH_1):VSENSE_PVCCIO_CPU1_AVSP
    2  VR_PVCCIO_CPU1_AVSP      B  @BASEBOARD_FAB2_LIB.BASEBOARD_FAB2(SCH_1):VR_PVCCIO_CPU1_AVSP

RES  I109  R4E8   [RES_0402-10.0,1%,1/16W,CHIP,G2A]
    1  VSENSE_PVCCIN_CPU0_P      A  @BASEBOARD_FAB2_LIB.BASEBOARD_FAB2(SCH_1):VSENSE_PVCCIN_CPU0_P
    2  VSENSE_PVCCIN_CPU0_AVSP      B  @BASEBOARD_FAB2_LIB.BASEBOARD_FAB2(SCH_1):VSENSE_PVCCIN_CPU0_AVSP

RES  I52  R4E9   [RES_0402-49.9,1%,1/16W,CHIP,G2A]
    2  SVID_CLK0_CPU0_R      B  @BASEBOARD_FAB2_LIB.BASEBOARD_FAB2(SCH_1):SVID_CLK0_CPU0_R
    1  PVCCIO_CPU0        A  @BASEBOARD_FAB2_LIB.BASEBOARD_FAB2(SCH_1):PVCCIO_CPU0

RES  I20  R4E10  [RES_0402-100.0,1%,1/16W,CHIP,GA]
    2  SVID_DIO0_CPU0_R      B  @BASEBOARD_FAB2_LIB.BASEBOARD_FAB2(SCH_1):SVID_DIO0_CPU0_R
    1  PVCCIO_CPU0        A  @BASEBOARD_FAB2_LIB.BASEBOARD_FAB2(SCH_1):PVCCIO_CPU0

RES  I67  R4E13  [RES_0603-100.0,1%,1/10W,CHIP,GA]
    1  PVCCIN_CPU0        A  @BASEBOARD_FAB2_LIB.BASEBOARD_FAB2(SCH_1):PVCCIN_CPU0
    2  GND                B  @BASEBOARD_FAB2_LIB.BASEBOARD_FAB2(SCH_1):GND

RES  I60  R4E14  [RES_0402-100.0,1%,1/16W,CHIP,GA]
    1  VSENSE_PVCCIN_CPU0_P      A  @BASEBOARD_FAB2_LIB.BASEBOARD_FAB2(SCH_1):VSENSE_PVCCIN_CPU0_P
    2  PVCCIN_CPU0        B  @BASEBOARD_FAB2_LIB.BASEBOARD_FAB2(SCH_1):PVCCIN_CPU0

RES  I63  R4E15  [RES_0402-1.00K,1%,1/16W,EMPTY,A]
    1  VSENSE_PVCCIN_CPU0_P      A  @BASEBOARD_FAB2_LIB.BASEBOARD_FAB2(SCH_1):VSENSE_PVCCIN_CPU0_P
    2  VSENSE_PVCCIN_CPU0_N      B  @BASEBOARD_FAB2_LIB.BASEBOARD_FAB2(SCH_1):VSENSE_PVCCIN_CPU0_N

RES  I61  R4E16  [RES_0402-0.0,5%,1/16W,CHIP,G21A]
    2  VSENSE_PVCCIN_CPU0_SKT_VSEN      B  @BASEBOARD_FAB2_LIB.BASEBOARD_FAB2(SCH_1):VSENSE_PVCCIN_CPU0_SKT_VSEN
    1  VSENSE_PVCCIN_CPU0_P      A  @BASEBOARD_FAB2_LIB.BASEBOARD_FAB2(SCH_1):VSENSE_PVCCIN_CPU0_P

RES  I62  R4E17  [RES_0402-0.0,5%,1/16W,CHIP,G21A]
    2  VSENSE_PVCCIN_CPU0_SKT_VRTN      B  @BASEBOARD_FAB2_LIB.BASEBOARD_FAB2(SCH_1):VSENSE_PVCCIN_CPU0_SKT_VRTN
    1  VSENSE_PVCCIN_CPU0_N      A  @BASEBOARD_FAB2_LIB.BASEBOARD_FAB2(SCH_1):VSENSE_PVCCIN_CPU0_N

RES  I64  R4E18  [RES_0402-100.0,1%,1/16W,CHIP,GA]
    1  VSENSE_PVCCIN_CPU0_N      A  @BASEBOARD_FAB2_LIB.BASEBOARD_FAB2(SCH_1):VSENSE_PVCCIN_CPU0_N
    2  GND                B  @BASEBOARD_FAB2_LIB.BASEBOARD_FAB2(SCH_1):GND

RES  I67  R4E19  [RES_0402-68.1K,1%,1/16W,EMPTY,A]
    1  VR_PVCCIN_CPU0_PH2_OCSET      A  @BASEBOARD_FAB2_LIB.BASEBOARD_FAB2(SCH_1):VR_PVCCIN_CPU0_PH2_OCSET
    2  GND                B  @BASEBOARD_FAB2_LIB.BASEBOARD_FAB2(SCH_1):GND

RES  I116  R4E20  [RES_0402-2.26K,1.0%,1/16W,EMPTA]
    2  PU_VR_PVCCIN_CPU0_FLT1_SMBALT_N      B  @BASEBOARD_FAB2_LIB.BASEBOARD_FAB2(SCH_1):PU_VR_PVCCIN_CPU0_FLT1_SMBALT_N_IMON
    1  P3V3_STBY          A  @BASEBOARD_FAB2_LIB.BASEBOARD_FAB2(SCH_1):P3V3_STBY

RES  I127  R4E21  [RES_0402-68.1K,1%,1/16W,EMPTY,A]
    1  VR_PVCCIO_CPU1_OCSET      A  @BASEBOARD_FAB2_LIB.BASEBOARD_FAB2(SCH_1):VR_PVCCIO_CPU1_OCSET
    2  GND                B  @BASEBOARD_FAB2_LIB.BASEBOARD_FAB2(SCH_1):GND

RES  I65  R4E22  [RES_0402-68.1K,1%,1/16W,EMPTY,A]
    1  VR_PVCCIN_CPU0_PH1_OCSET      A  @BASEBOARD_FAB2_LIB.BASEBOARD_FAB2(SCH_1):VR_PVCCIN_CPU0_PH1_OCSET
    2  GND                B  @BASEBOARD_FAB2_LIB.BASEBOARD_FAB2(SCH_1):GND

RES  I110  R4F1   [RES_0402-0.0,5%,1/16W,CHIP,G21A]
    1  VR_PVDDQ_ABC_AIINSEN_R      A  @BASEBOARD_FAB2_LIB.BASEBOARD_FAB2(SCH_1):VR_PVDDQ_ABC_AIINSEN_R
    2  VR_PVDDQ_ABC_AIINSEN      B  @BASEBOARD_FAB2_LIB.BASEBOARD_FAB2(SCH_1):VR_PVDDQ_ABC_AIINSEN

RES  I99  R4F2   [RES_1206-0.002,1%,1W,CHIP,G521A]
    2  P12V_STBY          B  @BASEBOARD_FAB2_LIB.BASEBOARD_FAB2(SCH_1):P12V_STBY
    1  P12V_NVDIMM_ABC      A  @BASEBOARD_FAB2_LIB.BASEBOARD_FAB2(SCH_1):P12V_NVDIMM_ABC

RES  I5   R4F3   [RES_0402-2,1.0%,1/16W,CHIP,G21A]
    2  M_A_VREF           B  @BASEBOARD_FAB2_LIB.BASEBOARD_FAB2(SCH_1):M_A_VREF
    1  M_A_CPU_VREF       A  @BASEBOARD_FAB2_LIB.BASEBOARD_FAB2(SCH_1):M_A_CPU_VREF

RES  I36  R4F4   [RES_0402-1.00K,1%,1/16W,CHIP,GA]
    1  PVDDQ_ABC          A  @BASEBOARD_FAB2_LIB.BASEBOARD_FAB2(SCH_1):PVDDQ_ABC
    2  M_A_VREF           B  @BASEBOARD_FAB2_LIB.BASEBOARD_FAB2(SCH_1):M_A_VREF

RES  I4   R4F5   [RES_0402-1.00K,1%,1/16W,CHIP,GA]
    1  M_A_VREF           A  @BASEBOARD_FAB2_LIB.BASEBOARD_FAB2(SCH_1):M_A_VREF
    2  GND                B  @BASEBOARD_FAB2_LIB.BASEBOARD_FAB2(SCH_1):GND

RES  I208  R4F6   [RES_0402-2.2,5%,1/16W,EMPTY,G2A]
    1  VR_PVPP_GHJ_SNUB      A  @BASEBOARD_FAB2_LIB.BASEBOARD_FAB2(SCH_1):VR_PVPP_GHJ_SNUB
    2  GND                B  @BASEBOARD_FAB2_LIB.BASEBOARD_FAB2(SCH_1):GND

RES  I42  R4G1   [RES_0402-2,1.0%,1/16W,CHIP,G21A]
    2  M_B_VREF           B  @BASEBOARD_FAB2_LIB.BASEBOARD_FAB2(SCH_1):M_B_VREF
    1  M_B_CPU_VREF       A  @BASEBOARD_FAB2_LIB.BASEBOARD_FAB2(SCH_1):M_B_CPU_VREF

RES  I38  R4G2   [RES_0402-1.00K,1%,1/16W,CHIP,GA]
    1  PVDDQ_ABC          A  @BASEBOARD_FAB2_LIB.BASEBOARD_FAB2(SCH_1):PVDDQ_ABC
    2  M_B_VREF           B  @BASEBOARD_FAB2_LIB.BASEBOARD_FAB2(SCH_1):M_B_VREF

RES  I40  R4G3   [RES_0402-1.00K,1%,1/16W,CHIP,GA]
    1  M_B_VREF           A  @BASEBOARD_FAB2_LIB.BASEBOARD_FAB2(SCH_1):M_B_VREF
    2  GND                B  @BASEBOARD_FAB2_LIB.BASEBOARD_FAB2(SCH_1):GND

RES  I275  R4G4   [RES_0402-0.0,5%,1/16W,CHIP,G21A]
    2  FM_PVPP_PVDDQ_CPU1_EN_GHJ      B  @BASEBOARD_FAB2_LIB.BASEBOARD_FAB2(SCH_1):FM_PVPP_PVDDQ_CPU1_EN_GHJ
    1  FM_PVPP_CPU1_EN      A  @BASEBOARD_FAB2_LIB.BASEBOARD_FAB2(SCH_1):FM_PVPP_CPU1_EN

RES  I182  R4G5   [RES_0402-10.0K,1%,1/16W,CHIP,GA]
    2  GND                B  @BASEBOARD_FAB2_LIB.BASEBOARD_FAB2(SCH_1):GND
    1  FM_PVPP_CPU1_EN      A  @BASEBOARD_FAB2_LIB.BASEBOARD_FAB2(SCH_1):FM_PVPP_CPU1_EN

RES  I211  R4G6   [RES_0603-120.0,1%,1/10W,CHIP,GA]
    1  PVPP_GHJ           A  @BASEBOARD_FAB2_LIB.BASEBOARD_FAB2(SCH_1):PVPP_GHJ
    2  GND                B  @BASEBOARD_FAB2_LIB.BASEBOARD_FAB2(SCH_1):GND

RES  I270  R4G7   [RES_0402-20.0K,1%,1/16W,CHIP,GA]
    1  VSENSE_PVPP_GHJ      A  @BASEBOARD_FAB2_LIB.BASEBOARD_FAB2(SCH_1):VSENSE_PVPP_GHJ
    2  VR_FB_PVPP_GHJ      B  @BASEBOARD_FAB2_LIB.BASEBOARD_FAB2(SCH_1):VR_FB_PVPP_GHJ

RES  I271  R4G8   [RES_0402-0.0,5%,1/16W,CHIP,G21A]
    2  VSENSE_PVPP_GHJ      B  @BASEBOARD_FAB2_LIB.BASEBOARD_FAB2(SCH_1):VSENSE_PVPP_GHJ
    1  PVPP_GHJ           A  @BASEBOARD_FAB2_LIB.BASEBOARD_FAB2(SCH_1):PVPP_GHJ

RES  I269  R4G9   [RES_0402-6.34K,1%,1/16W,CHIP,GA]
    1  VR_FB_PVPP_GHJ      A  @BASEBOARD_FAB2_LIB.BASEBOARD_FAB2(SCH_1):VR_FB_PVPP_GHJ
    2  AGND_PVPP_GHJ      B  @BASEBOARD_FAB2_LIB.BASEBOARD_FAB2(SCH_1):AGND_PVPP_GHJ

RES  I266  R4G10  [RES_0402-1.0K,0.1%,1/16W,CHIP,A]
    1  VSENSE_PVPP_GHJ      A  @BASEBOARD_FAB2_LIB.BASEBOARD_FAB2(SCH_1):VSENSE_PVPP_GHJ
    2  VR_COMP_PVPP_GHJ      B  @BASEBOARD_FAB2_LIB.BASEBOARD_FAB2(SCH_1):VR_COMP_PVPP_GHJ

RES  I184  R4G11  [RES_0402-7.87K,1.0%,1/16W,CHIPA]
    1  VR_PVPP_GHJ_ISET      A  @BASEBOARD_FAB2_LIB.BASEBOARD_FAB2(SCH_1):VR_PVPP_GHJ_ISET
    2  AGND_PVPP_GHJ      B  @BASEBOARD_FAB2_LIB.BASEBOARD_FAB2(SCH_1):AGND_PVPP_GHJ

RES  I247  R4G12  [RES_0402-22.1,1.0%,1/16W,CHIP,A]
    1  PWRGD_PVPP_GHJ_R      A  @BASEBOARD_FAB2_LIB.BASEBOARD_FAB2(SCH_1):PWRGD_PVPP_GHJ_R
    2  PWRGD_PVPP_GHJ      B  @BASEBOARD_FAB2_LIB.BASEBOARD_FAB2(SCH_1):PWRGD_PVPP_GHJ

RES  I272  R4G13  [RES_0402-7.87K,1.0%,1/16W,CHIPA]
    2  VR_FB_PVPP_GHJ      B  @BASEBOARD_FAB2_LIB.BASEBOARD_FAB2(SCH_1):VR_FB_PVPP_GHJ
    1  VR_COMP_RC_PVPP_GHJ      A  @BASEBOARD_FAB2_LIB.BASEBOARD_FAB2(SCH_1):VR_COMP_RC_PVPP_GHJ

RES  I185  R4G14  [RES_0402-1.00K,1%,1/16W,CHIP,GA]
    2  PWRGD_PVPP_GHJ_R      B  @BASEBOARD_FAB2_LIB.BASEBOARD_FAB2(SCH_1):PWRGD_PVPP_GHJ_R
    1  P3V3_STBY          A  @BASEBOARD_FAB2_LIB.BASEBOARD_FAB2(SCH_1):P3V3_STBY

RES  I51  R4G15  [RES_0402-33.2,1%,1/16W,CHIP,G2A]
    1  PWRGD_PVTT_GHJ_CPU1_R      A  @BASEBOARD_FAB2_LIB.BASEBOARD_FAB2(SCH_1):PWRGD_PVTT_GHJ_CPU1_R
    2  PWRGD_PVTT_CPU1      B  @BASEBOARD_FAB2_LIB.BASEBOARD_FAB2(SCH_1):PWRGD_PVTT_CPU1

RES  I35  R4G16  [RES_0402-0.0,5%,1/16W,CHIP,G21A]
    1  PWRGD_PVDDQ_GHJ      A  @BASEBOARD_FAB2_LIB.BASEBOARD_FAB2(SCH_1):PWRGD_PVDDQ_GHJ
    2  FM_PVTT_GHJ_EN_R      B  @BASEBOARD_FAB2_LIB.BASEBOARD_FAB2(SCH_1):FM_PVTT_GHJ_EN_R

RES  I14  R4G17  [RES_0402-10.0K,1%,1/16W,CHIP,GA]
    2  PWRGD_PVTT_GHJ_CPU1_R      B  @BASEBOARD_FAB2_LIB.BASEBOARD_FAB2(SCH_1):PWRGD_PVTT_GHJ_CPU1_R
    1  P3V3               A  @BASEBOARD_FAB2_LIB.BASEBOARD_FAB2(SCH_1):P3V3

RES  I45  R4G18  [RES_0402-10.0K,1%,1/16W,CHIP,GA]
    2  PWRGD_PVTT_ABC_CPU0_R      B  @BASEBOARD_FAB2_LIB.BASEBOARD_FAB2(SCH_1):PWRGD_PVTT_ABC_CPU0_R
    1  P3V3               A  @BASEBOARD_FAB2_LIB.BASEBOARD_FAB2(SCH_1):P3V3

RES  I54  R4G19  [RES_0402-33.2,1%,1/16W,CHIP,G2A]
    2  PWRGD_PVTT_CPU0      B  @BASEBOARD_FAB2_LIB.BASEBOARD_FAB2(SCH_1):PWRGD_PVTT_CPU0
    1  PWRGD_PVTT_ABC_CPU0_R      A  @BASEBOARD_FAB2_LIB.BASEBOARD_FAB2(SCH_1):PWRGD_PVTT_ABC_CPU0_R

RES  I50  R4G20  [RES_0402-2,1.0%,1/16W,CHIP,G21A]
    2  M_C_VREF           B  @BASEBOARD_FAB2_LIB.BASEBOARD_FAB2(SCH_1):M_C_VREF
    1  M_C_CPU_VREF       A  @BASEBOARD_FAB2_LIB.BASEBOARD_FAB2(SCH_1):M_C_CPU_VREF

RES  I46  R4G21  [RES_0402-1.00K,1%,1/16W,CHIP,GA]
    1  PVDDQ_ABC          A  @BASEBOARD_FAB2_LIB.BASEBOARD_FAB2(SCH_1):PVDDQ_ABC
    2  M_C_VREF           B  @BASEBOARD_FAB2_LIB.BASEBOARD_FAB2(SCH_1):M_C_VREF

RES  I48  R4G22  [RES_0402-1.00K,1%,1/16W,CHIP,GA]
    1  M_C_VREF           A  @BASEBOARD_FAB2_LIB.BASEBOARD_FAB2(SCH_1):M_C_VREF
    2  GND                B  @BASEBOARD_FAB2_LIB.BASEBOARD_FAB2(SCH_1):GND

RES  I38  R4G23  [RES_0402-0.0,5%,1/16W,CHIP,G21A]
    1  PWRGD_PVDDQ_ABC      A  @BASEBOARD_FAB2_LIB.BASEBOARD_FAB2(SCH_1):PWRGD_PVDDQ_ABC
    2  FM_PVTT_ABC_EN_R      B  @BASEBOARD_FAB2_LIB.BASEBOARD_FAB2(SCH_1):FM_PVTT_ABC_EN_R

RES  I199  R4G24  [RES_0402-0.0,5%,1/16W,CHIP,G21A]
    2  VR_PVPP_GHJ_BOOT_R      B  @BASEBOARD_FAB2_LIB.BASEBOARD_FAB2(SCH_1):VR_PVPP_GHJ_BOOT_R
    1  VR_PVPP_GHJ_BOOT      A  @BASEBOARD_FAB2_LIB.BASEBOARD_FAB2(SCH_1):VR_PVPP_GHJ_BOOT

RES  I157  R4G25  [RES_0402-0.0,5%,1/16W,CHIP,G21A]
    1  GND                A  @BASEBOARD_FAB2_LIB.BASEBOARD_FAB2(SCH_1):GND
    2  AGND_PVPP_GHJ      B  @BASEBOARD_FAB2_LIB.BASEBOARD_FAB2(SCH_1):AGND_PVPP_GHJ

RES  I74  R4L2   [RES_0402-100.0,1%,1/16W,EMPTY,A]
    1  VSENSE_PVDDQ_DEF_P      A  @BASEBOARD_FAB2_LIB.BASEBOARD_FAB2(SCH_1):VSENSE_PVDDQ_DEF_P
    2  VSENSE_PVDDQ_DEF_N      B  @BASEBOARD_FAB2_LIB.BASEBOARD_FAB2(SCH_1):VSENSE_PVDDQ_DEF_N

RES  I58  R4L4   [RES_0603-120.0,1%,1/10W,CHIP,GA]
    1  PVDDQ_DEF          A  @BASEBOARD_FAB2_LIB.BASEBOARD_FAB2(SCH_1):PVDDQ_DEF
    2  GND                B  @BASEBOARD_FAB2_LIB.BASEBOARD_FAB2(SCH_1):GND

RES  I4   R4P1   [RES_0402-240,1.0%,1/16W,EMPTY,A]
    2  PD_CPU0_BIST_ENABLE      B  @BASEBOARD_FAB2_LIB.BASEBOARD_FAB2(SCH_1):PD_CPU0_BIST_ENABLE
    1  GND                A  @BASEBOARD_FAB2_LIB.BASEBOARD_FAB2(SCH_1):GND

RES  I188  R4P2   [RES_0402-49.9,1%,1/16W,CHIP,G2A]
    2  GND                B  @BASEBOARD_FAB2_LIB.BASEBOARD_FAB2(SCH_1):GND
    1  A_CPU0_PE3_RBIAS      A  @BASEBOARD_FAB2_LIB.BASEBOARD_FAB2(SCH_1):A_CPU0_PE3_RBIAS

RES  I186  R4P3   [RES_0402-49.9,1%,1/16W,CHIP,G2A]
    2  GND                B  @BASEBOARD_FAB2_LIB.BASEBOARD_FAB2(SCH_1):GND
    1  A_CPU0_PE012_RBIAS      A  @BASEBOARD_FAB2_LIB.BASEBOARD_FAB2(SCH_1):A_CPU0_PE012_RBIAS

RES  I189  R4P4   [RES_0402-49.9,1%,1/16W,CHIP,G2A]
    2  GND                B  @BASEBOARD_FAB2_LIB.BASEBOARD_FAB2(SCH_1):GND
    1  A_CPU0_UPI2_RBIAS      A  @BASEBOARD_FAB2_LIB.BASEBOARD_FAB2(SCH_1):A_CPU0_UPI2_RBIAS

RES  I80  R4P5   [RES_0402-10.0K,1%,1/16W,CHIP,GA]
    2  PD_CPU0_MCP01_DMON      B  @BASEBOARD_FAB2_LIB.BASEBOARD_FAB2(SCH_1):PD_CPU0_MCP01_DMON
    1  GND                A  @BASEBOARD_FAB2_LIB.BASEBOARD_FAB2(SCH_1):GND

RES  I68  R4P6   [RES_0402-240,1.0%,1/16W,EMPTY,A]
    2  PD_CPU0_DMIMODE_OVERRIDE      B  @BASEBOARD_FAB2_LIB.BASEBOARD_FAB2(SCH_1):PD_CPU0_DMIMODE_OVERRIDE
    1  GND                A  @BASEBOARD_FAB2_LIB.BASEBOARD_FAB2(SCH_1):GND

RES  I72  R4P7   [RES_0402-240,1.0%,1/16W,EMPTY,A]
    2  PD_CPU0_KSFC_DIS      B  @BASEBOARD_FAB2_LIB.BASEBOARD_FAB2(SCH_1):PD_CPU0_KSFC_DIS
    1  GND                A  @BASEBOARD_FAB2_LIB.BASEBOARD_FAB2(SCH_1):GND

RES  I180  R4P8   [RES_0402-90.9,1%,1/16W,CHIP,G2A]
    2  GND                B  @BASEBOARD_FAB2_LIB.BASEBOARD_FAB2(SCH_1):GND
    1  A_CPU0_ABC_RCOMP0      A  @BASEBOARD_FAB2_LIB.BASEBOARD_FAB2(SCH_1):A_CPU0_ABC_RCOMP0

RES  I181  R4P10  [RES_0402-90.9,1%,1/16W,CHIP,G2A]
    2  GND                B  @BASEBOARD_FAB2_LIB.BASEBOARD_FAB2(SCH_1):GND
    1  A_CPU0_ABC_RCOMP1      A  @BASEBOARD_FAB2_LIB.BASEBOARD_FAB2(SCH_1):A_CPU0_ABC_RCOMP1

RES  I182  R4P11  [RES_0402-100.0,1%,1/16W,CHIP,GA]
    2  GND                B  @BASEBOARD_FAB2_LIB.BASEBOARD_FAB2(SCH_1):GND
    1  A_CPU0_ABC_RCOMP2      A  @BASEBOARD_FAB2_LIB.BASEBOARD_FAB2(SCH_1):A_CPU0_ABC_RCOMP2

RES  I57  R4P12  [RES_0402-100.0,1%,1/16W,CHIP,GA]
    2  XDP_CPU_MBP0_N      B  @BASEBOARD_FAB2_LIB.BASEBOARD_FAB2(SCH_1):XDP_CPU_MBP0_N
    1  PVCCIO_CPU0        A  @BASEBOARD_FAB2_LIB.BASEBOARD_FAB2(SCH_1):PVCCIO_CPU0

RES  I53  R4P14  [RES_0402-240,1.0%,1/16W,CHIP,GA]
    1  PVCCIO_CPU0        A  @BASEBOARD_FAB2_LIB.BASEBOARD_FAB2(SCH_1):PVCCIO_CPU0
    2  PU_CPU0_LEGACY_SKT      B  @BASEBOARD_FAB2_LIB.BASEBOARD_FAB2(SCH_1):PU_CPU0_LEGACY_SKT

RES  I53  R4P15  [RES_0402-100.0,1%,1/16W,CHIP,GA]
    2  XDP_CPU_MBP1_N      B  @BASEBOARD_FAB2_LIB.BASEBOARD_FAB2(SCH_1):XDP_CPU_MBP1_N
    1  PVCCIO_CPU0        A  @BASEBOARD_FAB2_LIB.BASEBOARD_FAB2(SCH_1):PVCCIO_CPU0

RES  I58  R4P17  [RES_0402-150.0,1%,1/16W,CHIP,GA]
    2  PVCCIO_CPU0        B  @BASEBOARD_FAB2_LIB.BASEBOARD_FAB2(SCH_1):PVCCIO_CPU0
    1  H_CPU0_MEMABC_MEMHOT_G_N      A  @BASEBOARD_FAB2_LIB.BASEBOARD_FAB2(SCH_1):H_CPU0_MEMABC_MEMHOT_G_N

RES  I244  R4P18  [RES_0402-49.9,1%,1/16W,CHIP,G2A]
    1  H_PM_SYNC_GTL_R1      A  @BASEBOARD_FAB2_LIB.BASEBOARD_FAB2(SCH_1):H_PM_SYNC_GTL_R1
    2  H_PM_SYNC_GTL      B  @BASEBOARD_FAB2_LIB.BASEBOARD_FAB2(SCH_1):H_PM_SYNC_GTL

RES  I219  R4P19  [RES_0402-49.9,1%,1/16W,CHIP,G2A]
    1  H_PMSYNC_CLK_24M_CPU0      A  @BASEBOARD_FAB2_LIB.BASEBOARD_FAB2(SCH_1):H_PMSYNC_CLK_24M_CPU0
    2  H_PMSYNC_CLK_24M      B  @BASEBOARD_FAB2_LIB.BASEBOARD_FAB2(SCH_1):H_PMSYNC_CLK_24M

RES  I59  R4P20  [RES_0402-150.0,1%,1/16W,CHIP,GA]
    2  PVCCIO_CPU0        B  @BASEBOARD_FAB2_LIB.BASEBOARD_FAB2(SCH_1):PVCCIO_CPU0
    1  H_CPU0_MEMDEF_MEMHOT_G_N      A  @BASEBOARD_FAB2_LIB.BASEBOARD_FAB2(SCH_1):H_CPU0_MEMDEF_MEMHOT_G_N

RES  I72  R4P21  [RES_0402-240,1.0%,1/16W,CHIP,GA]
    1  PVCCIO_CPU0        A  @BASEBOARD_FAB2_LIB.BASEBOARD_FAB2(SCH_1):PVCCIO_CPU0
    2  PU_CPU0_TSC_SYNC      B  @BASEBOARD_FAB2_LIB.BASEBOARD_FAB2(SCH_1):PU_CPU0_TSC_SYNC

RES  I58  R4P23  [RES_0402-150.0,1%,1/16W,CHIP,GA]
    2  XDP_CPU0_TDO       B  @BASEBOARD_FAB2_LIB.BASEBOARD_FAB2(SCH_1):XDP_CPU0_TDO
    1  PVCCIO_CPU0        A  @BASEBOARD_FAB2_LIB.BASEBOARD_FAB2(SCH_1):PVCCIO_CPU0

RES  I59  R4P24  [RES_0402-150.0,1%,1/16W,CHIP,GA]
    2  XDP_CPU_TDI        B  @BASEBOARD_FAB2_LIB.BASEBOARD_FAB2(SCH_1):XDP_CPU_TDI
    1  PVCCIO_CPU0        A  @BASEBOARD_FAB2_LIB.BASEBOARD_FAB2(SCH_1):PVCCIO_CPU0

RES  I368  R4R1   [RES_0402-1.00K,1%,1/16W,CHIP,GA]
    1  H_CPU0_FAST_WAKE_N      A  @BASEBOARD_FAB2_LIB.BASEBOARD_FAB2(SCH_1):H_CPU0_FAST_WAKE_N
    2  H_CPU0_FAST_WAKE_B_N      B  @BASEBOARD_FAB2_LIB.BASEBOARD_FAB2(SCH_1):H_CPU0_FAST_WAKE_B_N

RES  I101  R4R2   [RES_0402-150.0,1%,1/16W,CHIP,GA]
    1  PVCCIO_CPU0        A  @BASEBOARD_FAB2_LIB.BASEBOARD_FAB2(SCH_1):PVCCIO_CPU0
    2  H_CPU0_CATERR_G_N      B  @BASEBOARD_FAB2_LIB.BASEBOARD_FAB2(SCH_1):H_CPU0_CATERR_G_N

RES  I79  R4R3   [RES_0402-150.0,1%,1/16W,CHIP,GA]
    1  PVCCIO_CPU0        A  @BASEBOARD_FAB2_LIB.BASEBOARD_FAB2(SCH_1):PVCCIO_CPU0
    2  H_CPU0_PROCHOT_G_N      B  @BASEBOARD_FAB2_LIB.BASEBOARD_FAB2(SCH_1):H_CPU0_PROCHOT_G_N

RES  I42  R4R4   [RES_0402-150.0,1%,1/16W,CHIP,GA]
    1  PVCCIO_CPU0        A  @BASEBOARD_FAB2_LIB.BASEBOARD_FAB2(SCH_1):PVCCIO_CPU0
    2  H_CPU0_FAST_WAKE_N      B  @BASEBOARD_FAB2_LIB.BASEBOARD_FAB2(SCH_1):H_CPU0_FAST_WAKE_N

RES  I258  R4R5   [RES_0402-4.75K,1%,1/16W,CHIP,GA]
    1  P3V3_STBY          A  @BASEBOARD_FAB2_LIB.BASEBOARD_FAB2(SCH_1):P3V3_STBY
    2  FM_CPU0_SKTOCC_LVT3_N      B  @BASEBOARD_FAB2_LIB.BASEBOARD_FAB2(SCH_1):FM_CPU0_SKTOCC_LVT3_N

RES  I134  R4R6   [RES_0402-49.9,1%,1/16W,CHIP,G2A]
    1  JTAG_MCP_CPU0_TDI_R      A  @BASEBOARD_FAB2_LIB.BASEBOARD_FAB2(SCH_1):JTAG_MCP_CPU0_TDI_R
    2  JTAG_MCP_CPU0_TDI      B  @BASEBOARD_FAB2_LIB.BASEBOARD_FAB2(SCH_1):JTAG_MCP_CPU0_TDI

RES  I2   R4T1   [RES_0402-0.0,5%,1/16W,CHIP,G21A]
    2  FM_ADR_COMPLETE_R      B  @BASEBOARD_FAB2_LIB.BASEBOARD_FAB2(SCH_1):FM_ADR_COMPLETE_R
    1  FM_ADR_COMPLETE_DLY      A  @BASEBOARD_FAB2_LIB.BASEBOARD_FAB2(SCH_1):FM_ADR_COMPLETE_DLY

RES  I1   R4T2   [RES_0402-0.0,5%,1/16W,EMPTY,G2A]
    2  FM_ADR_COMPLETE_R      B  @BASEBOARD_FAB2_LIB.BASEBOARD_FAB2(SCH_1):FM_ADR_COMPLETE_R
    1  FM_ADR_COMPLETE      A  @BASEBOARD_FAB2_LIB.BASEBOARD_FAB2(SCH_1):FM_ADR_COMPLETE

RES  I83  R4T3   [RES_0402-10.0,1%,1/16W,CHIP,G2A]
    1  SMB_DDR_ABC_SCL_G_R      A  @BASEBOARD_FAB2_LIB.BASEBOARD_FAB2(SCH_1):SMB_DDR_ABC_SCL_G_R
    2  SMB_DDR_ABC_SCL_G      B  @BASEBOARD_FAB2_LIB.BASEBOARD_FAB2(SCH_1):SMB_DDR_ABC_SCL_G

RES  I20  R4T4   [RES_0402-10.0,1%,1/16W,CHIP,G2A]
    1  SMB_DDR_ABC_SDA_G_R      A  @BASEBOARD_FAB2_LIB.BASEBOARD_FAB2(SCH_1):SMB_DDR_ABC_SDA_G_R
    2  SMB_DDR_ABC_SDA_G      B  @BASEBOARD_FAB2_LIB.BASEBOARD_FAB2(SCH_1):SMB_DDR_ABC_SDA_G

RES  I19  R4T5   [RES_0402-240,1.0%,1/16W,CHIP,GA]
    2  SMB_DDR_ABC_SCL_G      B  @BASEBOARD_FAB2_LIB.BASEBOARD_FAB2(SCH_1):SMB_DDR_ABC_SCL_G
    1  PVCCIO_CPU0        A  @BASEBOARD_FAB2_LIB.BASEBOARD_FAB2(SCH_1):PVCCIO_CPU0

RES  I17  R4T6   [RES_0402-240,1.0%,1/16W,CHIP,GA]
    2  SMB_DDR_ABC_SDA_G      B  @BASEBOARD_FAB2_LIB.BASEBOARD_FAB2(SCH_1):SMB_DDR_ABC_SDA_G
    1  PVCCIO_CPU0        A  @BASEBOARD_FAB2_LIB.BASEBOARD_FAB2(SCH_1):PVCCIO_CPU0

RES  I13  R4T7   [RES_0402-665,1.0%,1/16W,CHIP,GA]
    2  SMB_DDR_ABC_VPP_SCL_R      B  @BASEBOARD_FAB2_LIB.BASEBOARD_FAB2(SCH_1):SMB_DDR_ABC_VPP_SCL_R
    1  PVPP_ABC           A  @BASEBOARD_FAB2_LIB.BASEBOARD_FAB2(SCH_1):PVPP_ABC

RES  I11  R4T8   [RES_0402-665,1.0%,1/16W,CHIP,GA]
    2  SMB_DDR_ABC_VPP_SDA_R      B  @BASEBOARD_FAB2_LIB.BASEBOARD_FAB2(SCH_1):SMB_DDR_ABC_VPP_SDA_R
    1  PVPP_ABC           A  @BASEBOARD_FAB2_LIB.BASEBOARD_FAB2(SCH_1):PVPP_ABC

RES  I9   R4T9   [RES_0402-20.0,1%,1/16W,CHIP,G2A]
    1  SMB_DDR_ABC_VPP_SCL_R      A  @BASEBOARD_FAB2_LIB.BASEBOARD_FAB2(SCH_1):SMB_DDR_ABC_VPP_SCL_R
    2  SMB_DDR_ABC_VPP_SCL      B  @BASEBOARD_FAB2_LIB.BASEBOARD_FAB2(SCH_1):SMB_DDR_ABC_VPP_SCL

RES  I10  R4T10  [RES_0402-20.0,1%,1/16W,CHIP,G2A]
    1  SMB_DDR_ABC_VPP_SDA_R      A  @BASEBOARD_FAB2_LIB.BASEBOARD_FAB2(SCH_1):SMB_DDR_ABC_VPP_SDA_R
    2  SMB_DDR_ABC_VPP_SDA      B  @BASEBOARD_FAB2_LIB.BASEBOARD_FAB2(SCH_1):SMB_DDR_ABC_VPP_SDA

RES  I91  R4U1   [RES_0402-4.75K,1%,1/16W,CHIP,GA]
    1  P3V3_STBY          A  @BASEBOARD_FAB2_LIB.BASEBOARD_FAB2(SCH_1):P3V3_STBY
    2  FM_MEM_THERM_EVENT_LVT3_N      B  @BASEBOARD_FAB2_LIB.BASEBOARD_FAB2(SCH_1):FM_MEM_THERM_EVENT_LVT3_N

RES  I100  R4U2   [RES_0402-2.21K,1%,1/16W,CHIP,GA]
    1  PVPP_ABC           A  @BASEBOARD_FAB2_LIB.BASEBOARD_FAB2(SCH_1):PVPP_ABC
    2  FM_DIMM_EVENT_COD_N      B  @BASEBOARD_FAB2_LIB.BASEBOARD_FAB2(SCH_1):FM_DIMM_EVENT_COD_N

RES  I94  R4U3   [RES_0402-4.75K,1%,1/16W,CHIP,GA]
    1  PVPP_ABC           A  @BASEBOARD_FAB2_LIB.BASEBOARD_FAB2(SCH_1):PVPP_ABC
    2  FM_DIMM_EVENT_FET      B  @BASEBOARD_FAB2_LIB.BASEBOARD_FAB2(SCH_1):FM_DIMM_EVENT_FET

RES  I104  R4U4   [RES_0402-33.0K,5%,1/16W,CHIP,GA]
    2  GND                B  @BASEBOARD_FAB2_LIB.BASEBOARD_FAB2(SCH_1):GND
    1  FM_DIMM_EVENT_FET      A  @BASEBOARD_FAB2_LIB.BASEBOARD_FAB2(SCH_1):FM_DIMM_EVENT_FET

RES  I74  R4U6   [RES_0402-100.0,1%,1/16W,EMPTY,A]
    1  VSENSE_PVDDQ_ABC_P      A  @BASEBOARD_FAB2_LIB.BASEBOARD_FAB2(SCH_1):VSENSE_PVDDQ_ABC_P
    2  VSENSE_PVDDQ_ABC_N      B  @BASEBOARD_FAB2_LIB.BASEBOARD_FAB2(SCH_1):VSENSE_PVDDQ_ABC_N

RES  I177  R5D1   [RES_0402-90.9,1%,1/16W,CHIP,G2A]
    2  GND                B  @BASEBOARD_FAB2_LIB.BASEBOARD_FAB2(SCH_1):GND
    1  A_CPU0_DEF_RCOMP0      A  @BASEBOARD_FAB2_LIB.BASEBOARD_FAB2(SCH_1):A_CPU0_DEF_RCOMP0

RES  I178  R5D2   [RES_0402-90.9,1%,1/16W,CHIP,G2A]
    2  GND                B  @BASEBOARD_FAB2_LIB.BASEBOARD_FAB2(SCH_1):GND
    1  A_CPU0_DEF_RCOMP1      A  @BASEBOARD_FAB2_LIB.BASEBOARD_FAB2(SCH_1):A_CPU0_DEF_RCOMP1

RES  I29  R5D3   [RES_0402-240,1.0%,1/16W,CHIP,GA]
    1  PVCCIO_CPU0        A  @BASEBOARD_FAB2_LIB.BASEBOARD_FAB2(SCH_1):PVCCIO_CPU0
    2  PU_CPU0_FRMAGENT      B  @BASEBOARD_FAB2_LIB.BASEBOARD_FAB2(SCH_1):PU_CPU0_FRMAGENT

RES  I32  R5D4   [RES_0402-240,1.0%,1/16W,EMPTY,A]
    1  PVCCIO_CPU0        A  @BASEBOARD_FAB2_LIB.BASEBOARD_FAB2(SCH_1):PVCCIO_CPU0
    2  PU_CPU0_TXT_AGENT      B  @BASEBOARD_FAB2_LIB.BASEBOARD_FAB2(SCH_1):PU_CPU0_TXT_AGENT

RES  I303  R5D5   [RES_0402-249,0.1%,1/16W,CHIP,GA]
    1  VSENSE_PMAX_CPU0      A  @BASEBOARD_FAB2_LIB.BASEBOARD_FAB2(SCH_1):VSENSE_PMAX_CPU0
    2  GND                B  @BASEBOARD_FAB2_LIB.BASEBOARD_FAB2(SCH_1):GND

RES  I312  R5D6   [RES_0402-10.0,1%,1/16W,EMPTY,GA]
    2  VSENSE_PMAX_CPU0      B  @BASEBOARD_FAB2_LIB.BASEBOARD_FAB2(SCH_1):VSENSE_PMAX_CPU0
    1  PVCCIO_CPU0        A  @BASEBOARD_FAB2_LIB.BASEBOARD_FAB2(SCH_1):PVCCIO_CPU0

RES  I238  R5N1   [RES_0402-10.0K,1%,1/16W,CHIP,GA]
    1  P3V3_STBY          A  @BASEBOARD_FAB2_LIB.BASEBOARD_FAB2(SCH_1):P3V3_STBY
    2  FM_CPU0_PKGID0      B  @BASEBOARD_FAB2_LIB.BASEBOARD_FAB2(SCH_1):FM_CPU0_PKGID0

RES  I227  R5N2   [RES_0402-1.8K,1%,1/16W,CHIP,G2A]
    1  P3V3_STBY          A  @BASEBOARD_FAB2_LIB.BASEBOARD_FAB2(SCH_1):P3V3_STBY
    2  FM_CPU0_PROC_ID1      B  @BASEBOARD_FAB2_LIB.BASEBOARD_FAB2(SCH_1):FM_CPU0_PROC_ID1

RES  I240  R5N3   [RES_0402-10.0K,1%,1/16W,CHIP,GA]
    1  P3V3_STBY          A  @BASEBOARD_FAB2_LIB.BASEBOARD_FAB2(SCH_1):P3V3_STBY
    2  FM_CPU0_PKGID2      B  @BASEBOARD_FAB2_LIB.BASEBOARD_FAB2(SCH_1):FM_CPU0_PKGID2

RES  I241  R5N4   [RES_0402-1.8K,1%,1/16W,CHIP,G2A]
    1  P3V3_STBY          A  @BASEBOARD_FAB2_LIB.BASEBOARD_FAB2(SCH_1):P3V3_STBY
    2  FM_CPU0_PROC_ID0      B  @BASEBOARD_FAB2_LIB.BASEBOARD_FAB2(SCH_1):FM_CPU0_PROC_ID0

RES  I239  R5N5   [RES_0402-10.0K,1%,1/16W,CHIP,GA]
    1  P3V3_STBY          A  @BASEBOARD_FAB2_LIB.BASEBOARD_FAB2(SCH_1):P3V3_STBY
    2  FM_CPU0_PKGID1      B  @BASEBOARD_FAB2_LIB.BASEBOARD_FAB2(SCH_1):FM_CPU0_PKGID1

RES  I309  R5P1   [RES_0603-100.0K,1%,1/10W,CHIP,A]
    2  VSENSE_VCCINR2PMAX_CPU0      B  @BASEBOARD_FAB2_LIB.BASEBOARD_FAB2(SCH_1):VSENSE_VCCINR2PMAX_CPU0
    1  PVCCIN_CPU0        A  @BASEBOARD_FAB2_LIB.BASEBOARD_FAB2(SCH_1):PVCCIN_CPU0

RES  I79  R5P2   [RES_0402-49.9,1%,1/16W,CHIP,G2A]
    1  PD_CPU0_TEST14      A  @BASEBOARD_FAB2_LIB.BASEBOARD_FAB2(SCH_1):PD_CPU0_TEST14
    2  GND                B  @BASEBOARD_FAB2_LIB.BASEBOARD_FAB2(SCH_1):GND

RES  I80  R5P3   [RES_0402-49.9,1%,1/16W,CHIP,G2A]
    1  PD_CPU0_TEST13      A  @BASEBOARD_FAB2_LIB.BASEBOARD_FAB2(SCH_1):PD_CPU0_TEST13
    2  GND                B  @BASEBOARD_FAB2_LIB.BASEBOARD_FAB2(SCH_1):GND

RES  I190  R5P4   [RES_0402-49.9,1%,1/16W,CHIP,G2A]
    1  PD_CPU0_RSVD_TEST_2      A  @BASEBOARD_FAB2_LIB.BASEBOARD_FAB2(SCH_1):PD_CPU0_RSVD_TEST_2
    2  GND                B  @BASEBOARD_FAB2_LIB.BASEBOARD_FAB2(SCH_1):GND

RES  I188  R5R1   [RES_0402-49.9,1%,1/16W,CHIP,G2A]
    1  PD_CPU0_RSVD_TEST_1      A  @BASEBOARD_FAB2_LIB.BASEBOARD_FAB2(SCH_1):PD_CPU0_RSVD_TEST_1
    2  GND                B  @BASEBOARD_FAB2_LIB.BASEBOARD_FAB2(SCH_1):GND

RES  I161  R6B1   [RES_0402-49.9,1%,1/16W,CHIP,G2A]
    2  SVID_ALERT1_CPU0_R_N      B  @BASEBOARD_FAB2_LIB.BASEBOARD_FAB2(SCH_1):SVID_ALERT1_CPU0_R_N
    1  PVCCIO_CPU0        A  @BASEBOARD_FAB2_LIB.BASEBOARD_FAB2(SCH_1):PVCCIO_CPU0

RES  I159  R6B2   [RES_0402-100.0,1%,1/16W,CHIP,GA]
    2  SVID_DIO1_CPU0_R      B  @BASEBOARD_FAB2_LIB.BASEBOARD_FAB2(SCH_1):SVID_DIO1_CPU0_R
    1  PVCCIO_CPU0        A  @BASEBOARD_FAB2_LIB.BASEBOARD_FAB2(SCH_1):PVCCIO_CPU0

RES  I152  R6B3   [RES_0402-221,1.0%,1/16W,CHIP,GA]
    2  SVID_ALERT1_CPU0_R_N      B  @BASEBOARD_FAB2_LIB.BASEBOARD_FAB2(SCH_1):SVID_ALERT1_CPU0_R_N
    1  SVID_ALERT1_CPU0_N      A  @BASEBOARD_FAB2_LIB.BASEBOARD_FAB2(SCH_1):SVID_ALERT1_CPU0_N

RES  I154  R6B4   [RES_0402-0.0,5%,1/16W,CHIP,G21A]
    2  SVID_DIO1_CPU0_R      B  @BASEBOARD_FAB2_LIB.BASEBOARD_FAB2(SCH_1):SVID_DIO1_CPU0_R
    1  SVID_DIO1_CPU0      A  @BASEBOARD_FAB2_LIB.BASEBOARD_FAB2(SCH_1):SVID_DIO1_CPU0

RES  I153  R6B5   [RES_0402-0.0,5%,1/16W,CHIP,G21A]
    2  SVID_CLK1_CPU0_R      B  @BASEBOARD_FAB2_LIB.BASEBOARD_FAB2(SCH_1):SVID_CLK1_CPU0_R
    1  SVID_CLK1_CPU0      A  @BASEBOARD_FAB2_LIB.BASEBOARD_FAB2(SCH_1):SVID_CLK1_CPU0

RES  I179  R6D1   [RES_0402-100.0,1%,1/16W,CHIP,GA]
    2  GND                B  @BASEBOARD_FAB2_LIB.BASEBOARD_FAB2(SCH_1):GND
    1  A_CPU0_DEF_RCOMP2      A  @BASEBOARD_FAB2_LIB.BASEBOARD_FAB2(SCH_1):A_CPU0_DEF_RCOMP2

RES  I204  R6D2   [RES_0402-49.9,1%,1/16W,CHIP,G2A]
    2  GND                B  @BASEBOARD_FAB2_LIB.BASEBOARD_FAB2(SCH_1):GND
    1  A_CPU0_MCP01_RBIAS      A  @BASEBOARD_FAB2_LIB.BASEBOARD_FAB2(SCH_1):A_CPU0_MCP01_RBIAS

RES  I81  R6D5   [RES_0402-49.9,1%,1/16W,CHIP,G2A]
    1  PD_CPU0_TEST12      A  @BASEBOARD_FAB2_LIB.BASEBOARD_FAB2(SCH_1):PD_CPU0_TEST12
    2  GND                B  @BASEBOARD_FAB2_LIB.BASEBOARD_FAB2(SCH_1):GND

RES  I3   R6D6   [RES_0402-240,1.0%,1/16W,CHIP,GA]
    2  PD_CPU0_TXT_PLTEN      B  @BASEBOARD_FAB2_LIB.BASEBOARD_FAB2(SCH_1):PD_CPU0_TXT_PLTEN
    1  GND                A  @BASEBOARD_FAB2_LIB.BASEBOARD_FAB2(SCH_1):GND

RES  I31  R6D7   [RES_0402-240,1.0%,1/16W,EMPTY,A]
    1  PVCCIO_CPU0        A  @BASEBOARD_FAB2_LIB.BASEBOARD_FAB2(SCH_1):PVCCIO_CPU0
    2  H_CPU0_BMCINIT      B  @BASEBOARD_FAB2_LIB.BASEBOARD_FAB2(SCH_1):H_CPU0_BMCINIT

RES  I3   R6D8   [RES_0402-49.9,1%,1/16W,CHIP,G2A]
    2  PWRGD_CPU0_G       B  @BASEBOARD_FAB2_LIB.BASEBOARD_FAB2(SCH_1):PWRGD_CPU0_G
    1  PVCCIO_CPU0        A  @BASEBOARD_FAB2_LIB.BASEBOARD_FAB2(SCH_1):PVCCIO_CPU0

RES  I64  R6D9   [RES_0402-150.0,1%,1/16W,CHIP,GA]
    1  PVCCIO_CPU0        A  @BASEBOARD_FAB2_LIB.BASEBOARD_FAB2(SCH_1):PVCCIO_CPU0
    2  H_CPU0_MSMI_G_N      B  @BASEBOARD_FAB2_LIB.BASEBOARD_FAB2(SCH_1):H_CPU0_MSMI_G_N

RES  I49  R6D10  [RES_0402-240,1.0%,1/16W,EMPTY,A]
    1  PVCCIO_CPU0        A  @BASEBOARD_FAB2_LIB.BASEBOARD_FAB2(SCH_1):PVCCIO_CPU0
    2  PU_CPU0_SOCKET_ID_1      B  @BASEBOARD_FAB2_LIB.BASEBOARD_FAB2(SCH_1):PU_CPU0_SOCKET_ID_1

RES  I184  R6D11  [RES_0402-49.9,1%,1/16W,CHIP,G2A]
    2  GND                B  @BASEBOARD_FAB2_LIB.BASEBOARD_FAB2(SCH_1):GND
    1  A_CPU0_UPI01_RBIAS      A  @BASEBOARD_FAB2_LIB.BASEBOARD_FAB2(SCH_1):A_CPU0_UPI01_RBIAS

RES  I2   R6D12  [RES_0402-49.9,1%,1/16W,CHIP,G2A]
    2  RST_CPU0_G_N       B  @BASEBOARD_FAB2_LIB.BASEBOARD_FAB2(SCH_1):RST_CPU0_G_N
    1  PVCCIO_CPU0        A  @BASEBOARD_FAB2_LIB.BASEBOARD_FAB2(SCH_1):PVCCIO_CPU0

RES  I33  R6D13  [RES_0402-240,1.0%,1/16W,EMPTY,A]
    1  PVCCIO_CPU0        A  @BASEBOARD_FAB2_LIB.BASEBOARD_FAB2(SCH_1):PVCCIO_CPU0
    2  PU_CPU0_SAFE_MODE_BOOT      B  @BASEBOARD_FAB2_LIB.BASEBOARD_FAB2(SCH_1):PU_CPU0_SAFE_MODE_BOOT

RES  I52  R6D14  [RES_0402-240,1.0%,1/16W,EMPTY,A]
    1  PVCCIO_CPU0        A  @BASEBOARD_FAB2_LIB.BASEBOARD_FAB2(SCH_1):PVCCIO_CPU0
    2  PU_CPU0_EAR_N      B  @BASEBOARD_FAB2_LIB.BASEBOARD_FAB2(SCH_1):PU_CPU0_EAR_N

RES  I48  R6D15  [RES_0402-240,1.0%,1/16W,EMPTY,A]
    1  PVCCIO_CPU0        A  @BASEBOARD_FAB2_LIB.BASEBOARD_FAB2(SCH_1):PVCCIO_CPU0
    2  PU_CPU0_SOCKET_ID_0      B  @BASEBOARD_FAB2_LIB.BASEBOARD_FAB2(SCH_1):PU_CPU0_SOCKET_ID_0

RES  I299  R6D16  [RES_0402-0.0,5%,1/16W,EMPTY,G2A]
    2  H_CPU0_BMCINIT      B  @BASEBOARD_FAB2_LIB.BASEBOARD_FAB2(SCH_1):H_CPU0_BMCINIT
    1  FM_CPU_BMC_INIT      A  @BASEBOARD_FAB2_LIB.BASEBOARD_FAB2(SCH_1):FM_CPU_BMC_INIT

RES  I4   R6F1   [RES_0402-49.9,1%,1/16W,CHIP,G2A]
    1  IRQ_DIMM_SAVE_N      A  @BASEBOARD_FAB2_LIB.BASEBOARD_FAB2(SCH_1):IRQ_DIMM_SAVE_N
    2  FM_ADR_COMPLETE_DEF_N      B  @BASEBOARD_FAB2_LIB.BASEBOARD_FAB2(SCH_1):FM_ADR_COMPLETE_DEF_N

RES  I6   R6F2   [RES_0402-49.9,1%,1/16W,CHIP,G2A]
    1  IRQ_DIMM_SAVE_N      A  @BASEBOARD_FAB2_LIB.BASEBOARD_FAB2(SCH_1):IRQ_DIMM_SAVE_N
    2  FM_ADR_COMPLETE_KLM_N      B  @BASEBOARD_FAB2_LIB.BASEBOARD_FAB2(SCH_1):FM_ADR_COMPLETE_KLM_N

RES  I7   R6F3   [RES_0402-10.0K,1%,1/16W,CHIP,GA]
    1  PVPP_ABC           A  @BASEBOARD_FAB2_LIB.BASEBOARD_FAB2(SCH_1):PVPP_ABC
    2  IRQ_DIMM_SAVE_N      B  @BASEBOARD_FAB2_LIB.BASEBOARD_FAB2(SCH_1):IRQ_DIMM_SAVE_N

RES  I3   R6F4   [RES_0402-49.9,1%,1/16W,CHIP,G2A]
    1  IRQ_DIMM_SAVE_N      A  @BASEBOARD_FAB2_LIB.BASEBOARD_FAB2(SCH_1):IRQ_DIMM_SAVE_N
    2  FM_ADR_COMPLETE_ABC_N      B  @BASEBOARD_FAB2_LIB.BASEBOARD_FAB2(SCH_1):FM_ADR_COMPLETE_ABC_N

RES  I5   R6F5   [RES_0402-49.9,1%,1/16W,CHIP,G2A]
    1  IRQ_DIMM_SAVE_N      A  @BASEBOARD_FAB2_LIB.BASEBOARD_FAB2(SCH_1):IRQ_DIMM_SAVE_N
    2  FM_ADR_COMPLETE_GHJ_N      B  @BASEBOARD_FAB2_LIB.BASEBOARD_FAB2(SCH_1):FM_ADR_COMPLETE_GHJ_N

RES  I41  R6F6   [RES_0402-0.0,5%,1/16W,EMPTY,G2A]
    1  CLK_322M_156M_CPU0_OSC_VRM_DN      A  @BASEBOARD_FAB2_LIB.BASEBOARD_FAB2(SCH_1):CLK_322M_156M_CPU0_OSC_VRM_DN
    2  CLK_156M_OSC_CPU0_HFI_DN      B  @BASEBOARD_FAB2_LIB.BASEBOARD_FAB2(SCH_1):CLK_156M_OSC_CPU0_HFI_DN

RES  I67  R6F7   [RES_0402-0.0,5%,1/16W,CHIP,G21A]
    2  CLK_156M_OSC_CPU0_HFI_DN      B  @BASEBOARD_FAB2_LIB.BASEBOARD_FAB2(SCH_1):CLK_156M_OSC_CPU0_HFI_DN
    1  CLK_156M_OSC_BRD_CPU0_DN      A  @BASEBOARD_FAB2_LIB.BASEBOARD_FAB2(SCH_1):CLK_156M_OSC_BRD_CPU0_DN

RES  I37  R6F8   [RES_0402-0.0,5%,1/16W,EMPTY,G2A]
    1  CLK_322M_156M_CPU0_OSC_VRM_DP      A  @BASEBOARD_FAB2_LIB.BASEBOARD_FAB2(SCH_1):CLK_322M_156M_CPU0_OSC_VRM_DP
    2  CLK_156M_OSC_CPU0_HFI_DP      B  @BASEBOARD_FAB2_LIB.BASEBOARD_FAB2(SCH_1):CLK_156M_OSC_CPU0_HFI_DP

RES  I68  R6F9   [RES_0402-0.0,5%,1/16W,CHIP,G21A]
    2  CLK_156M_OSC_CPU0_HFI_DP      B  @BASEBOARD_FAB2_LIB.BASEBOARD_FAB2(SCH_1):CLK_156M_OSC_CPU0_HFI_DP
    1  CLK_156M_OSC_BRD_CPU0_DP      A  @BASEBOARD_FAB2_LIB.BASEBOARD_FAB2(SCH_1):CLK_156M_OSC_BRD_CPU0_DP

RES  I78  R6F10  [RES_0402-0.0,5%,1/16W,EMPTY,G2A]
    2  CLK_322M_OSC_CPU0_RC_DN      B  @BASEBOARD_FAB2_LIB.BASEBOARD_FAB2(SCH_1):CLK_322M_OSC_CPU0_RC_DN
    1  CLK_322M_156M_CPU0_OSC_VRM_DN      A  @BASEBOARD_FAB2_LIB.BASEBOARD_FAB2(SCH_1):CLK_322M_156M_CPU0_OSC_VRM_DN

RES  I79  R6F11  [RES_0402-0.0,5%,1/16W,EMPTY,G2A]
    2  CLK_322M_OSC_CPU0_RC_DP      B  @BASEBOARD_FAB2_LIB.BASEBOARD_FAB2(SCH_1):CLK_322M_OSC_CPU0_RC_DP
    1  CLK_322M_156M_CPU0_OSC_VRM_DP      A  @BASEBOARD_FAB2_LIB.BASEBOARD_FAB2(SCH_1):CLK_322M_156M_CPU0_OSC_VRM_DP

RES  I64  R6L1   [RES_0402-1.00K,1%,1/16W,CHIP,GA]
    1  M_F_VREF           A  @BASEBOARD_FAB2_LIB.BASEBOARD_FAB2(SCH_1):M_F_VREF
    2  GND                B  @BASEBOARD_FAB2_LIB.BASEBOARD_FAB2(SCH_1):GND

RES  I62  R6L2   [RES_0402-1.00K,1%,1/16W,CHIP,GA]
    1  PVDDQ_DEF          A  @BASEBOARD_FAB2_LIB.BASEBOARD_FAB2(SCH_1):PVDDQ_DEF
    2  M_F_VREF           B  @BASEBOARD_FAB2_LIB.BASEBOARD_FAB2(SCH_1):M_F_VREF

RES  I66  R6L3   [RES_0402-2,1.0%,1/16W,CHIP,G21A]
    2  M_F_VREF           B  @BASEBOARD_FAB2_LIB.BASEBOARD_FAB2(SCH_1):M_F_VREF
    1  M_F_CPU_VREF       A  @BASEBOARD_FAB2_LIB.BASEBOARD_FAB2(SCH_1):M_F_CPU_VREF

RES  I37  R6L4   [RES_0402-1.0M,1%,1/16W,EMPTY,GA]
    1  P3V3               A  @BASEBOARD_FAB2_LIB.BASEBOARD_FAB2(SCH_1):P3V3
    2  FM_PVTT_DEF_EN_R      B  @BASEBOARD_FAB2_LIB.BASEBOARD_FAB2(SCH_1):FM_PVTT_DEF_EN_R

RES  I37  R6L5   [RES_0402-1.0M,1%,1/16W,EMPTY,GA]
    1  P3V3               A  @BASEBOARD_FAB2_LIB.BASEBOARD_FAB2(SCH_1):P3V3
    2  FM_PVTT_KLM_EN_R      B  @BASEBOARD_FAB2_LIB.BASEBOARD_FAB2(SCH_1):FM_PVTT_KLM_EN_R

RES  I34  R6L6   [RES_0402-0.0,5%,1/16W,CHIP,G21A]
    2  VSENSE_PVDDQ_KLM_VTT      B  @BASEBOARD_FAB2_LIB.BASEBOARD_FAB2(SCH_1):VSENSE_PVDDQ_KLM_VTT
    1  PVDDQ_KLM          A  @BASEBOARD_FAB2_LIB.BASEBOARD_FAB2(SCH_1):PVDDQ_KLM

RES  I52  R6L7   [RES_0402-51.1,1.0%,1/16W,CHIP,A]
    2  PVTT_KLM           B  @BASEBOARD_FAB2_LIB.BASEBOARD_FAB2(SCH_1):PVTT_KLM
    1  GND                A  @BASEBOARD_FAB2_LIB.BASEBOARD_FAB2(SCH_1):GND

RES  I30  R6L8   [RES_0402-0.0,5%,1/16W,CHIP,G21A]
    2  VR_PVTT_KLM_BIAS      B  @BASEBOARD_FAB2_LIB.BASEBOARD_FAB2(SCH_1):VR_PVTT_KLM_BIAS
    1  P3V3               A  @BASEBOARD_FAB2_LIB.BASEBOARD_FAB2(SCH_1):P3V3

RES  I19  R6L9   [RES_0402-10.0K,1%,1/16W,CHIP,GA]
    2  PWRGD_PVTT_DEF_CPU0_R      B  @BASEBOARD_FAB2_LIB.BASEBOARD_FAB2(SCH_1):PWRGD_PVTT_DEF_CPU0_R
    1  P3V3               A  @BASEBOARD_FAB2_LIB.BASEBOARD_FAB2(SCH_1):P3V3

RES  I34  R6L10  [RES_0402-0.0,5%,1/16W,CHIP,G21A]
    2  VSENSE_PVDDQ_DEF_VTT      B  @BASEBOARD_FAB2_LIB.BASEBOARD_FAB2(SCH_1):VSENSE_PVDDQ_DEF_VTT
    1  PVDDQ_DEF          A  @BASEBOARD_FAB2_LIB.BASEBOARD_FAB2(SCH_1):PVDDQ_DEF

RES  I30  R6L11  [RES_0402-0.0,5%,1/16W,CHIP,G21A]
    2  VR_PVTT_DEF_BIAS      B  @BASEBOARD_FAB2_LIB.BASEBOARD_FAB2(SCH_1):VR_PVTT_DEF_BIAS
    1  P3V3               A  @BASEBOARD_FAB2_LIB.BASEBOARD_FAB2(SCH_1):P3V3

RES  I56  R6L12  [RES_0402-1.00K,1%,1/16W,CHIP,GA]
    1  M_E_VREF           A  @BASEBOARD_FAB2_LIB.BASEBOARD_FAB2(SCH_1):M_E_VREF
    2  GND                B  @BASEBOARD_FAB2_LIB.BASEBOARD_FAB2(SCH_1):GND

RES  I54  R6L13  [RES_0402-1.00K,1%,1/16W,CHIP,GA]
    1  PVDDQ_DEF          A  @BASEBOARD_FAB2_LIB.BASEBOARD_FAB2(SCH_1):PVDDQ_DEF
    2  M_E_VREF           B  @BASEBOARD_FAB2_LIB.BASEBOARD_FAB2(SCH_1):M_E_VREF

RES  I58  R6L14  [RES_0402-2,1.0%,1/16W,CHIP,G21A]
    2  M_E_VREF           B  @BASEBOARD_FAB2_LIB.BASEBOARD_FAB2(SCH_1):M_E_VREF
    1  M_E_CPU_VREF       A  @BASEBOARD_FAB2_LIB.BASEBOARD_FAB2(SCH_1):M_E_CPU_VREF

RES  I12  R6L16  [RES_0402-1.00K,1%,1/16W,CHIP,GA]
    1  M_D_VREF           A  @BASEBOARD_FAB2_LIB.BASEBOARD_FAB2(SCH_1):M_D_VREF
    2  GND                B  @BASEBOARD_FAB2_LIB.BASEBOARD_FAB2(SCH_1):GND

RES  I9   R6M1   [RES_0402-1.00K,1%,1/16W,CHIP,GA]
    1  PVDDQ_DEF          A  @BASEBOARD_FAB2_LIB.BASEBOARD_FAB2(SCH_1):PVDDQ_DEF
    2  M_D_VREF           B  @BASEBOARD_FAB2_LIB.BASEBOARD_FAB2(SCH_1):M_D_VREF

RES  I14  R6M2   [RES_0402-2,1.0%,1/16W,CHIP,G21A]
    2  M_D_VREF           B  @BASEBOARD_FAB2_LIB.BASEBOARD_FAB2(SCH_1):M_D_VREF
    1  M_D_CPU_VREF       A  @BASEBOARD_FAB2_LIB.BASEBOARD_FAB2(SCH_1):M_D_CPU_VREF

RES  I82  R6M4   [RES_0402-4.75K,1%,1/16W,CHIP,GA]
    1  P3V3               A  @BASEBOARD_FAB2_LIB.BASEBOARD_FAB2(SCH_1):P3V3
    2  H_CPU1_MEMKLM_MEMHOT      B  @BASEBOARD_FAB2_LIB.BASEBOARD_FAB2(SCH_1):H_CPU1_MEMKLM_MEMHOT

RES  I188  R6M8   [RES_0402-49.9,1%,1/16W,CHIP,G2A]
    1  JTAG_MCP_CPU1_TDI_R      A  @BASEBOARD_FAB2_LIB.BASEBOARD_FAB2(SCH_1):JTAG_MCP_CPU1_TDI_R
    2  JTAG_MCP_CPU1_TDI      B  @BASEBOARD_FAB2_LIB.BASEBOARD_FAB2(SCH_1):JTAG_MCP_CPU1_TDI

RES  I49  R6M9   [RES_0402-4.75K,1%,1/16W,CHIP,GA]
    2  RST_CD_CPU1_POR_N      B  @BASEBOARD_FAB2_LIB.BASEBOARD_FAB2(SCH_1):RST_CD_CPU1_POR_N
    1  PVPP_KLM           A  @BASEBOARD_FAB2_LIB.BASEBOARD_FAB2(SCH_1):PVPP_KLM

RES  I164  R6N1   [RES_0402-49.9,1%,1/16W,CHIP,G2A]
    1  SVID_ALERT0_CPU0_R_N      A  @BASEBOARD_FAB2_LIB.BASEBOARD_FAB2(SCH_1):SVID_ALERT0_CPU0_R_N
    2  PVCCIO_CPU0        B  @BASEBOARD_FAB2_LIB.BASEBOARD_FAB2(SCH_1):PVCCIO_CPU0

RES  I163  R6N2   [RES_0402-100.0,1%,1/16W,CHIP,GA]
    1  SVID_DIO0_CPU0_R      A  @BASEBOARD_FAB2_LIB.BASEBOARD_FAB2(SCH_1):SVID_DIO0_CPU0_R
    2  PVCCIO_CPU0        B  @BASEBOARD_FAB2_LIB.BASEBOARD_FAB2(SCH_1):PVCCIO_CPU0

RES  I19  R6N3   [RES_0402-1.0,1%,1/16W,CHIP,G21A]
    1  VR_PVSA_CPU0_VCIN      A  @BASEBOARD_FAB2_LIB.BASEBOARD_FAB2(SCH_1):VR_PVSA_CPU0_VCIN
    2  P5V_STBY           B  @BASEBOARD_FAB2_LIB.BASEBOARD_FAB2(SCH_1):P5V_STBY

RES  I45  R6N4   [RES_0402-51.1,1.0%,1/16W,CHIP,A]
    1  PVSA_CPU0          A  @BASEBOARD_FAB2_LIB.BASEBOARD_FAB2(SCH_1):PVSA_CPU0
    2  GND                B  @BASEBOARD_FAB2_LIB.BASEBOARD_FAB2(SCH_1):GND

RES  I2   R6N8   [RES_0402-10.0,1%,1/16W,CHIP,G2A]
    1  SMB_CPU1_PE_HP_GTL_SCL      A  @BASEBOARD_FAB2_LIB.BASEBOARD_FAB2(SCH_1):SMB_CPU1_PE_HP_GTL_SCL
    2  SMB_CPU1_PE_HP_GTL_R_SCL      B  @BASEBOARD_FAB2_LIB.BASEBOARD_FAB2(SCH_1):SMB_CPU1_PE_HP_GTL_R_SCL

RES  I3   R6N9   [RES_0402-10.0,1%,1/16W,CHIP,G2A]
    1  SMB_CPU1_PE_HP_GTL_SDA      A  @BASEBOARD_FAB2_LIB.BASEBOARD_FAB2(SCH_1):SMB_CPU1_PE_HP_GTL_SDA
    2  SMB_CPU1_PE_HP_GTL_R_SDA      B  @BASEBOARD_FAB2_LIB.BASEBOARD_FAB2(SCH_1):SMB_CPU1_PE_HP_GTL_R_SDA

RES  I149  R6N10  [RES_0402-221,1.0%,1/16W,CHIP,GA]
    2  SVID_ALERT0_CPU0_R_N      B  @BASEBOARD_FAB2_LIB.BASEBOARD_FAB2(SCH_1):SVID_ALERT0_CPU0_R_N
    1  SVID_ALERT0_CPU0_N      A  @BASEBOARD_FAB2_LIB.BASEBOARD_FAB2(SCH_1):SVID_ALERT0_CPU0_N

RES  I151  R6N11  [RES_0402-0.0,5%,1/16W,CHIP,G21A]
    2  SVID_DIO0_CPU0_R      B  @BASEBOARD_FAB2_LIB.BASEBOARD_FAB2(SCH_1):SVID_DIO0_CPU0_R
    1  SVID_DIO0_CPU0      A  @BASEBOARD_FAB2_LIB.BASEBOARD_FAB2(SCH_1):SVID_DIO0_CPU0

RES  I150  R6N12  [RES_0402-0.0,5%,1/16W,CHIP,G21A]
    2  SVID_CLK0_CPU0_R      B  @BASEBOARD_FAB2_LIB.BASEBOARD_FAB2(SCH_1):SVID_CLK0_CPU0_R
    1  SVID_CLK0_CPU0      A  @BASEBOARD_FAB2_LIB.BASEBOARD_FAB2(SCH_1):SVID_CLK0_CPU0

RES  I303  R6N13  [RES_0402-1.00K,1%,1/16W,CHIP,GA]
    2  PD_PIROM_CPU0_ADDR1      B  @BASEBOARD_FAB2_LIB.BASEBOARD_FAB2(SCH_1):PD_PIROM_CPU0_ADDR1
    1  GND                A  @BASEBOARD_FAB2_LIB.BASEBOARD_FAB2(SCH_1):GND

RES  I302  R6N14  [RES_0402-1.00K,1%,1/16W,CHIP,GA]
    2  PD_PIROM_CPU0_ADDR0      B  @BASEBOARD_FAB2_LIB.BASEBOARD_FAB2(SCH_1):PD_PIROM_CPU0_ADDR0
    1  GND                A  @BASEBOARD_FAB2_LIB.BASEBOARD_FAB2(SCH_1):GND

RES  I304  R6N15  [RES_0402-1.00K,1%,1/16W,CHIP,GA]
    2  PD_PIROM_CPU0_ADDR2      B  @BASEBOARD_FAB2_LIB.BASEBOARD_FAB2(SCH_1):PD_PIROM_CPU0_ADDR2
    1  GND                A  @BASEBOARD_FAB2_LIB.BASEBOARD_FAB2(SCH_1):GND

RES  I149  R6P1   [RES_0402-42.2,1.0%,1/16W,EMPTYA]
    2  GND                B  @BASEBOARD_FAB2_LIB.BASEBOARD_FAB2(SCH_1):GND
    1  CLK_100M_CPU0_RC_REFCLK0_DP      A  @BASEBOARD_FAB2_LIB.BASEBOARD_FAB2(SCH_1):CLK_100M_CPU0_RC_REFCLK0_DP

RES  I151  R6P2   [RES_0402-42.2,1.0%,1/16W,EMPTYA]
    2  GND                B  @BASEBOARD_FAB2_LIB.BASEBOARD_FAB2(SCH_1):GND
    1  CLK_100M_CPU0_RC_REFCLK0_DN      A  @BASEBOARD_FAB2_LIB.BASEBOARD_FAB2(SCH_1):CLK_100M_CPU0_RC_REFCLK0_DN

RES  I145  R6P3   [RES_0402-42.2,1.0%,1/16W,EMPTYA]
    2  GND                B  @BASEBOARD_FAB2_LIB.BASEBOARD_FAB2(SCH_1):GND
    1  CLK_100M_CPU0_RC_REFCLK1_DP      A  @BASEBOARD_FAB2_LIB.BASEBOARD_FAB2(SCH_1):CLK_100M_CPU0_RC_REFCLK1_DP

RES  I147  R6P4   [RES_0402-42.2,1.0%,1/16W,EMPTYA]
    2  GND                B  @BASEBOARD_FAB2_LIB.BASEBOARD_FAB2(SCH_1):GND
    1  CLK_100M_CPU0_RC_REFCLK1_DN      A  @BASEBOARD_FAB2_LIB.BASEBOARD_FAB2(SCH_1):CLK_100M_CPU0_RC_REFCLK1_DN

RES  I141  R6P5   [RES_0402-42.2,1.0%,1/16W,EMPTYA]
    2  GND                B  @BASEBOARD_FAB2_LIB.BASEBOARD_FAB2(SCH_1):GND
    1  CLK_100M_CPU1_BCLK0_DP      A  @BASEBOARD_FAB2_LIB.BASEBOARD_FAB2(SCH_1):CLK_100M_CPU1_BCLK0_DP

RES  I143  R6P6   [RES_0402-42.2,1.0%,1/16W,EMPTYA]
    2  GND                B  @BASEBOARD_FAB2_LIB.BASEBOARD_FAB2(SCH_1):GND
    1  CLK_100M_CPU1_BCLK0_DN      A  @BASEBOARD_FAB2_LIB.BASEBOARD_FAB2(SCH_1):CLK_100M_CPU1_BCLK0_DN

RES  I137  R6P7   [RES_0402-42.2,1.0%,1/16W,EMPTYA]
    2  GND                B  @BASEBOARD_FAB2_LIB.BASEBOARD_FAB2(SCH_1):GND
    1  CLK_100M_CPU1_BCLK1_DP      A  @BASEBOARD_FAB2_LIB.BASEBOARD_FAB2(SCH_1):CLK_100M_CPU1_BCLK1_DP

RES  I139  R6P8   [RES_0402-42.2,1.0%,1/16W,EMPTYA]
    2  GND                B  @BASEBOARD_FAB2_LIB.BASEBOARD_FAB2(SCH_1):GND
    1  CLK_100M_CPU1_BCLK1_DN      A  @BASEBOARD_FAB2_LIB.BASEBOARD_FAB2(SCH_1):CLK_100M_CPU1_BCLK1_DN

RES  I155  R6P9   [RES_0402-42.2,1.0%,1/16W,EMPTYA]
    2  GND                B  @BASEBOARD_FAB2_LIB.BASEBOARD_FAB2(SCH_1):GND
    1  CLK_100M_CPU0_PE_REFCLK_DN      A  @BASEBOARD_FAB2_LIB.BASEBOARD_FAB2(SCH_1):CLK_100M_CPU0_PE_REFCLK_DN

RES  I50  R6P10  [RES_0402-1.0,1%,1/16W,CHIP,G21A]
    1  VR_PVCCIN_CPU0_PH4_VCIN      A  @BASEBOARD_FAB2_LIB.BASEBOARD_FAB2(SCH_1):VR_PVCCIN_CPU0_PH4_VCIN
    2  P5V_STBY           B  @BASEBOARD_FAB2_LIB.BASEBOARD_FAB2(SCH_1):P5V_STBY

RES  I153  R6P11  [RES_0402-42.2,1.0%,1/16W,EMPTYA]
    2  GND                B  @BASEBOARD_FAB2_LIB.BASEBOARD_FAB2(SCH_1):GND
    1  CLK_100M_CPU0_PE_REFCLK_DP      A  @BASEBOARD_FAB2_LIB.BASEBOARD_FAB2(SCH_1):CLK_100M_CPU0_PE_REFCLK_DP

RES  I159  R6P12  [RES_0402-42.2,1.0%,1/16W,EMPTYA]
    2  GND                B  @BASEBOARD_FAB2_LIB.BASEBOARD_FAB2(SCH_1):GND
    1  CLK_100M_CPU0_BCLK2_DN      A  @BASEBOARD_FAB2_LIB.BASEBOARD_FAB2(SCH_1):CLK_100M_CPU0_BCLK2_DN

RES  I157  R6P13  [RES_0402-42.2,1.0%,1/16W,EMPTYA]
    2  GND                B  @BASEBOARD_FAB2_LIB.BASEBOARD_FAB2(SCH_1):GND
    1  CLK_100M_CPU0_BCLK2_DP      A  @BASEBOARD_FAB2_LIB.BASEBOARD_FAB2(SCH_1):CLK_100M_CPU0_BCLK2_DP

RES  I167  R6P15  [RES_0402-42.2,1.0%,1/16W,EMPTYA]
    2  GND                B  @BASEBOARD_FAB2_LIB.BASEBOARD_FAB2(SCH_1):GND
    1  CLK_100M_CPU0_BCLK0_DN      A  @BASEBOARD_FAB2_LIB.BASEBOARD_FAB2(SCH_1):CLK_100M_CPU0_BCLK0_DN

RES  I132  R6P16  [RES_0402-1.00K,1%,1/16W,CHIP,GA]
    2  VR_PVCCIN_CPU0_VREN      B  @BASEBOARD_FAB2_LIB.BASEBOARD_FAB2(SCH_1):VR_PVCCIN_CPU0_VREN
    1  PVCCIO_CPU0        A  @BASEBOARD_FAB2_LIB.BASEBOARD_FAB2(SCH_1):PVCCIO_CPU0

RES  I165  R6P17  [RES_0402-42.2,1.0%,1/16W,EMPTYA]
    2  GND                B  @BASEBOARD_FAB2_LIB.BASEBOARD_FAB2(SCH_1):GND
    1  CLK_100M_CPU0_BCLK0_DP      A  @BASEBOARD_FAB2_LIB.BASEBOARD_FAB2(SCH_1):CLK_100M_CPU0_BCLK0_DP

RES  I131  R6P18  [RES_0402-0.0,5%,1/16W,CHIP,G21A]
    2  VR_PVCCIN_CPU0_VREN      B  @BASEBOARD_FAB2_LIB.BASEBOARD_FAB2(SCH_1):VR_PVCCIN_CPU0_VREN
    1  FM_PVCCIN_PVCCSA_CPU0_EN_LVC1      A  @BASEBOARD_FAB2_LIB.BASEBOARD_FAB2(SCH_1):FM_PVCCIN_PVCCSA_CPU0_EN_LVC1

RES  I38  R6P19  [RES_0402-1.0,1%,1/16W,CHIP,G21A]
    1  VR_PVCCIN_CPU0_PH3_VCIN      A  @BASEBOARD_FAB2_LIB.BASEBOARD_FAB2(SCH_1):VR_PVCCIN_CPU0_PH3_VCIN
    2  P5V_STBY           B  @BASEBOARD_FAB2_LIB.BASEBOARD_FAB2(SCH_1):P5V_STBY

RES  I81  R6P20  [RES_0402-1.00K,1%,1/16W,CHIP,GA]
    2  GND                B  @BASEBOARD_FAB2_LIB.BASEBOARD_FAB2(SCH_1):GND
    1  FM_DB1200_SMB_SA1      A  @BASEBOARD_FAB2_LIB.BASEBOARD_FAB2(SCH_1):FM_DB1200_SMB_SA1

RES  I80  R6P21  [RES_0402-1.00K,1%,1/16W,CHIP,GA]
    2  GND                B  @BASEBOARD_FAB2_LIB.BASEBOARD_FAB2(SCH_1):GND
    1  FM_DB1200_SMB_SA0      A  @BASEBOARD_FAB2_LIB.BASEBOARD_FAB2(SCH_1):FM_DB1200_SMB_SA0

RES  I47  R6P22  [RES_0402-4.75K,1%,1/16W,EMPTY,A]
    2  GND                B  @BASEBOARD_FAB2_LIB.BASEBOARD_FAB2(SCH_1):GND
    1  FM_HBW_BYPASS_LOWBW_N      A  @BASEBOARD_FAB2_LIB.BASEBOARD_FAB2(SCH_1):FM_HBW_BYPASS_LOWBW_N

RES  I46  R6P23  [RES_0402-4.75K,1%,1/16W,EMPTY,A]
    2  GND                B  @BASEBOARD_FAB2_LIB.BASEBOARD_FAB2(SCH_1):GND
    1  FM_100M_N          A  @BASEBOARD_FAB2_LIB.BASEBOARD_FAB2(SCH_1):FM_100M_N

RES  I26  R6P25  [RES_0603-2.2,1.0%,1/10W,CHIP,GA]
    2  P3V3_DB1200_R      B  @BASEBOARD_FAB2_LIB.BASEBOARD_FAB2(SCH_1):P3V3_DB1200_R
    1  P3V3_DB1200        A  @BASEBOARD_FAB2_LIB.BASEBOARD_FAB2(SCH_1):P3V3_DB1200

RES  I120  R6P27  [RES_0402-4.02K,1%,1/16W,CHIP,GA]
    1  VR_PVCCIN_CPU0_XADDR2      A  @BASEBOARD_FAB2_LIB.BASEBOARD_FAB2(SCH_1):VR_PVCCIN_CPU0_XADDR2
    2  GND                B  @BASEBOARD_FAB2_LIB.BASEBOARD_FAB2(SCH_1):GND

RES  I121  R6P28  [RES_0402-4.02K,1%,1/16W,CHIP,GA]
    1  VR_PVCCIN_CPU0_XADDR1      A  @BASEBOARD_FAB2_LIB.BASEBOARD_FAB2(SCH_1):VR_PVCCIN_CPU0_XADDR1
    2  GND                B  @BASEBOARD_FAB2_LIB.BASEBOARD_FAB2(SCH_1):GND

RES  I154  R6P29  [RES_0402-0.0,5%,1/16W,CHIP,G21A]
    2  VR_PVSA_CPU0_BIREF1      B  @BASEBOARD_FAB2_LIB.BASEBOARD_FAB2(SCH_1):VR_PVSA_CPU0_BIREF1
    1  VR_PVCCIN_CPU0_VD12      A  @BASEBOARD_FAB2_LIB.BASEBOARD_FAB2(SCH_1):VR_PVCCIN_CPU0_VD12

RES  I149  R6P30  [RES_0402-0.0,5%,1/16W,CHIP,G21A]
    1  VR_PVCCIN_CPU0_VD12      A  @BASEBOARD_FAB2_LIB.BASEBOARD_FAB2(SCH_1):VR_PVCCIN_CPU0_VD12
    2  VR_PVCCIN_CPU0_AIREF5      B  @BASEBOARD_FAB2_LIB.BASEBOARD_FAB2(SCH_1):VR_PVCCIN_CPU0_AIREF5

RES  I102  R6P32  [RES_0402-2.0K,1%,1/16W,EMPTY,GA]
    2  SMB_VR_STBY_LVC3_SDA      B  @BASEBOARD_FAB2_LIB.BASEBOARD_FAB2(SCH_1):SMB_VR_STBY_LVC3_SDA
    1  P3V3_STBY          A  @BASEBOARD_FAB2_LIB.BASEBOARD_FAB2(SCH_1):P3V3_STBY

RES  I30  R6P33  [RES_0402-110,1%,1/16W,EMPTY,G2A]
    2  SVID_CLK0_CPU1_R      B  @BASEBOARD_FAB2_LIB.BASEBOARD_FAB2(SCH_1):SVID_CLK0_CPU1_R
    1  PVCCIO_CPU1        A  @BASEBOARD_FAB2_LIB.BASEBOARD_FAB2(SCH_1):PVCCIO_CPU1

RES  I148  R6P34  [RES_0402-0.0,5%,1/16W,CHIP,G21A]
    1  VR_PVCCIN_CPU0_VD12      A  @BASEBOARD_FAB2_LIB.BASEBOARD_FAB2(SCH_1):VR_PVCCIN_CPU0_VD12
    2  VR_PVCCIN_CPU0_AIREF4      B  @BASEBOARD_FAB2_LIB.BASEBOARD_FAB2(SCH_1):VR_PVCCIN_CPU0_AIREF4

RES  I27  R6P35  [RES_0402-100.0,1%,1/16W,EMPTY,A]
    2  SVID_DIO0_CPU1_R      B  @BASEBOARD_FAB2_LIB.BASEBOARD_FAB2(SCH_1):SVID_DIO0_CPU1_R
    1  PVCCIO_CPU1        A  @BASEBOARD_FAB2_LIB.BASEBOARD_FAB2(SCH_1):PVCCIO_CPU1

RES  I103  R6P37  [RES_0402-2.0K,1%,1/16W,EMPTY,GA]
    2  SMB_VR_STBY_LVC3_SCL      B  @BASEBOARD_FAB2_LIB.BASEBOARD_FAB2(SCH_1):SMB_VR_STBY_LVC3_SCL
    1  P3V3_STBY          A  @BASEBOARD_FAB2_LIB.BASEBOARD_FAB2(SCH_1):P3V3_STBY

RES  I147  R6P38  [RES_0402-0.0,5%,1/16W,CHIP,G21A]
    1  VR_PVCCIN_CPU0_VD12      A  @BASEBOARD_FAB2_LIB.BASEBOARD_FAB2(SCH_1):VR_PVCCIN_CPU0_VD12
    2  VR_PVCCIN_CPU0_AIREF3      B  @BASEBOARD_FAB2_LIB.BASEBOARD_FAB2(SCH_1):VR_PVCCIN_CPU0_AIREF3

RES  I181  R6P39  [RES_0402-4.75K,1%,1/16W,CHIP,GA]
    1  P3V3_STBY          A  @BASEBOARD_FAB2_LIB.BASEBOARD_FAB2(SCH_1):P3V3_STBY
    2  FM_CPU1_SKTOCC_LVT3_N      B  @BASEBOARD_FAB2_LIB.BASEBOARD_FAB2(SCH_1):FM_CPU1_SKTOCC_LVT3_N

RES  I91  R6P40  [RES_0402-100.0K,1%,1/16W,EMPTYA]
    2  VR_PVCCIO_CPU1_EN      B  @BASEBOARD_FAB2_LIB.BASEBOARD_FAB2(SCH_1):VR_PVCCIO_CPU1_EN
    1  P3V3_STBY          A  @BASEBOARD_FAB2_LIB.BASEBOARD_FAB2(SCH_1):P3V3_STBY

RES  I90  R6P41  [RES_0402-0.0,5%,1/16W,CHIP,G21A]
    2  VR_PVCCIO_CPU1_EN      B  @BASEBOARD_FAB2_LIB.BASEBOARD_FAB2(SCH_1):VR_PVCCIO_CPU1_EN
    1  FM_PVCCIO_CPU1_EN      A  @BASEBOARD_FAB2_LIB.BASEBOARD_FAB2(SCH_1):FM_PVCCIO_CPU1_EN

RES  I139  R6P42  [RES_0402-0.0,5%,1/16W,CHIP,G21A]
    1  VR_PVCCIN_CPU0_VD12      A  @BASEBOARD_FAB2_LIB.BASEBOARD_FAB2(SCH_1):VR_PVCCIN_CPU0_VD12
    2  VR_PVCCIN_CPU0_AIREF2      B  @BASEBOARD_FAB2_LIB.BASEBOARD_FAB2(SCH_1):VR_PVCCIN_CPU0_AIREF2

RES  I150  R6P43  [RES_0402-0.0,5%,1/16W,CHIP,G21A]
    1  VR_PVCCIN_CPU0_VD12      A  @BASEBOARD_FAB2_LIB.BASEBOARD_FAB2(SCH_1):VR_PVCCIN_CPU0_VD12
    2  VR_PVCCIN_CPU0_AIREF1      B  @BASEBOARD_FAB2_LIB.BASEBOARD_FAB2(SCH_1):VR_PVCCIN_CPU0_AIREF1

RES  I128  R6P45  [RES_0402-33.2,1%,1/16W,CHIP,G2A]
    1  IRQ_PVCCIN_CPU0_VRHOT_LVC3_R_N      A  @BASEBOARD_FAB2_LIB.BASEBOARD_FAB2(SCH_1):IRQ_PVCCIN_CPU0_VRHOT_LVC3_R_N
    2  IRQ_PVCCIN_CPU0_VRHOT_LVC3_N      B  @BASEBOARD_FAB2_LIB.BASEBOARD_FAB2(SCH_1):IRQ_PVCCIN_CPU0_VRHOT_LVC3_N

RES  I49  R6P46  [RES_0402-100.0,1%,1/16W,CHIP,GA]
    2  XDP_CPU_MBP1_N      B  @BASEBOARD_FAB2_LIB.BASEBOARD_FAB2(SCH_1):XDP_CPU_MBP1_N
    1  PVCCIO_CPU0        A  @BASEBOARD_FAB2_LIB.BASEBOARD_FAB2(SCH_1):PVCCIO_CPU0

RES  I33  R6P47  [RES_0402-1.0,1%,1/16W,CHIP,G21A]
    1  VR_PVCCIN_CPU0_PH5_VCIN      A  @BASEBOARD_FAB2_LIB.BASEBOARD_FAB2(SCH_1):VR_PVCCIN_CPU0_PH5_VCIN
    2  P5V_STBY           B  @BASEBOARD_FAB2_LIB.BASEBOARD_FAB2(SCH_1):P5V_STBY

RES  I91  R6P48  [RES_0402-4.75K,1%,1/16W,CHIP,GA]
    1  P3V3               A  @BASEBOARD_FAB2_LIB.BASEBOARD_FAB2(SCH_1):P3V3
    2  FM_DB1200ZL_BCLKS_EN_N      B  @BASEBOARD_FAB2_LIB.BASEBOARD_FAB2(SCH_1):FM_DB1200ZL_BCLKS_EN_N

RES  I14  R6P49  [RES_0402-2.26K,1.0%,1/16W,EMPTA]
    2  PU_VR_PVCCIO_CPU1_FAULT1      B  @BASEBOARD_FAB2_LIB.BASEBOARD_FAB2(SCH_1):PU_VR_PVCCIO_CPU1_FAULT1
    1  P3V3_STBY          A  @BASEBOARD_FAB2_LIB.BASEBOARD_FAB2(SCH_1):P3V3_STBY

RES  I33  R6R2   [RES_0402-1.0,1%,1/16W,CHIP,G21A]
    1  VR_PVCCIN_CPU0_PH1_VCIN      A  @BASEBOARD_FAB2_LIB.BASEBOARD_FAB2(SCH_1):VR_PVCCIN_CPU0_PH1_VCIN
    2  P5V_STBY           B  @BASEBOARD_FAB2_LIB.BASEBOARD_FAB2(SCH_1):P5V_STBY

RES  I71  R6R5   [RES_0402-1.0,1%,1/16W,CHIP,G21A]
    1  VR_PVCCIO_CPU1_PH1_VCIN      A  @BASEBOARD_FAB2_LIB.BASEBOARD_FAB2(SCH_1):VR_PVCCIO_CPU1_PH1_VCIN
    2  P5V_STBY           B  @BASEBOARD_FAB2_LIB.BASEBOARD_FAB2(SCH_1):P5V_STBY

RES  I39  R6R6   [RES_0402-1.0,1%,1/16W,CHIP,G21A]
    1  VR_PVCCIN_CPU0_PH2_VCIN      A  @BASEBOARD_FAB2_LIB.BASEBOARD_FAB2(SCH_1):VR_PVCCIN_CPU0_PH2_VCIN
    2  P5V_STBY           B  @BASEBOARD_FAB2_LIB.BASEBOARD_FAB2(SCH_1):P5V_STBY

RES  I70  R6T1   [RES_0402-240,1.0%,1/16W,CHIP,GA]
    2  SMB_DDR_GHJ_SDA_G      B  @BASEBOARD_FAB2_LIB.BASEBOARD_FAB2(SCH_1):SMB_DDR_GHJ_SDA_G
    1  PVCCIO_CPU1        A  @BASEBOARD_FAB2_LIB.BASEBOARD_FAB2(SCH_1):PVCCIO_CPU1

RES  I72  R6T2   [RES_0402-240,1.0%,1/16W,CHIP,GA]
    2  SMB_DDR_GHJ_SCL_G      B  @BASEBOARD_FAB2_LIB.BASEBOARD_FAB2(SCH_1):SMB_DDR_GHJ_SCL_G
    1  PVCCIO_CPU1        A  @BASEBOARD_FAB2_LIB.BASEBOARD_FAB2(SCH_1):PVCCIO_CPU1

RES  I92  R6T3   [RES_0402-10.0,1%,1/16W,CHIP,G2A]
    1  SMB_DDR_GHJ_SCL_G_R      A  @BASEBOARD_FAB2_LIB.BASEBOARD_FAB2(SCH_1):SMB_DDR_GHJ_SCL_G_R
    2  SMB_DDR_GHJ_SCL_G      B  @BASEBOARD_FAB2_LIB.BASEBOARD_FAB2(SCH_1):SMB_DDR_GHJ_SCL_G

RES  I111  R6T4   [RES_0402-10.0,1%,1/16W,CHIP,G2A]
    1  SMB_DDR_GHJ_SDA_G_R      A  @BASEBOARD_FAB2_LIB.BASEBOARD_FAB2(SCH_1):SMB_DDR_GHJ_SDA_G_R
    2  SMB_DDR_GHJ_SDA_G      B  @BASEBOARD_FAB2_LIB.BASEBOARD_FAB2(SCH_1):SMB_DDR_GHJ_SDA_G

RES  I62  R6T5   [RES_0402-1.00K,1%,1/16W,CHIP,GA]
    1  XDP_CPU_TRST_N      A  @BASEBOARD_FAB2_LIB.BASEBOARD_FAB2(SCH_1):XDP_CPU_TRST_N
    2  GND                B  @BASEBOARD_FAB2_LIB.BASEBOARD_FAB2(SCH_1):GND

RES  I56  R6T6   [RES_0402-150.0,1%,1/16W,CHIP,GA]
    2  XDP_CPU1_TDI       B  @BASEBOARD_FAB2_LIB.BASEBOARD_FAB2(SCH_1):XDP_CPU1_TDI
    1  PVCCIO_CPU1        A  @BASEBOARD_FAB2_LIB.BASEBOARD_FAB2(SCH_1):PVCCIO_CPU1

RES  I55  R6T7   [RES_0402-150.0,1%,1/16W,CHIP,GA]
    2  XDP_CPU1_TDO       B  @BASEBOARD_FAB2_LIB.BASEBOARD_FAB2(SCH_1):XDP_CPU1_TDO
    1  PVCCIO_CPU1        A  @BASEBOARD_FAB2_LIB.BASEBOARD_FAB2(SCH_1):PVCCIO_CPU1

RES  I121  R6T8   [RES_0402-100.0,1%,1/16W,CHIP,GA]
    2  XDP_CPU_OBSFN_B0_MBP6_N      B  @BASEBOARD_FAB2_LIB.BASEBOARD_FAB2(SCH_1):XDP_CPU_OBSFN_B0_MBP6_N
    1  PVCCIO_CPU0        A  @BASEBOARD_FAB2_LIB.BASEBOARD_FAB2(SCH_1):PVCCIO_CPU0

RES  I120  R6T9   [RES_0402-100.0,1%,1/16W,CHIP,GA]
    2  XDP_CPU_OBSFN_B1_MBP7_N      B  @BASEBOARD_FAB2_LIB.BASEBOARD_FAB2(SCH_1):XDP_CPU_OBSFN_B1_MBP7_N
    1  PVCCIO_CPU0        A  @BASEBOARD_FAB2_LIB.BASEBOARD_FAB2(SCH_1):PVCCIO_CPU0

RES  I34  R6U3   [RES_0402-1.0M,1%,1/16W,EMPTY,GA]
    1  P3V3               A  @BASEBOARD_FAB2_LIB.BASEBOARD_FAB2(SCH_1):P3V3
    2  FM_PVTT_GHJ_EN_R      B  @BASEBOARD_FAB2_LIB.BASEBOARD_FAB2(SCH_1):FM_PVTT_GHJ_EN_R

RES  I28  R6U4   [RES_0402-0.0,5%,1/16W,CHIP,G21A]
    2  VR_PVTT_ABC_BIAS      B  @BASEBOARD_FAB2_LIB.BASEBOARD_FAB2(SCH_1):VR_PVTT_ABC_BIAS
    1  P3V3               A  @BASEBOARD_FAB2_LIB.BASEBOARD_FAB2(SCH_1):P3V3

RES  I32  R6U5   [RES_0402-0.0,5%,1/16W,CHIP,G21A]
    2  VSENSE_PVDDQ_ABC_VTT      B  @BASEBOARD_FAB2_LIB.BASEBOARD_FAB2(SCH_1):VSENSE_PVDDQ_ABC_VTT
    1  PVDDQ_ABC          A  @BASEBOARD_FAB2_LIB.BASEBOARD_FAB2(SCH_1):PVDDQ_ABC

RES  I39  R6U6   [RES_0402-0.0,5%,1/16W,CHIP,G21A]
    2  VSENSE_PVDDQ_GHJ_VTT      B  @BASEBOARD_FAB2_LIB.BASEBOARD_FAB2(SCH_1):VSENSE_PVDDQ_GHJ_VTT
    1  PVDDQ_GHJ          A  @BASEBOARD_FAB2_LIB.BASEBOARD_FAB2(SCH_1):PVDDQ_GHJ

RES  I32  R6U7   [RES_0402-0.0,5%,1/16W,CHIP,G21A]
    2  VR_PVTT_GHJ_BIAS      B  @BASEBOARD_FAB2_LIB.BASEBOARD_FAB2(SCH_1):VR_PVTT_GHJ_BIAS
    1  P3V3               A  @BASEBOARD_FAB2_LIB.BASEBOARD_FAB2(SCH_1):P3V3

RES  I52  R6U8   [RES_0402-51.1,1.0%,1/16W,CHIP,A]
    2  PVTT_GHJ           B  @BASEBOARD_FAB2_LIB.BASEBOARD_FAB2(SCH_1):PVTT_GHJ
    1  GND                A  @BASEBOARD_FAB2_LIB.BASEBOARD_FAB2(SCH_1):GND

RES  I42  R6U13  [RES_0402-20.0,1%,1/16W,CHIP,G2A]
    1  SMB_DDR_GHJ_VPP_SCL_R      A  @BASEBOARD_FAB2_LIB.BASEBOARD_FAB2(SCH_1):SMB_DDR_GHJ_VPP_SCL_R
    2  SMB_DDR_GHJ_VPP_SCL      B  @BASEBOARD_FAB2_LIB.BASEBOARD_FAB2(SCH_1):SMB_DDR_GHJ_VPP_SCL

RES  I43  R6U14  [RES_0402-20.0,1%,1/16W,CHIP,G2A]
    1  SMB_DDR_GHJ_VPP_SDA_R      A  @BASEBOARD_FAB2_LIB.BASEBOARD_FAB2(SCH_1):SMB_DDR_GHJ_VPP_SDA_R
    2  SMB_DDR_GHJ_VPP_SDA      B  @BASEBOARD_FAB2_LIB.BASEBOARD_FAB2(SCH_1):SMB_DDR_GHJ_VPP_SDA

RES  I37  R6U15  [RES_0402-1.0M,1%,1/16W,EMPTY,GA]
    1  P3V3               A  @BASEBOARD_FAB2_LIB.BASEBOARD_FAB2(SCH_1):P3V3
    2  FM_PVTT_ABC_EN_R      B  @BASEBOARD_FAB2_LIB.BASEBOARD_FAB2(SCH_1):FM_PVTT_ABC_EN_R

RES  I55  R6U16  [RES_0402-51.1,1.0%,1/16W,CHIP,A]
    2  PVTT_ABC           B  @BASEBOARD_FAB2_LIB.BASEBOARD_FAB2(SCH_1):PVTT_ABC
    1  GND                A  @BASEBOARD_FAB2_LIB.BASEBOARD_FAB2(SCH_1):GND

RES  I106  R6U17  [RES_0402-665,1.0%,1/16W,CHIP,GA]
    2  SMB_DDR_GHJ_VPP_SCL_R      B  @BASEBOARD_FAB2_LIB.BASEBOARD_FAB2(SCH_1):SMB_DDR_GHJ_VPP_SCL_R
    1  PVPP_GHJ           A  @BASEBOARD_FAB2_LIB.BASEBOARD_FAB2(SCH_1):PVPP_GHJ

RES  I104  R6U18  [RES_0402-665,1.0%,1/16W,CHIP,GA]
    2  SMB_DDR_GHJ_VPP_SDA_R      B  @BASEBOARD_FAB2_LIB.BASEBOARD_FAB2(SCH_1):SMB_DDR_GHJ_VPP_SDA_R
    1  PVPP_GHJ           A  @BASEBOARD_FAB2_LIB.BASEBOARD_FAB2(SCH_1):PVPP_GHJ

RES  I60  R7A7   [RES_0402-10.0,1%,1/16W,CHIP,G2A]
    1  VSENSE_PVDDQ_DEF_P      A  @BASEBOARD_FAB2_LIB.BASEBOARD_FAB2(SCH_1):VSENSE_PVDDQ_DEF_P
    2  VR_PVDDQ_DEF_AVSP      B  @BASEBOARD_FAB2_LIB.BASEBOARD_FAB2(SCH_1):VR_PVDDQ_DEF_AVSP

RES  I37  R7A8   [RES_0402-8.06K,1%,1/16W,CHIP,GA]
    1  VR_PVDDQ_DEF_XADDR2      A  @BASEBOARD_FAB2_LIB.BASEBOARD_FAB2(SCH_1):VR_PVDDQ_DEF_XADDR2
    2  GND                B  @BASEBOARD_FAB2_LIB.BASEBOARD_FAB2(SCH_1):GND

RES  I14  R7A9   [RES_0402-2.26K,1.0%,1/16W,EMPTA]
    2  PU_VR_PVDDQ_DEF_FAULT1      B  @BASEBOARD_FAB2_LIB.BASEBOARD_FAB2(SCH_1):PU_VR_PVDDQ_DEF_FAULT1
    1  P3V3_STBY          A  @BASEBOARD_FAB2_LIB.BASEBOARD_FAB2(SCH_1):P3V3_STBY

RES  I40  R7A10  [RES_0402-3.16K,1%,1/16W,CHIP,GA]
    1  VR_PVDDQ_DEF_XADDR1      A  @BASEBOARD_FAB2_LIB.BASEBOARD_FAB2(SCH_1):VR_PVDDQ_DEF_XADDR1
    2  GND                B  @BASEBOARD_FAB2_LIB.BASEBOARD_FAB2(SCH_1):GND

RES  I15  R7A11  [RES_0402-0.0,5%,1/16W,CHIP,G21A]
    1  SVID_ALERT_PVDDQ_DEF      A  @BASEBOARD_FAB2_LIB.BASEBOARD_FAB2(SCH_1):SVID_ALERT_PVDDQ_DEF
    2  SVID_ALERT1_CPU0_R_N      B  @BASEBOARD_FAB2_LIB.BASEBOARD_FAB2(SCH_1):SVID_ALERT1_CPU0_R_N

RES  I25  R7A12  [RES_0402-0.0,5%,1/16W,CHIP,G21A]
    1  SVID_VDIO_PVDDQ_DEF      A  @BASEBOARD_FAB2_LIB.BASEBOARD_FAB2(SCH_1):SVID_VDIO_PVDDQ_DEF
    2  SVID_DIO1_CPU0_R      B  @BASEBOARD_FAB2_LIB.BASEBOARD_FAB2(SCH_1):SVID_DIO1_CPU0_R

RES  I90  R7A13  [RES_0402-100.0,1%,1/16W,CHIP,GA]
    1  VSENSE_PVNN_PCH_STBY_AVSP      A  @BASEBOARD_FAB2_LIB.BASEBOARD_FAB2(SCH_1):VSENSE_PVNN_PCH_STBY_AVSP
    2  PVNN_PCH_STBY      B  @BASEBOARD_FAB2_LIB.BASEBOARD_FAB2(SCH_1):PVNN_PCH_STBY

RES  I94  R7A14  [RES_0402-10.0,1%,1/16W,CHIP,G2A]
    1  VSENSE_PVNN_PCH_STBY_FPK      A  @BASEBOARD_FAB2_LIB.BASEBOARD_FAB2(SCH_1):VSENSE_PVNN_PCH_STBY_FPK
    2  VSENSE_PVNN_PCH_STBY_AVSP      B  @BASEBOARD_FAB2_LIB.BASEBOARD_FAB2(SCH_1):VSENSE_PVNN_PCH_STBY_AVSP

RES  I218  R7A15  [RES_0402-2.2,5%,1/16W,EMPTY,G2A]
    1  VR_PVPP_DEF_SNUB      A  @BASEBOARD_FAB2_LIB.BASEBOARD_FAB2(SCH_1):VR_PVPP_DEF_SNUB
    2  GND                B  @BASEBOARD_FAB2_LIB.BASEBOARD_FAB2(SCH_1):GND

RES  I54  R7A16  [RES_0402-1.5K,1%,1/16W,CHIP,G2A]
    1  VR_PVDDQ_DEF_VINSEN      A  @BASEBOARD_FAB2_LIB.BASEBOARD_FAB2(SCH_1):VR_PVDDQ_DEF_VINSEN
    2  GND                B  @BASEBOARD_FAB2_LIB.BASEBOARD_FAB2(SCH_1):GND

RES  I48  R7A17  [RES_0402-150.0,1%,1/16W,CHIP,GA]
    2  SVID_CLK_PVDDQ_DEF      B  @BASEBOARD_FAB2_LIB.BASEBOARD_FAB2(SCH_1):SVID_CLK_PVDDQ_DEF
    1  SVID_CLK1_CPU0_R      A  @BASEBOARD_FAB2_LIB.BASEBOARD_FAB2(SCH_1):SVID_CLK1_CPU0_R

RES  I92  R7A18  [RES_0402-0.0,5%,1/16W,CHIP,G21A]
    2  VSENSE_PVNN_PCH_STBY_AVSN      B  @BASEBOARD_FAB2_LIB.BASEBOARD_FAB2(SCH_1):VSENSE_PVNN_PCH_STBY_AVSN
    1  GND                A  @BASEBOARD_FAB2_LIB.BASEBOARD_FAB2(SCH_1):GND

RES  I93  R7A19  [RES_0402-10.0,1%,1/16W,CHIP,G2A]
    1  VSENSE_PVNN_PCH_STBY_QAT      A  @BASEBOARD_FAB2_LIB.BASEBOARD_FAB2(SCH_1):VSENSE_PVNN_PCH_STBY_QAT
    2  VSENSE_PVNN_PCH_STBY_AVSP      B  @BASEBOARD_FAB2_LIB.BASEBOARD_FAB2(SCH_1):VSENSE_PVNN_PCH_STBY_AVSP

RES  I108  R7A20  [RES_0402-68.1K,1%,1/16W,EMPTY,A]
    1  VR_PVDDQ_DEF_PH1_OCSET      A  @BASEBOARD_FAB2_LIB.BASEBOARD_FAB2(SCH_1):VR_PVDDQ_DEF_PH1_OCSET
    2  GND                B  @BASEBOARD_FAB2_LIB.BASEBOARD_FAB2(SCH_1):GND

RES  I110  R7A21  [RES_0402-68.1K,1%,1/16W,EMPTY,A]
    1  VR_PVDDQ_DEF_PH2_OCSET      A  @BASEBOARD_FAB2_LIB.BASEBOARD_FAB2(SCH_1):VR_PVDDQ_DEF_PH2_OCSET
    2  GND                B  @BASEBOARD_FAB2_LIB.BASEBOARD_FAB2(SCH_1):GND

RES  I12  R7B1   [RES_0402-33.2,1%,1/16W,CHIP,G2A]
    1  IRQ_PVDDQ_DEF_VRHOT_LVT3_R_N      A  @BASEBOARD_FAB2_LIB.BASEBOARD_FAB2(SCH_1):IRQ_PVDDQ_DEF_VRHOT_LVT3_R_N
    2  IRQ_PVDDQ_DEF_VRHOT_LVT3_N      B  @BASEBOARD_FAB2_LIB.BASEBOARD_FAB2(SCH_1):IRQ_PVDDQ_DEF_VRHOT_LVT3_N

RES  I24  R7B2   [RES_0402-20.0,1%,1/16W,CHIP,G2A]
    2  SMB_VR_STBY_LVC3_SDA      B  @BASEBOARD_FAB2_LIB.BASEBOARD_FAB2(SCH_1):SMB_VR_STBY_LVC3_SDA
    1  SMB_VR_SDA_VDDQ_DEF      A  @BASEBOARD_FAB2_LIB.BASEBOARD_FAB2(SCH_1):SMB_VR_SDA_VDDQ_DEF

RES  I21  R7B3   [RES_0402-20.0,1%,1/16W,CHIP,G2A]
    2  SMB_VR_STBY_LVC3_SCL      B  @BASEBOARD_FAB2_LIB.BASEBOARD_FAB2(SCH_1):SMB_VR_STBY_LVC3_SCL
    1  SMB_VR_SCL_VDDQ_DEF      A  @BASEBOARD_FAB2_LIB.BASEBOARD_FAB2(SCH_1):SMB_VR_SCL_VDDQ_DEF

RES  I17  R7B4   [RES_0402-1.00K,1%,1/16W,CHIP,GA]
    1  P3V3_STBY          A  @BASEBOARD_FAB2_LIB.BASEBOARD_FAB2(SCH_1):P3V3_STBY
    2  IRQ_PVDDQ_DEF_VRHOT_LVT3_R_N      B  @BASEBOARD_FAB2_LIB.BASEBOARD_FAB2(SCH_1):IRQ_PVDDQ_DEF_VRHOT_LVT3_R_N

RES  I16  R7B5   [RES_0402-1.00K,1%,1/16W,CHIP,GA]
    2  PWRGD_PVDDQ_DEF_R      B  @BASEBOARD_FAB2_LIB.BASEBOARD_FAB2(SCH_1):PWRGD_PVDDQ_DEF_R
    1  P3V3_STBY          A  @BASEBOARD_FAB2_LIB.BASEBOARD_FAB2(SCH_1):P3V3_STBY

RES  I295  R7B6   [RES_0402-10.0K,1%,1/16W,CHIP,GA]
    1  P3V3_STBY          A  @BASEBOARD_FAB2_LIB.BASEBOARD_FAB2(SCH_1):P3V3_STBY
    2  FM_PCH_PRSNT_N      B  @BASEBOARD_FAB2_LIB.BASEBOARD_FAB2(SCH_1):FM_PCH_PRSNT_N

RES  I230  R7B7   [RES_0402-10.0K,1%,1/16W,EMPTY,A]
    2  GND                B  @BASEBOARD_FAB2_LIB.BASEBOARD_FAB2(SCH_1):GND
    1  A_EXTCLKP          A  @BASEBOARD_FAB2_LIB.BASEBOARD_FAB2(SCH_1):A_EXTCLKP

RES  I229  R7B8   [RES_0402-10.0K,1%,1/16W,EMPTY,A]
    2  GND                B  @BASEBOARD_FAB2_LIB.BASEBOARD_FAB2(SCH_1):GND
    1  A_EXTCLKN          A  @BASEBOARD_FAB2_LIB.BASEBOARD_FAB2(SCH_1):A_EXTCLKN

RES  I307  R7B9   [RES_0402-0.0,5%,1/16W,CHIP,G21A]
    2  FM_PVPP_PVDDQ_CPU0_EN_DEF      B  @BASEBOARD_FAB2_LIB.BASEBOARD_FAB2(SCH_1):FM_PVPP_PVDDQ_CPU0_EN_DEF
    1  FM_PVPP_CPU0_EN      A  @BASEBOARD_FAB2_LIB.BASEBOARD_FAB2(SCH_1):FM_PVPP_CPU0_EN

RES  I227  R7B10  [RES_0603-120.0,1%,1/10W,CHIP,GA]
    1  PVPP_DEF           A  @BASEBOARD_FAB2_LIB.BASEBOARD_FAB2(SCH_1):PVPP_DEF
    2  GND                B  @BASEBOARD_FAB2_LIB.BASEBOARD_FAB2(SCH_1):GND

RES  I299  R7B11  [RES_0402-0.0,5%,1/16W,CHIP,G21A]
    2  VSENSE_PVPP_DEF      B  @BASEBOARD_FAB2_LIB.BASEBOARD_FAB2(SCH_1):VSENSE_PVPP_DEF
    1  PVPP_DEF           A  @BASEBOARD_FAB2_LIB.BASEBOARD_FAB2(SCH_1):PVPP_DEF

RES  I257  R7B12  [RES_0402-22.1,1.0%,1/16W,CHIP,A]
    1  PWRGD_PVPP_DEF_R      A  @BASEBOARD_FAB2_LIB.BASEBOARD_FAB2(SCH_1):PWRGD_PVPP_DEF_R
    2  PWRGD_PVPP_DEF      B  @BASEBOARD_FAB2_LIB.BASEBOARD_FAB2(SCH_1):PWRGD_PVPP_DEF

RES  I304  R7B13  [RES_0402-6.34K,1%,1/16W,CHIP,GA]
    1  VR_FB_PVPP_DEF      A  @BASEBOARD_FAB2_LIB.BASEBOARD_FAB2(SCH_1):VR_FB_PVPP_DEF
    2  AGND_PVPP_DEF      B  @BASEBOARD_FAB2_LIB.BASEBOARD_FAB2(SCH_1):AGND_PVPP_DEF

RES  I193  R7B14  [RES_0402-7.87K,1.0%,1/16W,CHIPA]
    1  VR_PVPP_DEF_ISET      A  @BASEBOARD_FAB2_LIB.BASEBOARD_FAB2(SCH_1):VR_PVPP_DEF_ISET
    2  AGND_PVPP_DEF      B  @BASEBOARD_FAB2_LIB.BASEBOARD_FAB2(SCH_1):AGND_PVPP_DEF

RES  I303  R7B15  [RES_0402-20.0K,1%,1/16W,CHIP,GA]
    1  VSENSE_PVPP_DEF      A  @BASEBOARD_FAB2_LIB.BASEBOARD_FAB2(SCH_1):VSENSE_PVPP_DEF
    2  VR_FB_PVPP_DEF      B  @BASEBOARD_FAB2_LIB.BASEBOARD_FAB2(SCH_1):VR_FB_PVPP_DEF

RES  I300  R7B16  [RES_0402-7.87K,1.0%,1/16W,CHIPA]
    2  VR_FB_PVPP_DEF      B  @BASEBOARD_FAB2_LIB.BASEBOARD_FAB2(SCH_1):VR_FB_PVPP_DEF
    1  VR_COMP_RC_PVPP_DEF      A  @BASEBOARD_FAB2_LIB.BASEBOARD_FAB2(SCH_1):VR_COMP_RC_PVPP_DEF

RES  I210  R7B17  [RES_0402-1.00K,1%,1/16W,CHIP,GA]
    2  PWRGD_PVPP_DEF_R      B  @BASEBOARD_FAB2_LIB.BASEBOARD_FAB2(SCH_1):PWRGD_PVPP_DEF_R
    1  P3V3_STBY          A  @BASEBOARD_FAB2_LIB.BASEBOARD_FAB2(SCH_1):P3V3_STBY

RES  I298  R7B18  [RES_0402-1.0K,0.1%,1/16W,CHIP,A]
    1  VSENSE_PVPP_DEF      A  @BASEBOARD_FAB2_LIB.BASEBOARD_FAB2(SCH_1):VSENSE_PVPP_DEF
    2  VR_COMP_PVPP_DEF      B  @BASEBOARD_FAB2_LIB.BASEBOARD_FAB2(SCH_1):VR_COMP_PVPP_DEF

RES  I240  R7B19  [RES_0402-0.0,5%,1/16W,CHIP,G21A]
    2  VR_PVPP_DEF_BOOT_R      B  @BASEBOARD_FAB2_LIB.BASEBOARD_FAB2(SCH_1):VR_PVPP_DEF_BOOT_R
    1  VR_PVPP_DEF_BOOT      A  @BASEBOARD_FAB2_LIB.BASEBOARD_FAB2(SCH_1):VR_PVPP_DEF_BOOT

RES  I150  R7B20  [RES_0402-0.0,5%,1/16W,CHIP,G21A]
    1  GND                A  @BASEBOARD_FAB2_LIB.BASEBOARD_FAB2(SCH_1):GND
    2  AGND_PVPP_DEF      B  @BASEBOARD_FAB2_LIB.BASEBOARD_FAB2(SCH_1):AGND_PVPP_DEF

RES  I48  R7C1   [RES_0603-200K,0.1%,1/10W,CHIP,A]
    2  XTAL_PCH_48M_OUT      B  @BASEBOARD_FAB2_LIB.BASEBOARD_FAB2(SCH_1):XTAL_PCH_48M_OUT
    1  XTAL_PCH_48M_IN      A  @BASEBOARD_FAB2_LIB.BASEBOARD_FAB2(SCH_1):XTAL_PCH_48M_IN

RES  I141  R7C2   [RES_0402-0.0,5%,1/16W,EMPTY,G2A]
    1  CLK_100M_BMC_PE_R_DN      A  @BASEBOARD_FAB2_LIB.BASEBOARD_FAB2(SCH_1):CLK_100M_BMC_PE_R_DN
    2  CLK_100M_BMC_PE_DN      B  @BASEBOARD_FAB2_LIB.BASEBOARD_FAB2(SCH_1):CLK_100M_BMC_PE_DN

RES  I78  R7C3   [RES_0402-51.1,1.0%,1/16W,CHIP,A]
    1  PVCCIO_CPU0        A  @BASEBOARD_FAB2_LIB.BASEBOARD_FAB2(SCH_1):PVCCIO_CPU0
    2  GND                B  @BASEBOARD_FAB2_LIB.BASEBOARD_FAB2(SCH_1):GND

RES  I142  R7C4   [RES_0402-0.0,5%,1/16W,EMPTY,G2A]
    1  CLK_100M_BMC_PE_R_DP      A  @BASEBOARD_FAB2_LIB.BASEBOARD_FAB2(SCH_1):CLK_100M_BMC_PE_R_DP
    2  CLK_100M_BMC_PE_DP      B  @BASEBOARD_FAB2_LIB.BASEBOARD_FAB2(SCH_1):CLK_100M_BMC_PE_DP

RES  I297  R7C5   [RES_0402-10.0K,1%,1/16W,CHIP,GA]
    1  P3V3_STBY          A  @BASEBOARD_FAB2_LIB.BASEBOARD_FAB2(SCH_1):P3V3_STBY
    2  FM_SINT_PRSNT_N      B  @BASEBOARD_FAB2_LIB.BASEBOARD_FAB2(SCH_1):FM_SINT_PRSNT_N

RES  I54  R7C6   [RES_0603-10M,1.0%,1/10W,CHIP,GA]
    2  XTAL_33K_RTC2      B  @BASEBOARD_FAB2_LIB.BASEBOARD_FAB2(SCH_1):XTAL_33K_RTC2
    1  XTAL_33K_RTC1      A  @BASEBOARD_FAB2_LIB.BASEBOARD_FAB2(SCH_1):XTAL_33K_RTC1

RES  I296  R7C8   [RES_0402-10.0K,1%,1/16W,CHIP,GA]
    1  P3V3_STBY          A  @BASEBOARD_FAB2_LIB.BASEBOARD_FAB2(SCH_1):P3V3_STBY
    2  FM_WBG_PRSNT_N      B  @BASEBOARD_FAB2_LIB.BASEBOARD_FAB2(SCH_1):FM_WBG_PRSNT_N

RES  I13  R7C10  [RES_0402-20.0K,1%,1/16W,CHIP,GA]
    2  RST_RTCRST_N       B  @BASEBOARD_FAB2_LIB.BASEBOARD_FAB2(SCH_1):RST_RTCRST_N
    1  P3V3_RTC_STBY      A  @BASEBOARD_FAB2_LIB.BASEBOARD_FAB2(SCH_1):P3V3_RTC_STBY

RES  I11  R7C11  [RES_0402-1.0M,1%,1/16W,EMPTY,GA]
    2  RST_RTCRST_N       B  @BASEBOARD_FAB2_LIB.BASEBOARD_FAB2(SCH_1):RST_RTCRST_N
    1  GND                A  @BASEBOARD_FAB2_LIB.BASEBOARD_FAB2(SCH_1):GND

RES  I67  R7C13  [RES_0402-10.0K,1%,1/16W,CHIP,GA]
    1  P3V3_STBY          A  @BASEBOARD_FAB2_LIB.BASEBOARD_FAB2(SCH_1):P3V3_STBY
    2  FM_UART_PRES_N      B  @BASEBOARD_FAB2_LIB.BASEBOARD_FAB2(SCH_1):FM_UART_PRES_N

RES  I98  R7C14  [RES_0402-33.2,1%,1/16W,CHIP,G2A]
    2  RMII_BMC_PCH_SPRNGVLLE_RXER_R      B  @BASEBOARD_FAB2_LIB.BASEBOARD_FAB2(SCH_1):RMII_BMC_PCH_SPRNGVLLE_RXER_R
    1  RMII_BMC_PCH_SPRNGVLLE_RXER      A  @BASEBOARD_FAB2_LIB.BASEBOARD_FAB2(SCH_1):RMII_BMC_PCH_SPRNGVLLE_RXER

RES  I31  R7C15  [RES_0402-0.0,5%,1/16W,CHIP,G21A]
    1  SPI_PCH_MOSI_R      A  @BASEBOARD_FAB2_LIB.BASEBOARD_FAB2(SCH_1):SPI_PCH_MOSI_R
    2  SPI_PCH_MOSI       B  @BASEBOARD_FAB2_LIB.BASEBOARD_FAB2(SCH_1):SPI_PCH_MOSI

RES  I33  R7C16  [RES_0402-33.2,1%,1/16W,CHIP,G2A]
    1  SPI_PCH_CS0_R_N      A  @BASEBOARD_FAB2_LIB.BASEBOARD_FAB2(SCH_1):SPI_PCH_CS0_R_N
    2  SPI_PCH_CS0_N      B  @BASEBOARD_FAB2_LIB.BASEBOARD_FAB2(SCH_1):SPI_PCH_CS0_N

RES  I28  R7C17  [RES_0402-4.75K,1%,1/16W,CHIP,GA]
    1  PVCCIO_CPU0        A  @BASEBOARD_FAB2_LIB.BASEBOARD_FAB2(SCH_1):PVCCIO_CPU0
    2  PECI_BMC           B  @BASEBOARD_FAB2_LIB.BASEBOARD_FAB2(SCH_1):PECI_BMC

RES  I11  R7C18  [RES_0402-0.0,5%,1/16W,EMPTY,G2A]
    2  PECI_CPU_G         B  @BASEBOARD_FAB2_LIB.BASEBOARD_FAB2(SCH_1):PECI_CPU_G
    1  PECI_BMC           A  @BASEBOARD_FAB2_LIB.BASEBOARD_FAB2(SCH_1):PECI_BMC

RES  I15  R7C19  [RES_0402-0.0,5%,1/16W,CHIP,G21A]
    1  PECI_PCH           A  @BASEBOARD_FAB2_LIB.BASEBOARD_FAB2(SCH_1):PECI_PCH
    2  PECI_CPU_G         B  @BASEBOARD_FAB2_LIB.BASEBOARD_FAB2(SCH_1):PECI_CPU_G

RES  I73  R7C20  [RES_0402-10.0K,1%,1/16W,CHIP,GA]
    2  GND                B  @BASEBOARD_FAB2_LIB.BASEBOARD_FAB2(SCH_1):GND
    1  CLK_50M_CKMNG_PCH_10GBE      A  @BASEBOARD_FAB2_LIB.BASEBOARD_FAB2(SCH_1):CLK_50M_CKMNG_PCH_10GBE

RES  I9   R7C21  [RES_0402-10.0K,1%,1/16W,CHIP,GA]
    1  P1V05_PCH_STBY      A  @BASEBOARD_FAB2_LIB.BASEBOARD_FAB2(SCH_1):P1V05_PCH_STBY
    2  FM_PCH_LVC1_THERMTRIP_N      B  @BASEBOARD_FAB2_LIB.BASEBOARD_FAB2(SCH_1):FM_PCH_LVC1_THERMTRIP_N

RES  I14  R7C22  [RES_0402-4.75K,1%,1/16W,EMPTY,A]
    1  PVCCIO_CPU0        A  @BASEBOARD_FAB2_LIB.BASEBOARD_FAB2(SCH_1):PVCCIO_CPU0
    2  PECI_PCH           B  @BASEBOARD_FAB2_LIB.BASEBOARD_FAB2(SCH_1):PECI_PCH

RES  I144  R7C23  [RES_0402-10.0K,1%,1/16W,CHIP,GA]
    2  XDP_PCH_PWR_DEBUG_N      B  @BASEBOARD_FAB2_LIB.BASEBOARD_FAB2(SCH_1):XDP_PCH_PWR_DEBUG_N
    1  P3V3_STBY          A  @BASEBOARD_FAB2_LIB.BASEBOARD_FAB2(SCH_1):P3V3_STBY

RES  I155  R7C24  [RES_0402-4.02K,1%,1/16W,CHIP,GA]
    1  VR_PVCCMCP_CPU0_XADDR2      A  @BASEBOARD_FAB2_LIB.BASEBOARD_FAB2(SCH_1):VR_PVCCMCP_CPU0_XADDR2
    2  GND                B  @BASEBOARD_FAB2_LIB.BASEBOARD_FAB2(SCH_1):GND

RES  I103  R7C25  [RES_0402-68.1K,1%,1/16W,EMPTY,A]
    1  VR_PVCCIO_CPU0_OCSET      A  @BASEBOARD_FAB2_LIB.BASEBOARD_FAB2(SCH_1):VR_PVCCIO_CPU0_OCSET
    2  GND                B  @BASEBOARD_FAB2_LIB.BASEBOARD_FAB2(SCH_1):GND

RES  I189  R7C26  [RES_0402-33.2,1%,1/16W,CHIP,G2A]
    2  CLK_24M_BMC_LPC_R      B  @BASEBOARD_FAB2_LIB.BASEBOARD_FAB2(SCH_1):CLK_24M_BMC_LPC_R
    1  CLK_24M_BMC_LPC      A  @BASEBOARD_FAB2_LIB.BASEBOARD_FAB2(SCH_1):CLK_24M_BMC_LPC

RES  I70  R7D1   [RES_0402-1.00K,1%,1/16W,CHIP,GA]
    1  RMII_PCH_SPRNGVLLE_ARB_OUT      A  @BASEBOARD_FAB2_LIB.BASEBOARD_FAB2(SCH_1):RMII_PCH_SPRNGVLLE_ARB_OUT
    2  GND                B  @BASEBOARD_FAB2_LIB.BASEBOARD_FAB2(SCH_1):GND

RES  I332  R7D2   [RES_0402-1.00K,1%,1/16W,CHIP,GA]
    2  PU_FM_RCIN_N       B  @BASEBOARD_FAB2_LIB.BASEBOARD_FAB2(SCH_1):PU_FM_RCIN_N
    1  P3V3_STBY          A  @BASEBOARD_FAB2_LIB.BASEBOARD_FAB2(SCH_1):P3V3_STBY

RES  I243  R7D3   [RES_0402-4.75K,1%,1/16W,CHIP,GA]
    1  P3V3_STBY          A  @BASEBOARD_FAB2_LIB.BASEBOARD_FAB2(SCH_1):P3V3_STBY
    2  IRQ_LPC_SERIRQ_N      B  @BASEBOARD_FAB2_LIB.BASEBOARD_FAB2(SCH_1):IRQ_LPC_SERIRQ_N

RES  I245  R7D4   [RES_0402-10.0K,1%,1/16W,CHIP,GA]
    2  PU_IRQ_PCH_SCI_WHEA_N      B  @BASEBOARD_FAB2_LIB.BASEBOARD_FAB2(SCH_1):PU_IRQ_PCH_SCI_WHEA_N
    1  P3V3_STBY          A  @BASEBOARD_FAB2_LIB.BASEBOARD_FAB2(SCH_1):P3V3_STBY

RES  I199  R7D5   [RES_0402-2.26K,1.0%,1/16W,CHIPA]
    1  P3V3_STBY          A  @BASEBOARD_FAB2_LIB.BASEBOARD_FAB2(SCH_1):P3V3_STBY
    2  FM_MB_SLOT_ID0      B  @BASEBOARD_FAB2_LIB.BASEBOARD_FAB2(SCH_1):FM_MB_SLOT_ID0

RES  I306  R7D6   [RES_0402-4.75K,1%,1/16W,CHIP,GA]
    1  P3V3_STBY          A  @BASEBOARD_FAB2_LIB.BASEBOARD_FAB2(SCH_1):P3V3_STBY
    2  FM_BMC_READY_N      B  @BASEBOARD_FAB2_LIB.BASEBOARD_FAB2(SCH_1):FM_BMC_READY_N

RES  I331  R7D7   [RES_0402-1.00K,1%,1/16W,CHIP,GA]
    1  P3V3_STBY          A  @BASEBOARD_FAB2_LIB.BASEBOARD_FAB2(SCH_1):P3V3_STBY
    2  IRQ_PIRQA_SPI_TPM_N      B  @BASEBOARD_FAB2_LIB.BASEBOARD_FAB2(SCH_1):IRQ_PIRQA_SPI_TPM_N

RES  I200  R7D8   [RES_0402-10.0K,1%,1/16W,CHIP,GA]
    2  PU_LPC_CLKRUN_N      B  @BASEBOARD_FAB2_LIB.BASEBOARD_FAB2(SCH_1):PU_LPC_CLKRUN_N
    1  P3V3_STBY          A  @BASEBOARD_FAB2_LIB.BASEBOARD_FAB2(SCH_1):P3V3_STBY

RES  I200  R7D9   [RES_0402-2.26K,1.0%,1/16W,CHIPA]
    1  P3V3_STBY          A  @BASEBOARD_FAB2_LIB.BASEBOARD_FAB2(SCH_1):P3V3_STBY
    2  FM_MB_SLOT_ID1      B  @BASEBOARD_FAB2_LIB.BASEBOARD_FAB2(SCH_1):FM_MB_SLOT_ID1

RES  I202  R7D10  [RES_0402-10.0K,1%,1/16W,CHIP,GA]
    2  PU_LPC_PME_N       B  @BASEBOARD_FAB2_LIB.BASEBOARD_FAB2(SCH_1):PU_LPC_PME_N
    1  P3V3_STBY          A  @BASEBOARD_FAB2_LIB.BASEBOARD_FAB2(SCH_1):P3V3_STBY

RES  I237  R7D12  [RES_0402-10.0K,1%,1/16W,CHIP,GA]
    1  P3V3_STBY          A  @BASEBOARD_FAB2_LIB.BASEBOARD_FAB2(SCH_1):P3V3_STBY
    2  FM_OCP_MEZZA_PRES_N      B  @BASEBOARD_FAB2_LIB.BASEBOARD_FAB2(SCH_1):FM_OCP_MEZZA_PRES_N

RES  I60  R7D13  [RES_0402-8.2K,1%,1/16W,EMPTY,GA]
    2  RMII_BMC_PCH_SPRNGVLLE_RXER      B  @BASEBOARD_FAB2_LIB.BASEBOARD_FAB2(SCH_1):RMII_BMC_PCH_SPRNGVLLE_RXER
    1  P3V3_STBY          A  @BASEBOARD_FAB2_LIB.BASEBOARD_FAB2(SCH_1):P3V3_STBY

RES  I32  R7D15  [RES_0402-348,1%,1/16W,CHIP,G21A]
    1  PECI_CPU_G         A  @BASEBOARD_FAB2_LIB.BASEBOARD_FAB2(SCH_1):PECI_CPU_G
    2  GND                B  @BASEBOARD_FAB2_LIB.BASEBOARD_FAB2(SCH_1):GND

RES  I11  R7D18  [RES_0402-1.00K,1%,1/16W,CHIP,GA]
    2  FM_THERMTRIP_DLY_R      B  @BASEBOARD_FAB2_LIB.BASEBOARD_FAB2(SCH_1):FM_THERMTRIP_DLY_R
    1  FM_THERMTRIP_DLY      A  @BASEBOARD_FAB2_LIB.BASEBOARD_FAB2(SCH_1):FM_THERMTRIP_DLY

RES  I6   R7D19  [RES_0402-1.00K,1%,1/16W,EMPTY,A]
    2  GND                B  @BASEBOARD_FAB2_LIB.BASEBOARD_FAB2(SCH_1):GND
    1  FM_OC_DETECT_EN_N      A  @BASEBOARD_FAB2_LIB.BASEBOARD_FAB2(SCH_1):FM_OC_DETECT_EN_N

RES  I131  R7D23  [RES_0402-0.0,5%,1/16W,CHIP,G21A]
    2  RST_BMC_SRST_R_N      B  @BASEBOARD_FAB2_LIB.BASEBOARD_FAB2(SCH_1):RST_BMC_SRST_R_N
    1  RST_BMC_SRST_N      A  @BASEBOARD_FAB2_LIB.BASEBOARD_FAB2(SCH_1):RST_BMC_SRST_N

RES  I62  R7D24  [RES_0402-33.2,1%,1/16W,CHIP,G2A]
    2  FM_CPU1_PROCHOT_LVT3_N      B  @BASEBOARD_FAB2_LIB.BASEBOARD_FAB2(SCH_1):FM_CPU1_PROCHOT_LVT3_N
    1  FM_CPU1_PROCHOT_LVT3_K_N      A  @BASEBOARD_FAB2_LIB.BASEBOARD_FAB2(SCH_1):FM_CPU1_PROCHOT_LVT3_K_N

RES  I70  R7D25  [RES_0402-33.2,1%,1/16W,CHIP,G2A]
    1  FM_CPU_MSMI_LVT3_R_N      A  @BASEBOARD_FAB2_LIB.BASEBOARD_FAB2(SCH_1):FM_CPU_MSMI_LVT3_R_N
    2  FM_CPU_MSMI_LVT3_N      B  @BASEBOARD_FAB2_LIB.BASEBOARD_FAB2(SCH_1):FM_CPU_MSMI_LVT3_N

RES  I54  R7D26  [RES_0402-1.00K,1%,1/16W,CHIP,GA]
    1  PD_GTL2104_DIR_0      A  @BASEBOARD_FAB2_LIB.BASEBOARD_FAB2(SCH_1):PD_GTL2104_DIR_0
    2  GND                B  @BASEBOARD_FAB2_LIB.BASEBOARD_FAB2(SCH_1):GND

RES  I68  R7D27  [RES_0402-0.0,5%,1/16W,CHIP,G21A]
    2  H_CPU_MSMI_G_N      B  @BASEBOARD_FAB2_LIB.BASEBOARD_FAB2(SCH_1):H_CPU_MSMI_G_N
    1  H_CPU0_MSMI_G_N      A  @BASEBOARD_FAB2_LIB.BASEBOARD_FAB2(SCH_1):H_CPU0_MSMI_G_N

RES  I67  R7D28  [RES_0402-0.0,5%,1/16W,CHIP,G21A]
    2  H_CPU_MSMI_G_N      B  @BASEBOARD_FAB2_LIB.BASEBOARD_FAB2(SCH_1):H_CPU_MSMI_G_N
    1  H_CPU1_MSMI_G_N      A  @BASEBOARD_FAB2_LIB.BASEBOARD_FAB2(SCH_1):H_CPU1_MSMI_G_N

RES  I30  R7D29  [RES_0402-33.2,1%,1/16W,CHIP,G2A]
    1  FM_CPU0_FIVR_FAULT_R_LVT3      A  @BASEBOARD_FAB2_LIB.BASEBOARD_FAB2(SCH_1):FM_CPU0_FIVR_FAULT_R_LVT3
    2  FM_CPU0_FIVR_FAULT_LVT3      B  @BASEBOARD_FAB2_LIB.BASEBOARD_FAB2(SCH_1):FM_CPU0_FIVR_FAULT_LVT3

RES  I121  R7D30  [RES_0402-4.75K,1%,1/16W,CHIP,GA]
    1  P3V3_STBY          A  @BASEBOARD_FAB2_LIB.BASEBOARD_FAB2(SCH_1):P3V3_STBY
    2  FM_CPLD_UART_CH_LOCK_N      B  @BASEBOARD_FAB2_LIB.BASEBOARD_FAB2(SCH_1):FM_CPLD_UART_CH_LOCK_N

RES  I29  R7D31  [RES_0402-33.2,1%,1/16W,CHIP,G2A]
    1  FM_CPU_ERR2_LVT3_R_N      A  @BASEBOARD_FAB2_LIB.BASEBOARD_FAB2(SCH_1):FM_CPU_ERR2_LVT3_R_N
    2  FM_CPU_ERR2_LVT3_N      B  @BASEBOARD_FAB2_LIB.BASEBOARD_FAB2(SCH_1):FM_CPU_ERR2_LVT3_N

RES  I48  R7D32  [RES_0402-100.0,1%,1/16W,CHIP,GA]
    1  P0V7_GTL2104_VREF_0      A  @BASEBOARD_FAB2_LIB.BASEBOARD_FAB2(SCH_1):P0V7_GTL2104_VREF_0
    2  GND                B  @BASEBOARD_FAB2_LIB.BASEBOARD_FAB2(SCH_1):GND

RES  I51  R7D33  [RES_0402-49.9,1%,1/16W,CHIP,G2A]
    1  PVCCIO_CPU0        A  @BASEBOARD_FAB2_LIB.BASEBOARD_FAB2(SCH_1):PVCCIO_CPU0
    2  P0V7_GTL2104_VREF_0      B  @BASEBOARD_FAB2_LIB.BASEBOARD_FAB2(SCH_1):P0V7_GTL2104_VREF_0

RES  I24  R7D34  [RES_0402-33.2,1%,1/16W,CHIP,G2A]
    1  FM_CPU0_THERMTRIP_LVT3_R_N      A  @BASEBOARD_FAB2_LIB.BASEBOARD_FAB2(SCH_1):FM_CPU0_THERMTRIP_LVT3_R_N
    2  FM_CPU0_THERMTRIP_LVT3_N      B  @BASEBOARD_FAB2_LIB.BASEBOARD_FAB2(SCH_1):FM_CPU0_THERMTRIP_LVT3_N

RES  I96  R7D36  [RES_0402-0.0,5%,1/16W,CHIP,G21A]
    2  FM_CPU1_STL_BRD_OSC_EN      B  @BASEBOARD_FAB2_LIB.BASEBOARD_FAB2(SCH_1):FM_CPU1_STL_BRD_OSC_EN
    1  FM_156M_CPU1_BRD_OSC_EN      A  @BASEBOARD_FAB2_LIB.BASEBOARD_FAB2(SCH_1):FM_156M_CPU1_BRD_OSC_EN

RES  I98  R7D37  [RES_0402-0.0,5%,1/16W,EMPTY,G2A]
    1  FM_CPU1_VRM_OSC_EN      A  @BASEBOARD_FAB2_LIB.BASEBOARD_FAB2(SCH_1):FM_CPU1_VRM_OSC_EN
    2  FM_CPU1_VRM_322M_156M_OSC_EN      B  @BASEBOARD_FAB2_LIB.BASEBOARD_FAB2(SCH_1):FM_CPU1_VRM_322M_156M_OSC_EN

RES  I97  R7D38  [RES_0402-0.0,5%,1/16W,EMPTY,G2A]
    1  FM_CPU1_VRM_OSC_EN      A  @BASEBOARD_FAB2_LIB.BASEBOARD_FAB2(SCH_1):FM_CPU1_VRM_OSC_EN
    2  FM_CPU1_STL_BRD_OSC_EN      B  @BASEBOARD_FAB2_LIB.BASEBOARD_FAB2(SCH_1):FM_CPU1_STL_BRD_OSC_EN

RES  I95  R7D39  [RES_0402-0.0,5%,1/16W,EMPTY,G2A]
    1  FM_CPU0_VRM_OSC_EN      A  @BASEBOARD_FAB2_LIB.BASEBOARD_FAB2(SCH_1):FM_CPU0_VRM_OSC_EN
    2  FM_CPU0_VRM_322M_156M_OSC_EN      B  @BASEBOARD_FAB2_LIB.BASEBOARD_FAB2(SCH_1):FM_CPU0_VRM_322M_156M_OSC_EN

RES  I94  R7D40  [RES_0402-0.0,5%,1/16W,EMPTY,G2A]
    1  FM_CPU0_VRM_OSC_EN      A  @BASEBOARD_FAB2_LIB.BASEBOARD_FAB2(SCH_1):FM_CPU0_VRM_OSC_EN
    2  FM_CPU0_STL_BRD_OSC_EN      B  @BASEBOARD_FAB2_LIB.BASEBOARD_FAB2(SCH_1):FM_CPU0_STL_BRD_OSC_EN

RES  I114  R7D41  [RES_0402-0.0,5%,1/16W,CHIP,G21A]
    1  FM_CPU1_PROCHOT_LVT3_R_N      A  @BASEBOARD_FAB2_LIB.BASEBOARD_FAB2(SCH_1):FM_CPU1_PROCHOT_LVT3_R_N
    2  FM_CPU1_PROCHOT_LVT3_K_N      B  @BASEBOARD_FAB2_LIB.BASEBOARD_FAB2(SCH_1):FM_CPU1_PROCHOT_LVT3_K_N

RES  I193  R7D42  [RES_0402-4.75K,1%,1/16W,CHIP,GA]
    2  PU_FAB2_MARKER_CPLD      B  @BASEBOARD_FAB2_LIB.BASEBOARD_FAB2(SCH_1):PU_FAB2_MARKER_CPLD
    1  P3V3_STBY          A  @BASEBOARD_FAB2_LIB.BASEBOARD_FAB2(SCH_1):P3V3_STBY

RES  I110  R7D43  [RES_0402-0.0,5%,1/16W,EMPTY,G2A]
    2  H_CPU1_PROCHOT_G_PCH_N      B  @BASEBOARD_FAB2_LIB.BASEBOARD_FAB2(SCH_1):H_CPU1_PROCHOT_G_PCH_N
    1  FM_CPU1_PROCHOT_LVT3_K_N      A  @BASEBOARD_FAB2_LIB.BASEBOARD_FAB2(SCH_1):FM_CPU1_PROCHOT_LVT3_K_N

RES  I356  R7D44  [RES_0402-4.75K,1%,1/16W,CHIP,GA]
    1  P1V05_PCH_STBY      A  @BASEBOARD_FAB2_LIB.BASEBOARD_FAB2(SCH_1):P1V05_PCH_STBY
    2  FM_OCP_MEZZB_PRES_N      B  @BASEBOARD_FAB2_LIB.BASEBOARD_FAB2(SCH_1):FM_OCP_MEZZB_PRES_N

RES  I19  R7E2   [RES_0402-75,1.0%,1/16W,CHIP,G2A]
    1  PVCCIO_CPU0        A  @BASEBOARD_FAB2_LIB.BASEBOARD_FAB2(SCH_1):PVCCIO_CPU0
    2  H_CPU0_THERMTRIP_G_N      B  @BASEBOARD_FAB2_LIB.BASEBOARD_FAB2(SCH_1):H_CPU0_THERMTRIP_G_N

RES  I38  R7E5   [RES_0402-10.0K,1%,1/16W,CHIP,GA]
    2  PU_THERMTRIP_FORCE_N      B  @BASEBOARD_FAB2_LIB.BASEBOARD_FAB2(SCH_1):PU_THERMTRIP_FORCE_N
    1  P3V3_STBY          A  @BASEBOARD_FAB2_LIB.BASEBOARD_FAB2(SCH_1):P3V3_STBY

RES  I33  R7E6   [RES_0402-10.0K,1%,1/16W,CHIP,GA]
    2  PU_RST_PERST_BIT1      B  @BASEBOARD_FAB2_LIB.BASEBOARD_FAB2(SCH_1):PU_RST_PERST_BIT1
    1  P3V3_STBY          A  @BASEBOARD_FAB2_LIB.BASEBOARD_FAB2(SCH_1):P3V3_STBY

RES  I106  R7E7   [RES_0402-4.75K,1%,1/16W,CHIP,GA]
    1  P3V3               A  @BASEBOARD_FAB2_LIB.BASEBOARD_FAB2(SCH_1):P3V3
    2  FM_SYS_THROTTLE_LVC3      B  @BASEBOARD_FAB2_LIB.BASEBOARD_FAB2(SCH_1):FM_SYS_THROTTLE_LVC3

RES  I108  R7E9   [RES_0402-0.0,5%,1/16W,CHIP,G21A]
    2  FM_THROTTLE_R_N      B  @BASEBOARD_FAB2_LIB.BASEBOARD_FAB2(SCH_1):FM_THROTTLE_R_N
    1  FM_THROTTLE_N      A  @BASEBOARD_FAB2_LIB.BASEBOARD_FAB2(SCH_1):FM_THROTTLE_N

RES  I62  R7E10  [RES_0402-4.75K,1%,1/16W,CHIP,GA]
    1  P3V3               A  @BASEBOARD_FAB2_LIB.BASEBOARD_FAB2(SCH_1):P3V3
    2  IRQ_CPU0_VRHOT      B  @BASEBOARD_FAB2_LIB.BASEBOARD_FAB2(SCH_1):IRQ_CPU0_VRHOT

RES  I72  R7E11  [RES_0402-4.75K,1%,1/16W,CHIP,GA]
    1  P3V3               A  @BASEBOARD_FAB2_LIB.BASEBOARD_FAB2(SCH_1):P3V3
    2  IRQ_CPU1_VRHOT      B  @BASEBOARD_FAB2_LIB.BASEBOARD_FAB2(SCH_1):IRQ_CPU1_VRHOT

RES  I11  R7E12  [RES_0402-1.00K,1%,1/16W,CHIP,GA]
    2  PWRGD_P5V_STBY_R      B  @BASEBOARD_FAB2_LIB.BASEBOARD_FAB2(SCH_1):PWRGD_P5V_STBY_R
    1  P5V_STBY           A  @BASEBOARD_FAB2_LIB.BASEBOARD_FAB2(SCH_1):P5V_STBY

RES  I58  R7E13  [RES_0402-0.0,5%,1/16W,CHIP,G21A]
    1  GND                A  @BASEBOARD_FAB2_LIB.BASEBOARD_FAB2(SCH_1):GND
    2  AGND_P5V_STBY      B  @BASEBOARD_FAB2_LIB.BASEBOARD_FAB2(SCH_1):AGND_P5V_STBY

RES  I18  R7E14  [RES_0402-75K,1%,1/16W,CHIP,G21A]
    1  VR_P5V_STBY_RT      A  @BASEBOARD_FAB2_LIB.BASEBOARD_FAB2(SCH_1):VR_P5V_STBY_RT
    2  AGND_P5V_STBY      B  @BASEBOARD_FAB2_LIB.BASEBOARD_FAB2(SCH_1):AGND_P5V_STBY

RES  I89  R7E15  [RES_0402-22.1,1.0%,1/16W,CHIP,A]
    1  PWRGD_P5V_STBY_R      A  @BASEBOARD_FAB2_LIB.BASEBOARD_FAB2(SCH_1):PWRGD_P5V_STBY_R
    2  PWRGD_P5V_STBY      B  @BASEBOARD_FAB2_LIB.BASEBOARD_FAB2(SCH_1):PWRGD_P5V_STBY

RES  I51  R7E16  [RES_0402-1.37K,1%,1/16W,CHIP,GA]
    1  VR_P5V_STBY_VSENSE      A  @BASEBOARD_FAB2_LIB.BASEBOARD_FAB2(SCH_1):VR_P5V_STBY_VSENSE
    2  AGND_P5V_STBY      B  @BASEBOARD_FAB2_LIB.BASEBOARD_FAB2(SCH_1):AGND_P5V_STBY

RES  I37  R7E17  [RES_0402-0.0,5%,1/16W,CHIP,G21A]
    2  VR_P5V_STBY_VIN      B  @BASEBOARD_FAB2_LIB.BASEBOARD_FAB2(SCH_1):VR_P5V_STBY_VIN
    1  VR_FET_SW_P5V_STBY_PVIN      A  @BASEBOARD_FAB2_LIB.BASEBOARD_FAB2(SCH_1):VR_FET_SW_P5V_STBY_PVIN

RES  I55  R7E18  [RES_0402-4.75K,1%,1/16W,CHIP,GA]
    2  RST_RSMRST_N       B  @BASEBOARD_FAB2_LIB.BASEBOARD_FAB2(SCH_1):RST_RSMRST_N
    1  P3V3_STBY          A  @BASEBOARD_FAB2_LIB.BASEBOARD_FAB2(SCH_1):P3V3_STBY

RES  I57  R7E19  [RES_0402-1.00K,1%,1/16W,EMPTY,A]
    1  P3V3_STBY          A  @BASEBOARD_FAB2_LIB.BASEBOARD_FAB2(SCH_1):P3V3_STBY
    2  FM_MEM_EVENT_FUNC      B  @BASEBOARD_FAB2_LIB.BASEBOARD_FAB2(SCH_1):FM_MEM_EVENT_FUNC

RES  I59  R7E20  [RES_0402-1.00K,1%,1/16W,CHIP,GA]
    2  GND                B  @BASEBOARD_FAB2_LIB.BASEBOARD_FAB2(SCH_1):GND
    1  FM_MEM_EVENT_FUNC      A  @BASEBOARD_FAB2_LIB.BASEBOARD_FAB2(SCH_1):FM_MEM_EVENT_FUNC

RES  I343  R7E21  [RES_0402-4.75K,1%,1/16W,CHIP,GA]
    1  P3V3               A  @BASEBOARD_FAB2_LIB.BASEBOARD_FAB2(SCH_1):P3V3
    2  FM_PWRBRK_N        B  @BASEBOARD_FAB2_LIB.BASEBOARD_FAB2(SCH_1):FM_PWRBRK_N

RES  I341  R7E22  [RES_0402-0.0,5%,1/16W,CHIP,G21A]
    2  FM_PWRBRK_SLOT_N      B  @BASEBOARD_FAB2_LIB.BASEBOARD_FAB2(SCH_1):FM_PWRBRK_SLOT_N
    1  FM_PWRBRK_N        A  @BASEBOARD_FAB2_LIB.BASEBOARD_FAB2(SCH_1):FM_PWRBRK_N

RES  I50  R7F1   [RES_0402-10.0K,1%,1/16W,CHIP,GA]
    1  VR_P5V_STBY_VSENSE_R      A  @BASEBOARD_FAB2_LIB.BASEBOARD_FAB2(SCH_1):VR_P5V_STBY_VSENSE_R
    2  VR_P5V_STBY_VSENSE      B  @BASEBOARD_FAB2_LIB.BASEBOARD_FAB2(SCH_1):VR_P5V_STBY_VSENSE

RES  I109  R7F3   [RES_0402-33.2,1%,1/16W,CHIP,G2A]
    1  SPI_BIOS_SOCKET_IO3      A  @BASEBOARD_FAB2_LIB.BASEBOARD_FAB2(SCH_1):SPI_BIOS_SOCKET_IO3
    2  PU_BIOS_SPI_HOLD0_N      B  @BASEBOARD_FAB2_LIB.BASEBOARD_FAB2(SCH_1):PU_BIOS_SPI_HOLD0_N

RES  I98  R7F4   [RES_0402-33.2,1%,1/16W,CHIP,G2A]
    1  SPI_SWITCH_MISO      A  @BASEBOARD_FAB2_LIB.BASEBOARD_FAB2(SCH_1):SPI_SWITCH_MISO
    2  SPI_MISO_R0        B  @BASEBOARD_FAB2_LIB.BASEBOARD_FAB2(SCH_1):SPI_MISO_R0

RES  I94  R7F5   [RES_0402-4.75K,1%,1/16W,CHIP,GA]
    2  SPI_CS0_PRIMARY_R_N      B  @BASEBOARD_FAB2_LIB.BASEBOARD_FAB2(SCH_1):SPI_CS0_PRIMARY_R_N
    1  P3V3_STBY          A  @BASEBOARD_FAB2_LIB.BASEBOARD_FAB2(SCH_1):P3V3_STBY

RES  I90  R7F6   [RES_0402-4.75K,1%,1/16W,EMPTY,A]
    2  PU_SPI0_RST        B  @BASEBOARD_FAB2_LIB.BASEBOARD_FAB2(SCH_1):PU_SPI0_RST
    1  P3V3_STBY          A  @BASEBOARD_FAB2_LIB.BASEBOARD_FAB2(SCH_1):P3V3_STBY

RES  I174  R7F7   [RES_0402-2.2,5%,1/16W,EMPTY,G2A]
    1  VR_PVPP_ABC_SNUB      A  @BASEBOARD_FAB2_LIB.BASEBOARD_FAB2(SCH_1):VR_PVPP_ABC_SNUB
    2  GND                B  @BASEBOARD_FAB2_LIB.BASEBOARD_FAB2(SCH_1):GND

RES  I154  R7F8   [RES_0402-0.0,5%,1/16W,CHIP,G21A]
    2  VR_PVPP_ABC_BOOT_R      B  @BASEBOARD_FAB2_LIB.BASEBOARD_FAB2(SCH_1):VR_PVPP_ABC_BOOT_R
    1  VR_PVPP_ABC_BOOT      A  @BASEBOARD_FAB2_LIB.BASEBOARD_FAB2(SCH_1):VR_PVPP_ABC_BOOT

RES  I220  R7F9   [RES_0402-0.0,5%,1/16W,CHIP,G21A]
    2  FM_PVPP_PVDDQ_CPU0_EN_ABC      B  @BASEBOARD_FAB2_LIB.BASEBOARD_FAB2(SCH_1):FM_PVPP_PVDDQ_CPU0_EN_ABC
    1  FM_PVPP_CPU0_EN      A  @BASEBOARD_FAB2_LIB.BASEBOARD_FAB2(SCH_1):FM_PVPP_CPU0_EN

RES  I177  R7F10  [RES_0603-120.0,1%,1/10W,CHIP,GA]
    1  PVPP_ABC           A  @BASEBOARD_FAB2_LIB.BASEBOARD_FAB2(SCH_1):PVPP_ABC
    2  GND                B  @BASEBOARD_FAB2_LIB.BASEBOARD_FAB2(SCH_1):GND

RES  I166  R7F11  [RES_0402-6.34K,1%,1/16W,CHIP,GA]
    1  VR_FB_PVPP_ABC      A  @BASEBOARD_FAB2_LIB.BASEBOARD_FAB2(SCH_1):VR_FB_PVPP_ABC
    2  AGND_PVPP_ABC      B  @BASEBOARD_FAB2_LIB.BASEBOARD_FAB2(SCH_1):AGND_PVPP_ABC

RES  I168  R7F12  [RES_0402-0.0,5%,1/16W,CHIP,G21A]
    2  VSENSE_PVPP_ABC      B  @BASEBOARD_FAB2_LIB.BASEBOARD_FAB2(SCH_1):VSENSE_PVPP_ABC
    1  PVPP_ABC           A  @BASEBOARD_FAB2_LIB.BASEBOARD_FAB2(SCH_1):PVPP_ABC

RES  I167  R7F13  [RES_0402-20.0K,1%,1/16W,CHIP,GA]
    1  VSENSE_PVPP_ABC      A  @BASEBOARD_FAB2_LIB.BASEBOARD_FAB2(SCH_1):VSENSE_PVPP_ABC
    2  VR_FB_PVPP_ABC      B  @BASEBOARD_FAB2_LIB.BASEBOARD_FAB2(SCH_1):VR_FB_PVPP_ABC

RES  I136  R7F14  [RES_0402-10.0K,1%,1/16W,CHIP,GA]
    2  GND                B  @BASEBOARD_FAB2_LIB.BASEBOARD_FAB2(SCH_1):GND
    1  FM_PVPP_CPU0_EN      A  @BASEBOARD_FAB2_LIB.BASEBOARD_FAB2(SCH_1):FM_PVPP_CPU0_EN

RES  I134  R7F15  [RES_0402-7.87K,1.0%,1/16W,CHIPA]
    1  VR_PVPP_ABC_ISET      A  @BASEBOARD_FAB2_LIB.BASEBOARD_FAB2(SCH_1):VR_PVPP_ABC_ISET
    2  AGND_PVPP_ABC      B  @BASEBOARD_FAB2_LIB.BASEBOARD_FAB2(SCH_1):AGND_PVPP_ABC

RES  I208  R7F16  [RES_0402-22.1,1.0%,1/16W,CHIP,A]
    1  PWRGD_PVPP_ABC_R      A  @BASEBOARD_FAB2_LIB.BASEBOARD_FAB2(SCH_1):PWRGD_PVPP_ABC_R
    2  PWRGD_PVPP_ABC      B  @BASEBOARD_FAB2_LIB.BASEBOARD_FAB2(SCH_1):PWRGD_PVPP_ABC

RES  I218  R7F17  [RES_0402-1.0K,0.1%,1/16W,CHIP,A]
    1  VSENSE_PVPP_ABC      A  @BASEBOARD_FAB2_LIB.BASEBOARD_FAB2(SCH_1):VSENSE_PVPP_ABC
    2  VR_COMP_PVPP_ABC      B  @BASEBOARD_FAB2_LIB.BASEBOARD_FAB2(SCH_1):VR_COMP_PVPP_ABC

RES  I201  R7F18  [RES_0402-7.87K,1.0%,1/16W,CHIPA]
    2  VR_FB_PVPP_ABC      B  @BASEBOARD_FAB2_LIB.BASEBOARD_FAB2(SCH_1):VR_FB_PVPP_ABC
    1  VR_COMP_RC_PVPP_ABC      A  @BASEBOARD_FAB2_LIB.BASEBOARD_FAB2(SCH_1):VR_COMP_RC_PVPP_ABC

RES  I143  R7F19  [RES_0402-1.00K,1%,1/16W,CHIP,GA]
    2  PWRGD_PVPP_ABC_R      B  @BASEBOARD_FAB2_LIB.BASEBOARD_FAB2(SCH_1):PWRGD_PVPP_ABC_R
    1  P3V3_STBY          A  @BASEBOARD_FAB2_LIB.BASEBOARD_FAB2(SCH_1):P3V3_STBY

RES  I315  R7F20  [RES_0402-100.0K,1%,1/16W,EMPTYA]
    2  VR_PVDDQ_ABC_VREN      B  @BASEBOARD_FAB2_LIB.BASEBOARD_FAB2(SCH_1):VR_PVDDQ_ABC_VREN
    1  P3V3_STBY          A  @BASEBOARD_FAB2_LIB.BASEBOARD_FAB2(SCH_1):P3V3_STBY

RES  I343  R7F21  [RES_0402-0.0,5%,1/16W,CHIP,G21A]
    2  VR_PVDDQ_ABC_VREN      B  @BASEBOARD_FAB2_LIB.BASEBOARD_FAB2(SCH_1):VR_PVDDQ_ABC_VREN
    1  FM_PVDDQ_ABC_EN      A  @BASEBOARD_FAB2_LIB.BASEBOARD_FAB2(SCH_1):FM_PVDDQ_ABC_EN

RES  I301  R7F22  [RES_0402-1.00K,1%,1/16W,CHIP,GA]
    2  PWRGD_PVDDQ_ABC_R      B  @BASEBOARD_FAB2_LIB.BASEBOARD_FAB2(SCH_1):PWRGD_PVDDQ_ABC_R
    1  P3V3_STBY          A  @BASEBOARD_FAB2_LIB.BASEBOARD_FAB2(SCH_1):P3V3_STBY

RES  I297  R7F23  [RES_0402-33.2,1%,1/16W,CHIP,G2A]
    1  IRQ_PVDDQ_ABC_VRHOT_LVT3_R_N      A  @BASEBOARD_FAB2_LIB.BASEBOARD_FAB2(SCH_1):IRQ_PVDDQ_ABC_VRHOT_LVT3_R_N
    2  IRQ_PVDDQ_ABC_VRHOT_LVT3_N      B  @BASEBOARD_FAB2_LIB.BASEBOARD_FAB2(SCH_1):IRQ_PVDDQ_ABC_VRHOT_LVT3_N

RES  I296  R7F24  [RES_0402-22.1,1.0%,1/16W,CHIP,A]
    1  PWRGD_PVDDQ_ABC_R      A  @BASEBOARD_FAB2_LIB.BASEBOARD_FAB2(SCH_1):PWRGD_PVDDQ_ABC_R
    2  PWRGD_PVDDQ_ABC      B  @BASEBOARD_FAB2_LIB.BASEBOARD_FAB2(SCH_1):PWRGD_PVDDQ_ABC

RES  I298  R7F25  [RES_0402-20.0,1%,1/16W,CHIP,G2A]
    2  SMB_VR_STBY_LVC3_SCL      B  @BASEBOARD_FAB2_LIB.BASEBOARD_FAB2(SCH_1):SMB_VR_STBY_LVC3_SCL
    1  SMB_VR_SCL_VDDQ_ABC      A  @BASEBOARD_FAB2_LIB.BASEBOARD_FAB2(SCH_1):SMB_VR_SCL_VDDQ_ABC

RES  I304  R7F26  [RES_0402-20.0,1%,1/16W,CHIP,G2A]
    2  SMB_VR_STBY_LVC3_SDA      B  @BASEBOARD_FAB2_LIB.BASEBOARD_FAB2(SCH_1):SMB_VR_STBY_LVC3_SDA
    1  SMB_VR_SDA_VDDQ_ABC      A  @BASEBOARD_FAB2_LIB.BASEBOARD_FAB2(SCH_1):SMB_VR_SDA_VDDQ_ABC

RES  I303  R7F27  [RES_0402-1.00K,1%,1/16W,CHIP,GA]
    1  P3V3_STBY          A  @BASEBOARD_FAB2_LIB.BASEBOARD_FAB2(SCH_1):P3V3_STBY
    2  IRQ_PVDDQ_ABC_VRHOT_LVT3_R_N      B  @BASEBOARD_FAB2_LIB.BASEBOARD_FAB2(SCH_1):IRQ_PVDDQ_ABC_VRHOT_LVT3_R_N

RES  I168  R7F28  [RES_0402-10.0K,1%,1/16W,CHIP,GA]
    2  PU_BIOS_SPI_WP0_N      B  @BASEBOARD_FAB2_LIB.BASEBOARD_FAB2(SCH_1):PU_BIOS_SPI_WP0_N
    1  P3V3_STBY          A  @BASEBOARD_FAB2_LIB.BASEBOARD_FAB2(SCH_1):P3V3_STBY

RES  I181  R7F29  [RES_0402-33.2,1%,1/16W,CHIP,G2A]
    2  SPI_SWITCH_MOSI_R0      B  @BASEBOARD_FAB2_LIB.BASEBOARD_FAB2(SCH_1):SPI_SWITCH_MOSI_R0
    1  SPI_SWITCH_MOSI      A  @BASEBOARD_FAB2_LIB.BASEBOARD_FAB2(SCH_1):SPI_SWITCH_MOSI

RES  I170  R7F30  [RES_0402-10.0K,1%,1/16W,EMPTY,A]
    1  PU_BIOS_SPI_WP0_N      A  @BASEBOARD_FAB2_LIB.BASEBOARD_FAB2(SCH_1):PU_BIOS_SPI_WP0_N
    2  GND                B  @BASEBOARD_FAB2_LIB.BASEBOARD_FAB2(SCH_1):GND

RES  I140  R7F32  [RES_0402-10.0K,1%,1/16W,CHIP,GA]
    2  PU_BIOS_SPI_HOLD0_N      B  @BASEBOARD_FAB2_LIB.BASEBOARD_FAB2(SCH_1):PU_BIOS_SPI_HOLD0_N
    1  P3V3_STBY          A  @BASEBOARD_FAB2_LIB.BASEBOARD_FAB2(SCH_1):P3V3_STBY

RES  I65  R7F33  [RES_0402-4.75K,1%,1/16W,CHIP,GA]
    1  P5V_STBY           A  @BASEBOARD_FAB2_LIB.BASEBOARD_FAB2(SCH_1):P5V_STBY
    2  FAN_PWM_OUT_SYS1_R      B  @BASEBOARD_FAB2_LIB.BASEBOARD_FAB2(SCH_1):FAN_PWM_OUT_SYS1_R

RES  I336  R7F34  [RES_0402-100.0K,1%,1/16W,CHIP,B]
    2  VR_PVDDQ_ABC_VINSEN      B  @BASEBOARD_FAB2_LIB.BASEBOARD_FAB2(SCH_1):VR_PVDDQ_ABC_VINSEN
    1  VR_FET_SW_P12V_STBY_PVDDQ_ABC      A  @BASEBOARD_FAB2_LIB.BASEBOARD_FAB2(SCH_1):VR_FET_SW_P12V_STBY_PVDDQ_ABC

RES  I170  R7F35  [RES_0402-0.0,5%,1/16W,CHIP,G21A]
    1  GND                A  @BASEBOARD_FAB2_LIB.BASEBOARD_FAB2(SCH_1):GND
    2  AGND_PVPP_ABC      B  @BASEBOARD_FAB2_LIB.BASEBOARD_FAB2(SCH_1):AGND_PVPP_ABC

RES  I300  R7F36  [RES_0402-2.26K,1.0%,1/16W,EMPTA]
    2  PU_VR_PVDDQ_ABC_FAULT1      B  @BASEBOARD_FAB2_LIB.BASEBOARD_FAB2(SCH_1):PU_VR_PVDDQ_ABC_FAULT1
    1  P3V3_STBY          A  @BASEBOARD_FAB2_LIB.BASEBOARD_FAB2(SCH_1):P3V3_STBY

RES  I108  R7F37  [RES_0402-33.2,1%,1/16W,CHIP,G2A]
    1  SPI_BIOS_SOCKET_IO2      A  @BASEBOARD_FAB2_LIB.BASEBOARD_FAB2(SCH_1):SPI_BIOS_SOCKET_IO2
    2  PU_BIOS_SPI_WP0_N      B  @BASEBOARD_FAB2_LIB.BASEBOARD_FAB2(SCH_1):PU_BIOS_SPI_WP0_N

RES  I307  R7G2   [RES_0402-0.0,5%,1/16W,CHIP,G21A]
    1  SVID_VDIO_PVDDQ_ABC      A  @BASEBOARD_FAB2_LIB.BASEBOARD_FAB2(SCH_1):SVID_VDIO_PVDDQ_ABC
    2  SVID_DIO1_CPU0_R      B  @BASEBOARD_FAB2_LIB.BASEBOARD_FAB2(SCH_1):SVID_DIO1_CPU0_R

RES  I337  R7G3   [RES_0402-1.5K,1%,1/16W,CHIP,G2A]
    1  VR_PVDDQ_ABC_VINSEN      A  @BASEBOARD_FAB2_LIB.BASEBOARD_FAB2(SCH_1):VR_PVDDQ_ABC_VINSEN
    2  GND                B  @BASEBOARD_FAB2_LIB.BASEBOARD_FAB2(SCH_1):GND

RES  I302  R7G4   [RES_0402-0.0,5%,1/16W,CHIP,G21A]
    1  SVID_ALERT_PVDDQ_ABC      A  @BASEBOARD_FAB2_LIB.BASEBOARD_FAB2(SCH_1):SVID_ALERT_PVDDQ_ABC
    2  SVID_ALERT1_CPU0_R_N      B  @BASEBOARD_FAB2_LIB.BASEBOARD_FAB2(SCH_1):SVID_ALERT1_CPU0_R_N

RES  I51  R7G7   [RES_0402-4.75K,1%,1/16W,CHIP,GA]
    1  P3V3               A  @BASEBOARD_FAB2_LIB.BASEBOARD_FAB2(SCH_1):P3V3
    2  H_CPU0_MEMABC_MEMHOT      B  @BASEBOARD_FAB2_LIB.BASEBOARD_FAB2(SCH_1):H_CPU0_MEMABC_MEMHOT

RES  I321  R7G8   [RES_0402-4.02K,1%,1/16W,CHIP,GA]
    1  VR_PVDDQ_ABC_XADDR1      A  @BASEBOARD_FAB2_LIB.BASEBOARD_FAB2(SCH_1):VR_PVDDQ_ABC_XADDR1
    2  GND                B  @BASEBOARD_FAB2_LIB.BASEBOARD_FAB2(SCH_1):GND

RES  I344  R7G9   [RES_0402-10.0,1%,1/16W,CHIP,G2A]
    1  VSENSE_PVDDQ_ABC_P      A  @BASEBOARD_FAB2_LIB.BASEBOARD_FAB2(SCH_1):VSENSE_PVDDQ_ABC_P
    2  VR_PVDDQ_ABC_AVSP      B  @BASEBOARD_FAB2_LIB.BASEBOARD_FAB2(SCH_1):VR_PVDDQ_ABC_AVSP

RES  I317  R7G10  [RES_0402-8.06K,1%,1/16W,CHIP,GA]
    1  VR_PVDDQ_ABC_XADDR2      A  @BASEBOARD_FAB2_LIB.BASEBOARD_FAB2(SCH_1):VR_PVDDQ_ABC_XADDR2
    2  GND                B  @BASEBOARD_FAB2_LIB.BASEBOARD_FAB2(SCH_1):GND

RES  I38  R7G14  [RES_0402-0.0,5%,1/16W,CHIP,G21A]
    2  JTAG_TDO           B  @BASEBOARD_FAB2_LIB.BASEBOARD_FAB2(SCH_1):JTAG_TDO
    1  JTAG_PLD_TDO       A  @BASEBOARD_FAB2_LIB.BASEBOARD_FAB2(SCH_1):JTAG_PLD_TDO

RES  I36  R7G15  [RES_0402-0.0,5%,1/16W,EMPTY,G2A]
    2  JTAG_TDO           B  @BASEBOARD_FAB2_LIB.BASEBOARD_FAB2(SCH_1):JTAG_TDO
    1  JTAG_PCH_PLD_TDO      A  @BASEBOARD_FAB2_LIB.BASEBOARD_FAB2(SCH_1):JTAG_PCH_PLD_TDO

RES  I27  R7G16  [RES_0402-0.0,5%,1/16W,EMPTY,G2A]
    2  JTAG_TDO           B  @BASEBOARD_FAB2_LIB.BASEBOARD_FAB2(SCH_1):JTAG_TDO
    1  JTAG_PCH_GBE_TDO      A  @BASEBOARD_FAB2_LIB.BASEBOARD_FAB2(SCH_1):JTAG_PCH_GBE_TDO

RES  I37  R7G17  [RES_0402-0.0,5%,1/16W,CHIP,G21A]
    2  JTAG_TDO           B  @BASEBOARD_FAB2_LIB.BASEBOARD_FAB2(SCH_1):JTAG_TDO
    1  JTAG_BMC_TDO       A  @BASEBOARD_FAB2_LIB.BASEBOARD_FAB2(SCH_1):JTAG_BMC_TDO

RES  I13  R7G18  [RES_0402-0.0,5%,1/16W,EMPTY,G2A]
    2  JTAG_TDI           B  @BASEBOARD_FAB2_LIB.BASEBOARD_FAB2(SCH_1):JTAG_TDI
    1  JTAG_PCH_PLD_TDI      A  @BASEBOARD_FAB2_LIB.BASEBOARD_FAB2(SCH_1):JTAG_PCH_PLD_TDI

RES  I8   R7G19  [RES_0402-0.0,5%,1/16W,EMPTY,G2A]
    2  JTAG_TDI           B  @BASEBOARD_FAB2_LIB.BASEBOARD_FAB2(SCH_1):JTAG_TDI
    1  JTAG_PCH_GBE_TDI      A  @BASEBOARD_FAB2_LIB.BASEBOARD_FAB2(SCH_1):JTAG_PCH_GBE_TDI

RES  I63  R7G21  [RES_0402-0.0,5%,1/16W,CHIP,G21A]
    2  JTAG_TDO_R         B  @BASEBOARD_FAB2_LIB.BASEBOARD_FAB2(SCH_1):JTAG_TDO_R
    1  JTAG_TDO           A  @BASEBOARD_FAB2_LIB.BASEBOARD_FAB2(SCH_1):JTAG_TDO

RES  I53  R7G22  [RES_0402-10.0K,1%,1/16W,CHIP,GA]
    1  P3V3_STBY          A  @BASEBOARD_FAB2_LIB.BASEBOARD_FAB2(SCH_1):P3V3_STBY
    2  JTAG_TDO_R         B  @BASEBOARD_FAB2_LIB.BASEBOARD_FAB2(SCH_1):JTAG_TDO_R

RES  I51  R7G23  [RES_0402-10.0K,1%,1/16W,CHIP,GA]
    1  P3V3_STBY          A  @BASEBOARD_FAB2_LIB.BASEBOARD_FAB2(SCH_1):P3V3_STBY
    2  JTAG_TDI_R         B  @BASEBOARD_FAB2_LIB.BASEBOARD_FAB2(SCH_1):JTAG_TDI_R

RES  I331  R7G24  [RES_0402-150.0,1%,1/16W,CHIP,GA]
    2  SVID_CLK_PVDDQ_ABC      B  @BASEBOARD_FAB2_LIB.BASEBOARD_FAB2(SCH_1):SVID_CLK_PVDDQ_ABC
    1  SVID_CLK1_CPU0_R      A  @BASEBOARD_FAB2_LIB.BASEBOARD_FAB2(SCH_1):SVID_CLK1_CPU0_R

RES  I104  R7G25  [RES_0402-68.1K,1%,1/16W,EMPTY,A]
    1  VR_PVDDQ_ABC_PH1_OCSET      A  @BASEBOARD_FAB2_LIB.BASEBOARD_FAB2(SCH_1):VR_PVDDQ_ABC_PH1_OCSET
    2  GND                B  @BASEBOARD_FAB2_LIB.BASEBOARD_FAB2(SCH_1):GND

RES  I101  R7G26  [RES_0402-10.0K,1%,1/16W,CHIP,GA]
    1  P3V3_STBY          A  @BASEBOARD_FAB2_LIB.BASEBOARD_FAB2(SCH_1):P3V3_STBY
    2  FM_ME_RECOVER_N      B  @BASEBOARD_FAB2_LIB.BASEBOARD_FAB2(SCH_1):FM_ME_RECOVER_N

RES  I155  R7G27  [RES_0402-1.00K,1%,1/16W,CHIP,GA]
    2  PU_BIOS_USB_RECOVERY      B  @BASEBOARD_FAB2_LIB.BASEBOARD_FAB2(SCH_1):PU_BIOS_USB_RECOVERY
    1  P3V3_STBY          A  @BASEBOARD_FAB2_LIB.BASEBOARD_FAB2(SCH_1):P3V3_STBY

RES  I102  R7G28  [RES_0402-1.00K,1%,1/16W,CHIP,GA]
    1  PD_ME_RCVR_N       A  @BASEBOARD_FAB2_LIB.BASEBOARD_FAB2(SCH_1):PD_ME_RCVR_N
    2  GND                B  @BASEBOARD_FAB2_LIB.BASEBOARD_FAB2(SCH_1):GND

RES  I148  R7G29  [RES_0402-1.00K,1%,1/16W,CHIP,GA]
    1  PD_PASSWORD_CLEAR      A  @BASEBOARD_FAB2_LIB.BASEBOARD_FAB2(SCH_1):PD_PASSWORD_CLEAR
    2  GND                B  @BASEBOARD_FAB2_LIB.BASEBOARD_FAB2(SCH_1):GND

RES  I106  R7G30  [RES_0402-68.1K,1%,1/16W,EMPTY,A]
    1  VR_PVDDQ_ABC_PH2_OCSET      A  @BASEBOARD_FAB2_LIB.BASEBOARD_FAB2(SCH_1):VR_PVDDQ_ABC_PH2_OCSET
    2  GND                B  @BASEBOARD_FAB2_LIB.BASEBOARD_FAB2(SCH_1):GND

RES  I139  R7G31  [RES_0402-1.00K,1%,1/16W,CHIP,GA]
    2  PU_BIOS_RECOVER_BOOT      B  @BASEBOARD_FAB2_LIB.BASEBOARD_FAB2(SCH_1):PU_BIOS_RECOVER_BOOT
    1  P3V3_STBY          A  @BASEBOARD_FAB2_LIB.BASEBOARD_FAB2(SCH_1):P3V3_STBY

RES  I74  R7L2   [RES_0402-100.0,1%,1/16W,EMPTY,A]
    1  VSENSE_PVDDQ_KLM_P      A  @BASEBOARD_FAB2_LIB.BASEBOARD_FAB2(SCH_1):VSENSE_PVDDQ_KLM_P
    2  VSENSE_PVDDQ_KLM_N      B  @BASEBOARD_FAB2_LIB.BASEBOARD_FAB2(SCH_1):VSENSE_PVDDQ_KLM_N

RES  I109  R7M1   [RES_0402-665,1.0%,1/16W,CHIP,GA]
    2  SMB_DDR_KLM_VPP_SCL_R      B  @BASEBOARD_FAB2_LIB.BASEBOARD_FAB2(SCH_1):SMB_DDR_KLM_VPP_SCL_R
    1  PVPP_KLM           A  @BASEBOARD_FAB2_LIB.BASEBOARD_FAB2(SCH_1):PVPP_KLM

RES  I79  R7M2   [RES_0402-240,1.0%,1/16W,CHIP,GA]
    2  SMB_DDR_KLM_SCL_G      B  @BASEBOARD_FAB2_LIB.BASEBOARD_FAB2(SCH_1):SMB_DDR_KLM_SCL_G
    1  PVCCIO_CPU1        A  @BASEBOARD_FAB2_LIB.BASEBOARD_FAB2(SCH_1):PVCCIO_CPU1

RES  I98  R7M3   [RES_0402-10.0,1%,1/16W,CHIP,G2A]
    1  SMB_DDR_KLM_SCL_G_R      A  @BASEBOARD_FAB2_LIB.BASEBOARD_FAB2(SCH_1):SMB_DDR_KLM_SCL_G_R
    2  SMB_DDR_KLM_SCL_G      B  @BASEBOARD_FAB2_LIB.BASEBOARD_FAB2(SCH_1):SMB_DDR_KLM_SCL_G

RES  I56  R7M4   [RES_0402-20.0,1%,1/16W,CHIP,G2A]
    1  SMB_DDR_KLM_VPP_SCL_R      A  @BASEBOARD_FAB2_LIB.BASEBOARD_FAB2(SCH_1):SMB_DDR_KLM_VPP_SCL_R
    2  SMB_DDR_KLM_VPP_SCL      B  @BASEBOARD_FAB2_LIB.BASEBOARD_FAB2(SCH_1):SMB_DDR_KLM_VPP_SCL

RES  I55  R7M5   [RES_0402-20.0,1%,1/16W,CHIP,G2A]
    1  SMB_DDR_KLM_VPP_SDA_R      A  @BASEBOARD_FAB2_LIB.BASEBOARD_FAB2(SCH_1):SMB_DDR_KLM_VPP_SDA_R
    2  SMB_DDR_KLM_VPP_SDA      B  @BASEBOARD_FAB2_LIB.BASEBOARD_FAB2(SCH_1):SMB_DDR_KLM_VPP_SDA

RES  I107  R7M6   [RES_0402-665,1.0%,1/16W,CHIP,GA]
    2  SMB_DDR_KLM_VPP_SDA_R      B  @BASEBOARD_FAB2_LIB.BASEBOARD_FAB2(SCH_1):SMB_DDR_KLM_VPP_SDA_R
    1  PVPP_KLM           A  @BASEBOARD_FAB2_LIB.BASEBOARD_FAB2(SCH_1):PVPP_KLM

RES  I77  R7M7   [RES_0402-240,1.0%,1/16W,CHIP,GA]
    2  SMB_DDR_KLM_SDA_G      B  @BASEBOARD_FAB2_LIB.BASEBOARD_FAB2(SCH_1):SMB_DDR_KLM_SDA_G
    1  PVCCIO_CPU1        A  @BASEBOARD_FAB2_LIB.BASEBOARD_FAB2(SCH_1):PVCCIO_CPU1

RES  I112  R7M8   [RES_0402-10.0,1%,1/16W,CHIP,G2A]
    1  SMB_DDR_KLM_SDA_G_R      A  @BASEBOARD_FAB2_LIB.BASEBOARD_FAB2(SCH_1):SMB_DDR_KLM_SDA_G_R
    2  SMB_DDR_KLM_SDA_G      B  @BASEBOARD_FAB2_LIB.BASEBOARD_FAB2(SCH_1):SMB_DDR_KLM_SDA_G

RES  I28  R7M9   [RES_0402-64.9,1.0%,1/16W,CHIP,A]
    2  PWRGD_CPU1_DRAMPWROK_KLM_G      B  @BASEBOARD_FAB2_LIB.BASEBOARD_FAB2(SCH_1):PWRGD_CPU1_DRAMPWROK_KLM_G
    1  PVDDQ_KLM          A  @BASEBOARD_FAB2_LIB.BASEBOARD_FAB2(SCH_1):PVDDQ_KLM

RES  I133  R7P1   [RES_0402-42.2,1.0%,1/16W,EMPTYA]
    2  GND                B  @BASEBOARD_FAB2_LIB.BASEBOARD_FAB2(SCH_1):GND
    1  CLK_100M_CPU1_BCLK2_DP      A  @BASEBOARD_FAB2_LIB.BASEBOARD_FAB2(SCH_1):CLK_100M_CPU1_BCLK2_DP

RES  I135  R7P2   [RES_0402-42.2,1.0%,1/16W,EMPTYA]
    2  GND                B  @BASEBOARD_FAB2_LIB.BASEBOARD_FAB2(SCH_1):GND
    1  CLK_100M_CPU1_BCLK2_DN      A  @BASEBOARD_FAB2_LIB.BASEBOARD_FAB2(SCH_1):CLK_100M_CPU1_BCLK2_DN

RES  I129  R7P3   [RES_0402-42.2,1.0%,1/16W,EMPTYA]
    2  GND                B  @BASEBOARD_FAB2_LIB.BASEBOARD_FAB2(SCH_1):GND
    1  CLK_100M_CPU1_PE_REFCLK_DP      A  @BASEBOARD_FAB2_LIB.BASEBOARD_FAB2(SCH_1):CLK_100M_CPU1_PE_REFCLK_DP

RES  I131  R7P4   [RES_0402-42.2,1.0%,1/16W,EMPTYA]
    2  GND                B  @BASEBOARD_FAB2_LIB.BASEBOARD_FAB2(SCH_1):GND
    1  CLK_100M_CPU1_PE_REFCLK_DN      A  @BASEBOARD_FAB2_LIB.BASEBOARD_FAB2(SCH_1):CLK_100M_CPU1_PE_REFCLK_DN

RES  I61  R7P5   [RES_0402-150.0,1%,1/16W,CHIP,GA]
    2  PVCCIO_CPU1        B  @BASEBOARD_FAB2_LIB.BASEBOARD_FAB2(SCH_1):PVCCIO_CPU1
    1  H_CPU1_MEMGHJ_MEMHOT_G_N      A  @BASEBOARD_FAB2_LIB.BASEBOARD_FAB2(SCH_1):H_CPU1_MEMGHJ_MEMHOT_G_N

RES  I125  R7P6   [RES_0402-42.2,1.0%,1/16W,EMPTYA]
    2  GND                B  @BASEBOARD_FAB2_LIB.BASEBOARD_FAB2(SCH_1):GND
    1  CLK_100M_CPU1_RC_REFCLK0_DP      A  @BASEBOARD_FAB2_LIB.BASEBOARD_FAB2(SCH_1):CLK_100M_CPU1_RC_REFCLK0_DP

RES  I127  R7P7   [RES_0402-42.2,1.0%,1/16W,EMPTYA]
    2  GND                B  @BASEBOARD_FAB2_LIB.BASEBOARD_FAB2(SCH_1):GND
    1  CLK_100M_CPU1_RC_REFCLK0_DN      A  @BASEBOARD_FAB2_LIB.BASEBOARD_FAB2(SCH_1):CLK_100M_CPU1_RC_REFCLK0_DN

RES  I123  R7P8   [RES_0402-49.9,1%,1/16W,CHIP,G2A]
    2  GND                B  @BASEBOARD_FAB2_LIB.BASEBOARD_FAB2(SCH_1):GND
    1  A_CPU1_PE3_RBIAS      A  @BASEBOARD_FAB2_LIB.BASEBOARD_FAB2(SCH_1):A_CPU1_PE3_RBIAS

RES  I121  R7P9   [RES_0402-42.2,1.0%,1/16W,EMPTYA]
    2  GND                B  @BASEBOARD_FAB2_LIB.BASEBOARD_FAB2(SCH_1):GND
    1  CLK_100M_CPU1_RC_REFCLK1_DP      A  @BASEBOARD_FAB2_LIB.BASEBOARD_FAB2(SCH_1):CLK_100M_CPU1_RC_REFCLK1_DP

RES  I124  R7P10  [RES_0402-49.9,1%,1/16W,CHIP,G2A]
    2  GND                B  @BASEBOARD_FAB2_LIB.BASEBOARD_FAB2(SCH_1):GND
    1  A_CPU1_PE012_RBIAS      A  @BASEBOARD_FAB2_LIB.BASEBOARD_FAB2(SCH_1):A_CPU1_PE012_RBIAS

RES  I126  R7P11  [RES_0402-49.9,1%,1/16W,CHIP,G2A]
    2  GND                B  @BASEBOARD_FAB2_LIB.BASEBOARD_FAB2(SCH_1):GND
    1  A_CPU1_UPI2_RBIAS      A  @BASEBOARD_FAB2_LIB.BASEBOARD_FAB2(SCH_1):A_CPU1_UPI2_RBIAS

RES  I123  R7P12  [RES_0402-42.2,1.0%,1/16W,EMPTYA]
    2  GND                B  @BASEBOARD_FAB2_LIB.BASEBOARD_FAB2(SCH_1):GND
    1  CLK_100M_CPU1_RC_REFCLK1_DN      A  @BASEBOARD_FAB2_LIB.BASEBOARD_FAB2(SCH_1):CLK_100M_CPU1_RC_REFCLK1_DN

RES  I81  R7P13  [RES_0402-10.0K,1%,1/16W,CHIP,GA]
    2  PD_CPU1_MCP01_DMON      B  @BASEBOARD_FAB2_LIB.BASEBOARD_FAB2(SCH_1):PD_CPU1_MCP01_DMON
    1  GND                A  @BASEBOARD_FAB2_LIB.BASEBOARD_FAB2(SCH_1):GND

RES  I70  R7P14  [RES_0402-240,1.0%,1/16W,CHIP,GA]
    2  PD_CPU1_DMIMODE_OVERRIDE      B  @BASEBOARD_FAB2_LIB.BASEBOARD_FAB2(SCH_1):PD_CPU1_DMIMODE_OVERRIDE
    1  GND                A  @BASEBOARD_FAB2_LIB.BASEBOARD_FAB2(SCH_1):GND

RES  I74  R7P15  [RES_0402-240,1.0%,1/16W,EMPTY,A]
    2  PD_CPU1_KSFC_DIS      B  @BASEBOARD_FAB2_LIB.BASEBOARD_FAB2(SCH_1):PD_CPU1_KSFC_DIS
    1  GND                A  @BASEBOARD_FAB2_LIB.BASEBOARD_FAB2(SCH_1):GND

RES  I119  R7P16  [RES_0402-90.9,1%,1/16W,CHIP,G2A]
    2  GND                B  @BASEBOARD_FAB2_LIB.BASEBOARD_FAB2(SCH_1):GND
    1  A_CPU1_GHJ_RCOMP0      A  @BASEBOARD_FAB2_LIB.BASEBOARD_FAB2(SCH_1):A_CPU1_GHJ_RCOMP0

RES  I140  R7P17  [RES_0402-90.9,1%,1/16W,CHIP,G2A]
    2  GND                B  @BASEBOARD_FAB2_LIB.BASEBOARD_FAB2(SCH_1):GND
    1  A_CPU1_GHJ_RCOMP1      A  @BASEBOARD_FAB2_LIB.BASEBOARD_FAB2(SCH_1):A_CPU1_GHJ_RCOMP1

RES  I100  R7P18  [RES_0402-150.0,1%,1/16W,CHIP,GA]
    1  PVCCIO_CPU0        A  @BASEBOARD_FAB2_LIB.BASEBOARD_FAB2(SCH_1):PVCCIO_CPU0
    2  H_CPU1_CATERR_G_N      B  @BASEBOARD_FAB2_LIB.BASEBOARD_FAB2(SCH_1):H_CPU1_CATERR_G_N

RES  I115  R7P19  [RES_0402-100.0,1%,1/16W,CHIP,GA]
    2  GND                B  @BASEBOARD_FAB2_LIB.BASEBOARD_FAB2(SCH_1):GND
    1  A_CPU1_GHJ_RCOMP2      A  @BASEBOARD_FAB2_LIB.BASEBOARD_FAB2(SCH_1):A_CPU1_GHJ_RCOMP2

RES  I44  R7P20  [RES_0402-150.0,1%,1/16W,CHIP,GA]
    1  PVCCIO_CPU0        A  @BASEBOARD_FAB2_LIB.BASEBOARD_FAB2(SCH_1):PVCCIO_CPU0
    2  H_CPU1_FAST_WAKE_N      B  @BASEBOARD_FAB2_LIB.BASEBOARD_FAB2(SCH_1):H_CPU1_FAST_WAKE_N

RES  I62  R7P21  [RES_0402-150.0,1%,1/16W,CHIP,GA]
    2  PVCCIO_CPU1        B  @BASEBOARD_FAB2_LIB.BASEBOARD_FAB2(SCH_1):PVCCIO_CPU1
    1  H_CPU1_MEMKLM_MEMHOT_G_N      A  @BASEBOARD_FAB2_LIB.BASEBOARD_FAB2(SCH_1):H_CPU1_MEMKLM_MEMHOT_G_N

RES  I76  R7P22  [RES_0402-240,1.0%,1/16W,EMPTY,A]
    1  PVCCIO_CPU1        A  @BASEBOARD_FAB2_LIB.BASEBOARD_FAB2(SCH_1):PVCCIO_CPU1
    2  PU_CPU1_LEGACY_SKT      B  @BASEBOARD_FAB2_LIB.BASEBOARD_FAB2(SCH_1):PU_CPU1_LEGACY_SKT

RES  I170  R7P25  [RES_0402-49.9,1%,1/16W,CHIP,G2A]
    1  H_PM_SYNC_GTL_R2      A  @BASEBOARD_FAB2_LIB.BASEBOARD_FAB2(SCH_1):H_PM_SYNC_GTL_R2
    2  H_PM_SYNC_GTL      B  @BASEBOARD_FAB2_LIB.BASEBOARD_FAB2(SCH_1):H_PM_SYNC_GTL

RES  I156  R7P26  [RES_0402-49.9,1%,1/16W,CHIP,G2A]
    1  H_PMSYNC_CLK_24M_CPU1      A  @BASEBOARD_FAB2_LIB.BASEBOARD_FAB2(SCH_1):H_PMSYNC_CLK_24M_CPU1
    2  H_PMSYNC_CLK_24M      B  @BASEBOARD_FAB2_LIB.BASEBOARD_FAB2(SCH_1):H_PMSYNC_CLK_24M

RES  I65  R7P27  [RES_0402-150.0,1%,1/16W,CHIP,GA]
    1  PVCCIO_CPU0        A  @BASEBOARD_FAB2_LIB.BASEBOARD_FAB2(SCH_1):PVCCIO_CPU0
    2  H_CPU1_MSMI_G_N      B  @BASEBOARD_FAB2_LIB.BASEBOARD_FAB2(SCH_1):H_CPU1_MSMI_G_N

RES  I106  R7P28  [RES_0402-150.0,1%,1/16W,CHIP,GA]
    1  PVCCIO_CPU1        A  @BASEBOARD_FAB2_LIB.BASEBOARD_FAB2(SCH_1):PVCCIO_CPU1
    2  H_CPU1_PROCHOT_G_N      B  @BASEBOARD_FAB2_LIB.BASEBOARD_FAB2(SCH_1):H_CPU1_PROCHOT_G_N

RES  I61  R7P29  [RES_0402-51.1,1.0%,1/16W,CHIP,A]
    1  XDP_CPU_TCK0       A  @BASEBOARD_FAB2_LIB.BASEBOARD_FAB2(SCH_1):XDP_CPU_TCK0
    2  GND                B  @BASEBOARD_FAB2_LIB.BASEBOARD_FAB2(SCH_1):GND

RES  I50  R7P30  [RES_0402-100.0,1%,1/16W,CHIP,GA]
    2  XDP_CPU_MBP0_N      B  @BASEBOARD_FAB2_LIB.BASEBOARD_FAB2(SCH_1):XDP_CPU_MBP0_N
    1  PVCCIO_CPU0        A  @BASEBOARD_FAB2_LIB.BASEBOARD_FAB2(SCH_1):PVCCIO_CPU0

RES  I109  R7R1   [RES_0402-51.1,1.0%,1/16W,CHIP,A]
    1  PVCCIO_CPU1        A  @BASEBOARD_FAB2_LIB.BASEBOARD_FAB2(SCH_1):PVCCIO_CPU1
    2  GND                B  @BASEBOARD_FAB2_LIB.BASEBOARD_FAB2(SCH_1):GND

RES  I74  R7U2   [RES_0402-100.0,1%,1/16W,EMPTY,A]
    1  VSENSE_PVDDQ_GHJ_P      A  @BASEBOARD_FAB2_LIB.BASEBOARD_FAB2(SCH_1):VSENSE_PVDDQ_GHJ_P
    2  VSENSE_PVDDQ_GHJ_N      B  @BASEBOARD_FAB2_LIB.BASEBOARD_FAB2(SCH_1):VSENSE_PVDDQ_GHJ_N

RES  I210  R8A1   [RES_0402-10.0,1%,1/16W,CHIP,G2A]
    1  VSENSE_PVNN_PCH_STBY_AVSP      A  @BASEBOARD_FAB2_LIB.BASEBOARD_FAB2(SCH_1):VSENSE_PVNN_PCH_STBY_AVSP
    2  VR_PVNN_PCH_AVSP      B  @BASEBOARD_FAB2_LIB.BASEBOARD_FAB2(SCH_1):VR_PVNN_PCH_AVSP

RES  I217  R8A2   [RES_0402-2.67K,1%,1/16W,CHIP,GA]
    1  VR_PVNN_PCH_XADDR2      A  @BASEBOARD_FAB2_LIB.BASEBOARD_FAB2(SCH_1):VR_PVNN_PCH_XADDR2
    2  GND                B  @BASEBOARD_FAB2_LIB.BASEBOARD_FAB2(SCH_1):GND

RES  I165  R8A4   [RES_0402-100.0K,1%,1/16W,CHIP,B]
    2  VR_PVNN_PCH_VINSEN      B  @BASEBOARD_FAB2_LIB.BASEBOARD_FAB2(SCH_1):VR_PVNN_PCH_VINSEN
    1  VR_FET_SW_P12V_STBY_PVDDQ_DEF      A  @BASEBOARD_FAB2_LIB.BASEBOARD_FAB2(SCH_1):VR_FET_SW_P12V_STBY_PVDDQ_DEF

RES  I216  R8A5   [RES_0402-1.00K,1%,1/16W,CHIP,GA]
    1  P3V3_STBY          A  @BASEBOARD_FAB2_LIB.BASEBOARD_FAB2(SCH_1):P3V3_STBY
    2  IRQ_PVNN_PCH_VRHOT_N      B  @BASEBOARD_FAB2_LIB.BASEBOARD_FAB2(SCH_1):IRQ_PVNN_PCH_VRHOT_N

RES  I149  R8A6   [RES_0402-1.00K,1%,1/16W,CHIP,GA]
    2  PWRGD_PVNN_PCH_R      B  @BASEBOARD_FAB2_LIB.BASEBOARD_FAB2(SCH_1):PWRGD_PVNN_PCH_R
    1  P3V3_STBY          A  @BASEBOARD_FAB2_LIB.BASEBOARD_FAB2(SCH_1):P3V3_STBY

RES  I222  R8A7   [RES_0402-100.0K,1%,1/16W,EMPTYA]
    2  VR_PVNN_PCH_VREN      B  @BASEBOARD_FAB2_LIB.BASEBOARD_FAB2(SCH_1):VR_PVNN_PCH_VREN
    1  P3V3_STBY          A  @BASEBOARD_FAB2_LIB.BASEBOARD_FAB2(SCH_1):P3V3_STBY

RES  I172  R8A8   [RES_0402-20.0,1%,1/16W,CHIP,G2A]
    1  SMB_VR_STBY_LVC3_SDA      A  @BASEBOARD_FAB2_LIB.BASEBOARD_FAB2(SCH_1):SMB_VR_STBY_LVC3_SDA
    2  SMB_VR_SDA_PVNN_PCH      B  @BASEBOARD_FAB2_LIB.BASEBOARD_FAB2(SCH_1):SMB_VR_SDA_PVNN_PCH

RES  I173  R8A9   [RES_0402-20.0,1%,1/16W,CHIP,G2A]
    1  SMB_VR_STBY_LVC3_SCL      A  @BASEBOARD_FAB2_LIB.BASEBOARD_FAB2(SCH_1):SMB_VR_STBY_LVC3_SCL
    2  SMB_VR_SCL_PVNN_PCH      B  @BASEBOARD_FAB2_LIB.BASEBOARD_FAB2(SCH_1):SMB_VR_SCL_PVNN_PCH

RES  I3   R8A10  [RES_0402-5.11K,1%,1/16W,CHIP,GA]
    2  PWRGD_P1V8_PCH_STBY_R      B  @BASEBOARD_FAB2_LIB.BASEBOARD_FAB2(SCH_1):PWRGD_P1V8_PCH_STBY_R
    1  P3V3_STBY          A  @BASEBOARD_FAB2_LIB.BASEBOARD_FAB2(SCH_1):P3V3_STBY

RES  I90  R8A11  [RES_0402-22.1,1.0%,1/16W,CHIP,A]
    1  PWRGD_P1V8_PCH_STBY_R      A  @BASEBOARD_FAB2_LIB.BASEBOARD_FAB2(SCH_1):PWRGD_P1V8_PCH_STBY_R
    2  PWRGD_P1V8_PCH_STBY      B  @BASEBOARD_FAB2_LIB.BASEBOARD_FAB2(SCH_1):PWRGD_P1V8_PCH_STBY

RES  I15  R8A12  [RES_0603-475.0,1%,1/10W,CHIP,GA]
    1  P1V8_PCH_STBY      A  @BASEBOARD_FAB2_LIB.BASEBOARD_FAB2(SCH_1):P1V8_PCH_STBY
    2  GND                B  @BASEBOARD_FAB2_LIB.BASEBOARD_FAB2(SCH_1):GND

RES  I79  R8A13  [RES_0402-150.0,1%,1/16W,CHIP,GA]
    2  XDP_TDI            B  @BASEBOARD_FAB2_LIB.BASEBOARD_FAB2(SCH_1):XDP_TDI
    1  P1V05_PCH_STBY      A  @BASEBOARD_FAB2_LIB.BASEBOARD_FAB2(SCH_1):P1V05_PCH_STBY

RES  I80  R8A14  [RES_0402-150.0,1%,1/16W,CHIP,GA]
    2  XDP_TMS            B  @BASEBOARD_FAB2_LIB.BASEBOARD_FAB2(SCH_1):XDP_TMS
    1  P1V05_PCH_STBY      A  @BASEBOARD_FAB2_LIB.BASEBOARD_FAB2(SCH_1):P1V05_PCH_STBY

RES  I95  R8B1   [RES_0402-51.1,1.0%,1/16W,CHIP,A]
    1  XDP_PCH_TCK1       A  @BASEBOARD_FAB2_LIB.BASEBOARD_FAB2(SCH_1):XDP_PCH_TCK1
    2  GND                B  @BASEBOARD_FAB2_LIB.BASEBOARD_FAB2(SCH_1):GND

RES  I94  R8B2   [RES_0402-1.00K,1%,1/16W,CHIP,GA]
    1  XDP_TRST_N         A  @BASEBOARD_FAB2_LIB.BASEBOARD_FAB2(SCH_1):XDP_TRST_N
    2  GND                B  @BASEBOARD_FAB2_LIB.BASEBOARD_FAB2(SCH_1):GND

RES  I24  R8B3   [RES_0402-4.75K,1%,1/16W,CHIP,GA]
    1  PVPP_ABC           A  @BASEBOARD_FAB2_LIB.BASEBOARD_FAB2(SCH_1):PVPP_ABC
    2  FM_MODPRST_HFI0_CPU0_LVT2_N      B  @BASEBOARD_FAB2_LIB.BASEBOARD_FAB2(SCH_1):FM_MODPRST_HFI0_CPU0_LVT2_N

RES  I83  R8B4   [RES_0402-100.0K,1%,1/16W,CHIP,A]
    2  GND                B  @BASEBOARD_FAB2_LIB.BASEBOARD_FAB2(SCH_1):GND
    1  FM_CTNR_PS_ON      A  @BASEBOARD_FAB2_LIB.BASEBOARD_FAB2(SCH_1):FM_CTNR_PS_ON

RES  I22  R8B5   [RES_0402-4.75K,1%,1/16W,CHIP,GA]
    1  PVPP_ABC           A  @BASEBOARD_FAB2_LIB.BASEBOARD_FAB2(SCH_1):PVPP_ABC
    2  LED_HFI0_CPU0_N      B  @BASEBOARD_FAB2_LIB.BASEBOARD_FAB2(SCH_1):LED_HFI0_CPU0_N

RES  I37  R8B6   [RES_0402-1.8K,1%,1/16W,CHIP,G2A]
    2  SMB_HFI0_CPU0_LVC2_SCL      B  @BASEBOARD_FAB2_LIB.BASEBOARD_FAB2(SCH_1):SMB_HFI0_CPU0_LVC2_SCL
    1  PVPP_ABC           A  @BASEBOARD_FAB2_LIB.BASEBOARD_FAB2(SCH_1):PVPP_ABC

RES  I36  R8B7   [RES_0402-1.8K,1%,1/16W,CHIP,G2A]
    2  SMB_HFI0_CPU0_LVC2_SDA      B  @BASEBOARD_FAB2_LIB.BASEBOARD_FAB2(SCH_1):SMB_HFI0_CPU0_LVC2_SDA
    1  PVPP_ABC           A  @BASEBOARD_FAB2_LIB.BASEBOARD_FAB2(SCH_1):PVPP_ABC

RES  I14  R8B8   [RES_0402-4.75K,1%,1/16W,CHIP,GA]
    2  RST_HFI0_CPU0_LVT2_N      B  @BASEBOARD_FAB2_LIB.BASEBOARD_FAB2(SCH_1):RST_HFI0_CPU0_LVT2_N
    1  PVPP_ABC           A  @BASEBOARD_FAB2_LIB.BASEBOARD_FAB2(SCH_1):PVPP_ABC

RES  I90  R8B9   [RES_0402-113,1%,1/16W,CHIP,G21A]
    2  GND                B  @BASEBOARD_FAB2_LIB.BASEBOARD_FAB2(SCH_1):GND
    1  A_USB2_COMP        A  @BASEBOARD_FAB2_LIB.BASEBOARD_FAB2(SCH_1):A_USB2_COMP

RES  I16  R8B10  [RES_0402-4.75K,1%,1/16W,CHIP,GA]
    1  PVPP_ABC           A  @BASEBOARD_FAB2_LIB.BASEBOARD_FAB2(SCH_1):PVPP_ABC
    2  IRQ_HFI0_CPU0_LVT2_N      B  @BASEBOARD_FAB2_LIB.BASEBOARD_FAB2(SCH_1):IRQ_HFI0_CPU0_LVT2_N

RES  I35  R8B11  [RES_0402-1.8K,1%,1/16W,CHIP,G2A]
    2  SMB_HFI1_CPU0_LVC2_SCL      B  @BASEBOARD_FAB2_LIB.BASEBOARD_FAB2(SCH_1):SMB_HFI1_CPU0_LVC2_SCL
    1  PVPP_ABC           A  @BASEBOARD_FAB2_LIB.BASEBOARD_FAB2(SCH_1):PVPP_ABC

RES  I59  R8B12  [RES_0402-0.0,5%,1/16W,CHIP,G21A]
    1  VSENSE_P1V05_PCH_STBY_AVSN      A  @BASEBOARD_FAB2_LIB.BASEBOARD_FAB2(SCH_1):VSENSE_P1V05_PCH_STBY_AVSN
    2  GND                B  @BASEBOARD_FAB2_LIB.BASEBOARD_FAB2(SCH_1):GND

RES  I34  R8B13  [RES_0402-1.8K,1%,1/16W,CHIP,G2A]
    2  SMB_HFI1_CPU0_LVC2_SDA      B  @BASEBOARD_FAB2_LIB.BASEBOARD_FAB2(SCH_1):SMB_HFI1_CPU0_LVC2_SDA
    1  PVPP_ABC           A  @BASEBOARD_FAB2_LIB.BASEBOARD_FAB2(SCH_1):PVPP_ABC

RES  I56  R8B14  [RES_0402-0.0,5%,1/16W,CHIP,G21A]
    1  VSENSE_P1V05_PCH_STBY_AVSP      A  @BASEBOARD_FAB2_LIB.BASEBOARD_FAB2(SCH_1):VSENSE_P1V05_PCH_STBY_AVSP
    2  P1V05_PCH_STBY      B  @BASEBOARD_FAB2_LIB.BASEBOARD_FAB2(SCH_1):P1V05_PCH_STBY

RES  I57  R8B15  [RES_0402-100.0,1%,1/16W,EMPTY,A]
    1  VSENSE_P1V05_PCH_STBY_AVSP      A  @BASEBOARD_FAB2_LIB.BASEBOARD_FAB2(SCH_1):VSENSE_P1V05_PCH_STBY_AVSP
    2  VSENSE_P1V05_PCH_STBY_AVSN      B  @BASEBOARD_FAB2_LIB.BASEBOARD_FAB2(SCH_1):VSENSE_P1V05_PCH_STBY_AVSN

RES  I17  R8B16  [RES_0402-4.75K,1%,1/16W,CHIP,GA]
    2  RST_HFI1_CPU0_LVT2_N      B  @BASEBOARD_FAB2_LIB.BASEBOARD_FAB2(SCH_1):RST_HFI1_CPU0_LVT2_N
    1  PVPP_ABC           A  @BASEBOARD_FAB2_LIB.BASEBOARD_FAB2(SCH_1):PVPP_ABC

RES  I18  R8B17  [RES_0402-4.75K,1%,1/16W,CHIP,GA]
    1  PVPP_ABC           A  @BASEBOARD_FAB2_LIB.BASEBOARD_FAB2(SCH_1):PVPP_ABC
    2  IRQ_HFI1_CPU0_LVT2_N      B  @BASEBOARD_FAB2_LIB.BASEBOARD_FAB2(SCH_1):IRQ_HFI1_CPU0_LVT2_N

RES  I20  R8B18  [RES_0402-4.75K,1%,1/16W,CHIP,GA]
    1  PVPP_ABC           A  @BASEBOARD_FAB2_LIB.BASEBOARD_FAB2(SCH_1):PVPP_ABC
    2  LED_HFI1_CPU0_N      B  @BASEBOARD_FAB2_LIB.BASEBOARD_FAB2(SCH_1):LED_HFI1_CPU0_N

RES  I21  R8B19  [RES_0402-4.75K,1%,1/16W,CHIP,GA]
    1  PVPP_ABC           A  @BASEBOARD_FAB2_LIB.BASEBOARD_FAB2(SCH_1):PVPP_ABC
    2  FM_MODPRST_HFI1_CPU0_LVT2_N      B  @BASEBOARD_FAB2_LIB.BASEBOARD_FAB2(SCH_1):FM_MODPRST_HFI1_CPU0_LVT2_N

RES  I110  R8B20  [RES_0402-10.0,1%,1/16W,CHIP,G2A]
    1  H_PMSYNC_CLK_24M_R      A  @BASEBOARD_FAB2_LIB.BASEBOARD_FAB2(SCH_1):H_PMSYNC_CLK_24M_R
    2  H_PMSYNC_CLK_24M      B  @BASEBOARD_FAB2_LIB.BASEBOARD_FAB2(SCH_1):H_PMSYNC_CLK_24M

RES  I124  R8B21  [RES_0402-49.9,1%,1/16W,EMPTY,GA]
    1  H_PMSYNC_CLK_24M      A  @BASEBOARD_FAB2_LIB.BASEBOARD_FAB2(SCH_1):H_PMSYNC_CLK_24M
    2  GND                B  @BASEBOARD_FAB2_LIB.BASEBOARD_FAB2(SCH_1):GND

RES  I280  R8B23  [RES_0402-1.00K,1%,1/16W,CHIP,GA]
    1  P3V3_STBY          A  @BASEBOARD_FAB2_LIB.BASEBOARD_FAB2(SCH_1):P3V3_STBY
    2  FM_XRC_PRESENT_N      B  @BASEBOARD_FAB2_LIB.BASEBOARD_FAB2(SCH_1):FM_XRC_PRESENT_N

RES  I95  R8B24  [RES_0402-3.3K,5%,1/16W,CHIP,G2A]
    2  SMB_SLOTX24_PCH_STBY_LVC3_SDA      B  @BASEBOARD_FAB2_LIB.BASEBOARD_FAB2(SCH_1):SMB_SLOTX24_PCH_STBY_LVC3_SDA
    1  P3V3_STBY          A  @BASEBOARD_FAB2_LIB.BASEBOARD_FAB2(SCH_1):P3V3_STBY

RES  I140  R8B25  [RES_0402-4.75K,1%,1/16W,CHIP,GA]
    1  P3V3_STBY          A  @BASEBOARD_FAB2_LIB.BASEBOARD_FAB2(SCH_1):P3V3_STBY
    2  FM_BMC_HEARTBEAT_N      B  @BASEBOARD_FAB2_LIB.BASEBOARD_FAB2(SCH_1):FM_BMC_HEARTBEAT_N

RES  I96  R8B26  [RES_0402-3.3K,5%,1/16W,CHIP,G2A]
    2  SMB_SLOTX24_PCH_STBY_LVC3_SCL      B  @BASEBOARD_FAB2_LIB.BASEBOARD_FAB2(SCH_1):SMB_SLOTX24_PCH_STBY_LVC3_SCL
    1  P3V3_STBY          A  @BASEBOARD_FAB2_LIB.BASEBOARD_FAB2(SCH_1):P3V3_STBY

RES  I173  R8B27  [RES_0402-20.0,1%,1/16W,CHIP,G2A]
    1  SMB_SLOTX24_STBY_LVC3_SDA_R1      A  @BASEBOARD_FAB2_LIB.BASEBOARD_FAB2(SCH_1):SMB_SLOTX24_STBY_LVC3_SDA_R1
    2  SMB_SLOTX24_PCH_STBY_LVC3_SDA      B  @BASEBOARD_FAB2_LIB.BASEBOARD_FAB2(SCH_1):SMB_SLOTX24_PCH_STBY_LVC3_SDA

RES  I174  R8B28  [RES_0402-20.0,1%,1/16W,CHIP,G2A]
    1  SMB_SLOTX24_STBY_LVC3_SCL_R1      A  @BASEBOARD_FAB2_LIB.BASEBOARD_FAB2(SCH_1):SMB_SLOTX24_STBY_LVC3_SCL_R1
    2  SMB_SLOTX24_PCH_STBY_LVC3_SCL      B  @BASEBOARD_FAB2_LIB.BASEBOARD_FAB2(SCH_1):SMB_SLOTX24_PCH_STBY_LVC3_SCL

RES  I21  R8B29  [RES_0402-49.9,1%,1/16W,CHIP,G2A]
    2  SGPIO_PCH_SSATA_DOUT0_R      B  @BASEBOARD_FAB2_LIB.BASEBOARD_FAB2(SCH_1):SGPIO_PCH_SSATA_DOUT0_R
    1  SGPIO_PCH_SSATA_DOUT0      A  @BASEBOARD_FAB2_LIB.BASEBOARD_FAB2(SCH_1):SGPIO_PCH_SSATA_DOUT0

RES  I282  R8B30  [RES_0402-1.00K,1%,1/16W,CHIP,GA]
    1  P3V3_STBY          A  @BASEBOARD_FAB2_LIB.BASEBOARD_FAB2(SCH_1):P3V3_STBY
    2  FM_XRC_READY_N      B  @BASEBOARD_FAB2_LIB.BASEBOARD_FAB2(SCH_1):FM_XRC_READY_N

RES  I307  R8B31  [RES_0402-4.75K,1%,1/16W,CHIP,GA]
    1  P3V3_STBY          A  @BASEBOARD_FAB2_LIB.BASEBOARD_FAB2(SCH_1):P3V3_STBY
    2  FM_THROTTLE_N      B  @BASEBOARD_FAB2_LIB.BASEBOARD_FAB2(SCH_1):FM_THROTTLE_N

RES  I114  R8B32  [RES_0402-10.0K,1%,1/16W,CHIP,GA]
    2  GND                B  @BASEBOARD_FAB2_LIB.BASEBOARD_FAB2(SCH_1):GND
    1  A_USB2_VBUS        A  @BASEBOARD_FAB2_LIB.BASEBOARD_FAB2(SCH_1):A_USB2_VBUS

RES  I326  R8C1   [RES_0402-4.75K,1%,1/16W,CHIP,GA]
    1  P3V3_STBY          A  @BASEBOARD_FAB2_LIB.BASEBOARD_FAB2(SCH_1):P3V3_STBY
    2  FM_SLT_CFG1        B  @BASEBOARD_FAB2_LIB.BASEBOARD_FAB2(SCH_1):FM_SLT_CFG1

RES  I304  R8C2   [RES_0402-4.75K,1%,1/16W,CHIP,GA]
    1  P3V3_STBY          A  @BASEBOARD_FAB2_LIB.BASEBOARD_FAB2(SCH_1):P3V3_STBY
    2  IRQ_BMC_PCH_SCI_LPC_N      B  @BASEBOARD_FAB2_LIB.BASEBOARD_FAB2(SCH_1):IRQ_BMC_PCH_SCI_LPC_N

RES  I286  R8C4   [RES_0402-1.00K,1%,1/16W,CHIP,GA]
    1  P3V3_STBY          A  @BASEBOARD_FAB2_LIB.BASEBOARD_FAB2(SCH_1):P3V3_STBY
    2  IRQ_BMC_PCH_SMI_LPC_N      B  @BASEBOARD_FAB2_LIB.BASEBOARD_FAB2(SCH_1):IRQ_BMC_PCH_SMI_LPC_N

RES  I303  R8C6   [RES_0402-4.75K,1%,1/16W,CHIP,GA]
    1  P3V3_STBY          A  @BASEBOARD_FAB2_LIB.BASEBOARD_FAB2(SCH_1):P3V3_STBY
    2  FM_BIOS_POST_CMPLT_N      B  @BASEBOARD_FAB2_LIB.BASEBOARD_FAB2(SCH_1):FM_BIOS_POST_CMPLT_N

RES  I327  R8C7   [RES_0402-4.75K,1%,1/16W,CHIP,GA]
    1  P3V3_STBY          A  @BASEBOARD_FAB2_LIB.BASEBOARD_FAB2(SCH_1):P3V3_STBY
    2  FM_SLT_CFG0        B  @BASEBOARD_FAB2_LIB.BASEBOARD_FAB2(SCH_1):FM_SLT_CFG0

RES  I20  R8C9   [RES_0402-4.75K,1%,1/16W,CHIP,GA]
    1  P3V3_STBY          A  @BASEBOARD_FAB2_LIB.BASEBOARD_FAB2(SCH_1):P3V3_STBY
    2  IRQ_SML0_ALERT_N      B  @BASEBOARD_FAB2_LIB.BASEBOARD_FAB2(SCH_1):IRQ_SML0_ALERT_N

RES  I169  R8C11  [RES_0402-20.0,1%,1/16W,CHIP,G2A]
    1  SMB_SMLINK0_STBY_LVC3_SDA_R1      A  @BASEBOARD_FAB2_LIB.BASEBOARD_FAB2(SCH_1):SMB_SMLINK0_STBY_LVC3_SDA_R1
    2  SMB_SMLINK0_STBY_LVC3_SDA      B  @BASEBOARD_FAB2_LIB.BASEBOARD_FAB2(SCH_1):SMB_SMLINK0_STBY_LVC3_SDA

RES  I170  R8C12  [RES_0402-20.0,1%,1/16W,CHIP,G2A]
    1  SMB_SMLINK0_STBY_LVC3_SCL_R1      A  @BASEBOARD_FAB2_LIB.BASEBOARD_FAB2(SCH_1):SMB_SMLINK0_STBY_LVC3_SCL_R1
    2  SMB_SMLINK0_STBY_LVC3_SCL      B  @BASEBOARD_FAB2_LIB.BASEBOARD_FAB2(SCH_1):SMB_SMLINK0_STBY_LVC3_SCL

RES  I168  R8C14  [RES_0402-20.0,1%,1/16W,CHIP,G2A]
    1  SMB_HOST_STBY_LVC3_SCL_R1      A  @BASEBOARD_FAB2_LIB.BASEBOARD_FAB2(SCH_1):SMB_HOST_STBY_LVC3_SCL_R1
    2  SMB_HOST_STBY_LVC3_SCL      B  @BASEBOARD_FAB2_LIB.BASEBOARD_FAB2(SCH_1):SMB_HOST_STBY_LVC3_SCL

RES  I92  R8C15  [RES_0402-2.0K,1%,1/16W,CHIP,G2A]
    2  SMB_HOST_STBY_LVC3_SCL      B  @BASEBOARD_FAB2_LIB.BASEBOARD_FAB2(SCH_1):SMB_HOST_STBY_LVC3_SCL
    1  P3V3_STBY          A  @BASEBOARD_FAB2_LIB.BASEBOARD_FAB2(SCH_1):P3V3_STBY

RES  I91  R8C16  [RES_0402-2.0K,1%,1/16W,CHIP,G2A]
    2  SMB_HOST_STBY_LVC3_SDA      B  @BASEBOARD_FAB2_LIB.BASEBOARD_FAB2(SCH_1):SMB_HOST_STBY_LVC3_SDA
    1  P3V3_STBY          A  @BASEBOARD_FAB2_LIB.BASEBOARD_FAB2(SCH_1):P3V3_STBY

RES  I41  R8C17  [RES_0402-1.00K,1%,1/16W,EMPTY,A]
    1  PU_PCH_TLS_ENABLE_STRAP      A  @BASEBOARD_FAB2_LIB.BASEBOARD_FAB2(SCH_1):PU_PCH_TLS_ENABLE_STRAP
    2  GND                B  @BASEBOARD_FAB2_LIB.BASEBOARD_FAB2(SCH_1):GND

RES  I40  R8C18  [RES_0402-1.00K,1%,1/16W,CHIP,GA]
    2  PU_PCH_TLS_ENABLE_STRAP      B  @BASEBOARD_FAB2_LIB.BASEBOARD_FAB2(SCH_1):PU_PCH_TLS_ENABLE_STRAP
    1  P3V3_STBY          A  @BASEBOARD_FAB2_LIB.BASEBOARD_FAB2(SCH_1):P3V3_STBY

RES  I167  R8C20  [RES_0402-20.0,1%,1/16W,CHIP,G2A]
    1  SMB_HOST_STBY_LVC3_SDA_R1      A  @BASEBOARD_FAB2_LIB.BASEBOARD_FAB2(SCH_1):SMB_HOST_STBY_LVC3_SDA_R1
    2  SMB_HOST_STBY_LVC3_SDA      B  @BASEBOARD_FAB2_LIB.BASEBOARD_FAB2(SCH_1):SMB_HOST_STBY_LVC3_SDA

RES  I148  R8C21  [RES_0402-100.0,1%,1/16W,CHIP,GA]
    2  GND                B  @BASEBOARD_FAB2_LIB.BASEBOARD_FAB2(SCH_1):GND
    1  A_RCOMP_3P3        A  @BASEBOARD_FAB2_LIB.BASEBOARD_FAB2(SCH_1):A_RCOMP_3P3

RES  I125  R8C23  [RES_0402-0.0,5%,1/16W,EMPTY,G2A]
    1  FM_GBE_LOM_DISABLE_N      A  @BASEBOARD_FAB2_LIB.BASEBOARD_FAB2(SCH_1):FM_GBE_LOM_DISABLE_N
    2  FM_10GBE_LOM_DISABLE_N      B  @BASEBOARD_FAB2_LIB.BASEBOARD_FAB2(SCH_1):FM_10GBE_LOM_DISABLE_N

RES  I120  R8C24  [RES_0402-0.0,5%,1/16W,CHIP,G21A]
    1  FM_GBE_LOM_DISABLE_N      A  @BASEBOARD_FAB2_LIB.BASEBOARD_FAB2(SCH_1):FM_GBE_LOM_DISABLE_N
    2  FM_1GB_LOM_DISABLE_N      B  @BASEBOARD_FAB2_LIB.BASEBOARD_FAB2(SCH_1):FM_1GB_LOM_DISABLE_N

RES  I333  R8C25  [RES_0402-4.75K,1%,1/16W,CHIP,GA]
    1  P3V3_STBY          A  @BASEBOARD_FAB2_LIB.BASEBOARD_FAB2(SCH_1):P3V3_STBY
    2  IRQ_PCH_NIC_ALERT_N      B  @BASEBOARD_FAB2_LIB.BASEBOARD_FAB2(SCH_1):IRQ_PCH_NIC_ALERT_N

RES  I35  R8C26  [RES_0402-100.0,1%,1/16W,CHIP,GA]
    2  GND                B  @BASEBOARD_FAB2_LIB.BASEBOARD_FAB2(SCH_1):GND
    1  A_1P8_3P3_RCOMP      A  @BASEBOARD_FAB2_LIB.BASEBOARD_FAB2(SCH_1):A_1P8_3P3_RCOMP

RES  I161  R8D3   [RES_0402-20.0,1%,1/16W,CHIP,G2A]
    1  SMB_SENSOR_STBY_LVC3_SCL_R1      A  @BASEBOARD_FAB2_LIB.BASEBOARD_FAB2(SCH_1):SMB_SENSOR_STBY_LVC3_SCL_R1
    2  SMB_SENSOR_PCH_STBY_LVC3_SCL      B  @BASEBOARD_FAB2_LIB.BASEBOARD_FAB2(SCH_1):SMB_SENSOR_PCH_STBY_LVC3_SCL

RES  I164  R8D4   [RES_0402-20.0,1%,1/16W,CHIP,G2A]
    1  SMB_VR_STBY_LVC3_SCL_R1      A  @BASEBOARD_FAB2_LIB.BASEBOARD_FAB2(SCH_1):SMB_VR_STBY_LVC3_SCL_R1
    2  SMB_VR_STBY_LVC3_SCL      B  @BASEBOARD_FAB2_LIB.BASEBOARD_FAB2(SCH_1):SMB_VR_STBY_LVC3_SCL

RES  I50  R8D5   [RES_0402-1.00K,1%,1/16W,EMPTY,A]
    1  PU_ADR_TIMER_HOLD_OFF_N      A  @BASEBOARD_FAB2_LIB.BASEBOARD_FAB2(SCH_1):PU_ADR_TIMER_HOLD_OFF_N
    2  GND                B  @BASEBOARD_FAB2_LIB.BASEBOARD_FAB2(SCH_1):GND

RES  I162  R8D6   [RES_0402-20.0,1%,1/16W,CHIP,G2A]
    1  SMB_SENSOR_STBY_LVC3_SDA_R1      A  @BASEBOARD_FAB2_LIB.BASEBOARD_FAB2(SCH_1):SMB_SENSOR_STBY_LVC3_SDA_R1
    2  SMB_SENSOR_PCH_STBY_LVC3_SDA      B  @BASEBOARD_FAB2_LIB.BASEBOARD_FAB2(SCH_1):SMB_SENSOR_PCH_STBY_LVC3_SDA

RES  I163  R8D7   [RES_0402-20.0,1%,1/16W,CHIP,G2A]
    1  SMB_VR_STBY_LVC3_SDA_R1      A  @BASEBOARD_FAB2_LIB.BASEBOARD_FAB2(SCH_1):SMB_VR_STBY_LVC3_SDA_R1
    2  SMB_VR_STBY_LVC3_SDA      B  @BASEBOARD_FAB2_LIB.BASEBOARD_FAB2(SCH_1):SMB_VR_STBY_LVC3_SDA

RES  I101  R8D11  [RES_0402-33.2,1%,1/16W,CHIP,G2A]
    2  RMII_PCH_SPRNGVLLE_ARB_OUT_R      B  @BASEBOARD_FAB2_LIB.BASEBOARD_FAB2(SCH_1):RMII_PCH_SPRNGVLLE_ARB_OUT_R
    1  RMII_PCH_SPRNGVLLE_ARB_OUT      A  @BASEBOARD_FAB2_LIB.BASEBOARD_FAB2(SCH_1):RMII_PCH_SPRNGVLLE_ARB_OUT

RES  I52  R8D13  [RES_0402-10.0K,1%,1/16W,CHIP,GA]
    2  PU_ADR_TIMER_HOLD_OFF_N      B  @BASEBOARD_FAB2_LIB.BASEBOARD_FAB2(SCH_1):PU_ADR_TIMER_HOLD_OFF_N
    1  P3V3_STBY          A  @BASEBOARD_FAB2_LIB.BASEBOARD_FAB2(SCH_1):P3V3_STBY

RES  I301  R8D14  [RES_0402-4.75K,1%,1/16W,CHIP,GA]
    1  P3V3_STBY          A  @BASEBOARD_FAB2_LIB.BASEBOARD_FAB2(SCH_1):P3V3_STBY
    2  FP_PWR_ID_LED_N      B  @BASEBOARD_FAB2_LIB.BASEBOARD_FAB2(SCH_1):FP_PWR_ID_LED_N

RES  I88  R8D15  [RES_0402-1.37K,1%,1/16W,CHIP,GA]
    2  SMB_VR_STBY_LVC3_SCL      B  @BASEBOARD_FAB2_LIB.BASEBOARD_FAB2(SCH_1):SMB_VR_STBY_LVC3_SCL
    1  P3V3_STBY          A  @BASEBOARD_FAB2_LIB.BASEBOARD_FAB2(SCH_1):P3V3_STBY

RES  I71  R8D16  [RES_0402-10.0K,1%,1/16W,EMPTY,A]
    2  RMII_PCH_SPRNGVLLE_ARB_OUT      B  @BASEBOARD_FAB2_LIB.BASEBOARD_FAB2(SCH_1):RMII_PCH_SPRNGVLLE_ARB_OUT
    1  P3V3_STBY          A  @BASEBOARD_FAB2_LIB.BASEBOARD_FAB2(SCH_1):P3V3_STBY

RES  I87  R8D17  [RES_0402-1.37K,1%,1/16W,CHIP,GA]
    2  SMB_VR_STBY_LVC3_SDA      B  @BASEBOARD_FAB2_LIB.BASEBOARD_FAB2(SCH_1):SMB_VR_STBY_LVC3_SDA
    1  P3V3_STBY          A  @BASEBOARD_FAB2_LIB.BASEBOARD_FAB2(SCH_1):P3V3_STBY

RES  I8   R8D19  [RES_0402-49.9,1%,1/16W,CHIP,G2A]
    2  SGPIO_PCH_SATA_DOUT0_R      B  @BASEBOARD_FAB2_LIB.BASEBOARD_FAB2(SCH_1):SGPIO_PCH_SATA_DOUT0_R
    1  SGPIO_PCH_SATA_DOUT0      A  @BASEBOARD_FAB2_LIB.BASEBOARD_FAB2(SCH_1):SGPIO_PCH_SATA_DOUT0

RES  I1   R8D20  [RES_0402-49.9,1%,1/16W,CHIP,G2A]
    2  SGPIO_PCH_SATA_LOAD_R      B  @BASEBOARD_FAB2_LIB.BASEBOARD_FAB2(SCH_1):SGPIO_PCH_SATA_LOAD_R
    1  SGPIO_PCH_SATA_LOAD      A  @BASEBOARD_FAB2_LIB.BASEBOARD_FAB2(SCH_1):SGPIO_PCH_SATA_LOAD

RES  I120  R8D21  [RES_0402-1.00K,1%,1/16W,CHIP,GA]
    1  P3V3_STBY          A  @BASEBOARD_FAB2_LIB.BASEBOARD_FAB2(SCH_1):P3V3_STBY
    2  FM_IE_DISABLE_N      B  @BASEBOARD_FAB2_LIB.BASEBOARD_FAB2(SCH_1):FM_IE_DISABLE_N

RES  I386  R8D22  [RES_0402-33.2,1%,1/16W,CHIP,G2A]
    1  RST_BMC_SRST_R2_N      A  @BASEBOARD_FAB2_LIB.BASEBOARD_FAB2(SCH_1):RST_BMC_SRST_R2_N
    2  RST_BMC_SRST_N      B  @BASEBOARD_FAB2_LIB.BASEBOARD_FAB2(SCH_1):RST_BMC_SRST_N

RES  I85  R8D23  [RES_0402-20.0,1%,1/16W,CHIP,G2A]
    1  SMB_SENSOR_STBY_LVC3_SDA_R2      A  @BASEBOARD_FAB2_LIB.BASEBOARD_FAB2(SCH_1):SMB_SENSOR_STBY_LVC3_SDA_R2
    2  SMB_SENSOR_STBY_LVC3_SDA      B  @BASEBOARD_FAB2_LIB.BASEBOARD_FAB2(SCH_1):SMB_SENSOR_STBY_LVC3_SDA

RES  I84  R8D24  [RES_0402-20.0,1%,1/16W,CHIP,G2A]
    2  SMB_SENSOR_STBY_LVC3_SCL_R2      B  @BASEBOARD_FAB2_LIB.BASEBOARD_FAB2(SCH_1):SMB_SENSOR_STBY_LVC3_SCL_R2
    1  SMB_SENSOR_STBY_LVC3_SCL      A  @BASEBOARD_FAB2_LIB.BASEBOARD_FAB2(SCH_1):SMB_SENSOR_STBY_LVC3_SCL

RES  I335  R8D25  [RES_0402-4.75K,1%,1/16W,CHIP,GA]
    2  RST_BMC_SRST_R2_N      B  @BASEBOARD_FAB2_LIB.BASEBOARD_FAB2(SCH_1):RST_BMC_SRST_R2_N
    1  P3V3_STBY          A  @BASEBOARD_FAB2_LIB.BASEBOARD_FAB2(SCH_1):P3V3_STBY

RES  I71  R8D26  [RES_0402-4.75K,1%,1/16W,CHIP,GA]
    1  P3V3_STBY          A  @BASEBOARD_FAB2_LIB.BASEBOARD_FAB2(SCH_1):P3V3_STBY
    2  IRQ_SML1_PMBUS_ALERT_BUF_N      B  @BASEBOARD_FAB2_LIB.BASEBOARD_FAB2(SCH_1):IRQ_SML1_PMBUS_ALERT_BUF_N

RES  I50  R8D27  [RES_0402-1.00K,1%,1/16W,CHIP,GA]
    1  PD_FRU_WP          A  @BASEBOARD_FAB2_LIB.BASEBOARD_FAB2(SCH_1):PD_FRU_WP
    2  GND                B  @BASEBOARD_FAB2_LIB.BASEBOARD_FAB2(SCH_1):GND

RES  I70  R8D28  [RES_0402-1.00K,1%,1/16W,CHIP,GA]
    2  PU_AT24C64_A2      B  @BASEBOARD_FAB2_LIB.BASEBOARD_FAB2(SCH_1):PU_AT24C64_A2
    1  P3V3_STBY          A  @BASEBOARD_FAB2_LIB.BASEBOARD_FAB2(SCH_1):P3V3_STBY

RES  I26  R8D29  [RES_0402-4.75K,1%,1/16W,CHIP,GA]
    1  P3V3_STBY          A  @BASEBOARD_FAB2_LIB.BASEBOARD_FAB2(SCH_1):P3V3_STBY
    2  IRQ_DIMM_SAVE_LVT3      B  @BASEBOARD_FAB2_LIB.BASEBOARD_FAB2(SCH_1):IRQ_DIMM_SAVE_LVT3

RES  I34  R8D30  [RES_0402-10.0K,1%,1/16W,CHIP,GA]
    2  IRQ_DIMM_SAVE_R_N      B  @BASEBOARD_FAB2_LIB.BASEBOARD_FAB2(SCH_1):IRQ_DIMM_SAVE_R_N
    1  IRQ_DIMM_SAVE_N      A  @BASEBOARD_FAB2_LIB.BASEBOARD_FAB2(SCH_1):IRQ_DIMM_SAVE_N

RES  I27  R8D31  [RES_0402-4.75K,1%,1/16W,CHIP,GA]
    1  P3V3_STBY          A  @BASEBOARD_FAB2_LIB.BASEBOARD_FAB2(SCH_1):P3V3_STBY
    2  IRQ_DIMM_SAVE_LVT3_N      B  @BASEBOARD_FAB2_LIB.BASEBOARD_FAB2(SCH_1):IRQ_DIMM_SAVE_LVT3_N

RES  I92  R8D35  [RES_0402-0.0,5%,1/16W,CHIP,G21A]
    2  SPI_PCH_TPM_CS_R_N      B  @BASEBOARD_FAB2_LIB.BASEBOARD_FAB2(SCH_1):SPI_PCH_TPM_CS_R_N
    1  SPI_PCH_TPM_CS_N      A  @BASEBOARD_FAB2_LIB.BASEBOARD_FAB2(SCH_1):SPI_PCH_TPM_CS_N

RES  I388  R8D36  [RES_0402-33.2,1%,1/16W,CHIP,G2A]
    1  RST_BMC_SRST_R2_N      A  @BASEBOARD_FAB2_LIB.BASEBOARD_FAB2(SCH_1):RST_BMC_SRST_R2_N
    2  RST_BMC_DDR3_BUF_IN_N      B  @BASEBOARD_FAB2_LIB.BASEBOARD_FAB2(SCH_1):RST_BMC_DDR3_BUF_IN_N

RES  I115  R8D37  [RES_0402-4.75K,1%,1/16W,CHIP,GA]
    2  GND                B  @BASEBOARD_FAB2_LIB.BASEBOARD_FAB2(SCH_1):GND
    1  A_PG_P5V           A  @BASEBOARD_FAB2_LIB.BASEBOARD_FAB2(SCH_1):A_PG_P5V

RES  I112  R8D38  [RES_0402-100.0K,1%,1/16W,CHIP,A]
    1  P12V               A  @BASEBOARD_FAB2_LIB.BASEBOARD_FAB2(SCH_1):P12V
    2  A_PG_P12V_MAIN      B  @BASEBOARD_FAB2_LIB.BASEBOARD_FAB2(SCH_1):A_PG_P12V_MAIN

RES  I114  R8D39  [RES_0402-49.9K,1%,1/16W,CHIP,GA]
    1  P5V                A  @BASEBOARD_FAB2_LIB.BASEBOARD_FAB2(SCH_1):P5V
    2  A_PG_P5V           B  @BASEBOARD_FAB2_LIB.BASEBOARD_FAB2(SCH_1):A_PG_P5V

RES  I113  R8D40  [RES_0402-3.74K,1%,1/16W,CHIP,GA]
    2  GND                B  @BASEBOARD_FAB2_LIB.BASEBOARD_FAB2(SCH_1):GND
    1  A_PG_P12V_MAIN      A  @BASEBOARD_FAB2_LIB.BASEBOARD_FAB2(SCH_1):A_PG_P12V_MAIN

RES  I120  R8D41  [RES_0402-10.0K,1%,1/16W,CHIP,GA]
    2  PWRGD_P12V_MAIN_R      B  @BASEBOARD_FAB2_LIB.BASEBOARD_FAB2(SCH_1):PWRGD_P12V_MAIN_R
    1  P3V3_STBY          A  @BASEBOARD_FAB2_LIB.BASEBOARD_FAB2(SCH_1):P3V3_STBY

RES  I106  R8D42  [RES_0402-100.0,1%,1/16W,CHIP,GA]
    1  PWRGD_P12V_MAIN_R      A  @BASEBOARD_FAB2_LIB.BASEBOARD_FAB2(SCH_1):PWRGD_P12V_MAIN_R
    2  PWRGD_P12V_MAIN      B  @BASEBOARD_FAB2_LIB.BASEBOARD_FAB2(SCH_1):PWRGD_P12V_MAIN

RES  I93  R8D43  [RES_0402-0.0,5%,1/16W,CHIP,G21A]
    2  FM_CPU0_STL_BRD_OSC_EN      B  @BASEBOARD_FAB2_LIB.BASEBOARD_FAB2(SCH_1):FM_CPU0_STL_BRD_OSC_EN
    1  FM_156M_CPU0_BRD_OSC_EN      A  @BASEBOARD_FAB2_LIB.BASEBOARD_FAB2(SCH_1):FM_156M_CPU0_BRD_OSC_EN

RES  I362  R8D44  [RES_0402-10.0K,1%,1/16W,CHIP,GA]
    1  P3V3_STBY          A  @BASEBOARD_FAB2_LIB.BASEBOARD_FAB2(SCH_1):P3V3_STBY
    2  FM_CPU0_RC_EN      B  @BASEBOARD_FAB2_LIB.BASEBOARD_FAB2(SCH_1):FM_CPU0_RC_EN

RES  I99  R8E1   [RES_0402-0.0,5%,1/16W,CHIP,G21A]
    1  IRQ_SPI_TPM_N_R      A  @BASEBOARD_FAB2_LIB.BASEBOARD_FAB2(SCH_1):IRQ_SPI_TPM_N_R
    2  IRQ_PIRQA_SPI_TPM_N      B  @BASEBOARD_FAB2_LIB.BASEBOARD_FAB2(SCH_1):IRQ_PIRQA_SPI_TPM_N

RES  I89  R8E2   [RES_0402-1.00K,1%,1/16W,CHIP,GA]
    1  XDP_SPI_PCH_MOSI_BOOT_HALT_N      A  @BASEBOARD_FAB2_LIB.BASEBOARD_FAB2(SCH_1):XDP_SPI_PCH_MOSI_BOOT_HALT_N
    2  SPI_PCH_MOSI       B  @BASEBOARD_FAB2_LIB.BASEBOARD_FAB2(SCH_1):SPI_PCH_MOSI

RES  I355  R8E3   [RES_0402-10.0K,1%,1/16W,CHIP,GA]
    1  P3V3_STBY          A  @BASEBOARD_FAB2_LIB.BASEBOARD_FAB2(SCH_1):P3V3_STBY
    2  FM_TPM_PRES_N      B  @BASEBOARD_FAB2_LIB.BASEBOARD_FAB2(SCH_1):FM_TPM_PRES_N

RES  I24  R8E4   [RES_0402-1.00K,1%,1/16W,EMPTY,A]
    1  SPI_PCH_MOSI       A  @BASEBOARD_FAB2_LIB.BASEBOARD_FAB2(SCH_1):SPI_PCH_MOSI
    2  GND                B  @BASEBOARD_FAB2_LIB.BASEBOARD_FAB2(SCH_1):GND

RES  I218  R8E5   [RES_0402-33.2,1%,1/16W,CHIP,G2A]
    1  FM_CTNR_PS_ON_R      A  @BASEBOARD_FAB2_LIB.BASEBOARD_FAB2(SCH_1):FM_CTNR_PS_ON_R
    2  FM_CTNR_PS_ON      B  @BASEBOARD_FAB2_LIB.BASEBOARD_FAB2(SCH_1):FM_CTNR_PS_ON

RES  I21  R8E6   [RES_0402-1.00K,1%,1/16W,EMPTY,A]
    2  SPI_PCH_MOSI       B  @BASEBOARD_FAB2_LIB.BASEBOARD_FAB2(SCH_1):SPI_PCH_MOSI
    1  P3V3_STBY          A  @BASEBOARD_FAB2_LIB.BASEBOARD_FAB2(SCH_1):P3V3_STBY

RES  I90  R8E7   [RES_0402-22.1,1.0%,1/16W,CHIP,A]
    1  PWRGD_P12V_HSC_DLY_R      A  @BASEBOARD_FAB2_LIB.BASEBOARD_FAB2(SCH_1):PWRGD_P12V_HSC_DLY_R
    2  PWRGD_P12V_HSC_DLY      B  @BASEBOARD_FAB2_LIB.BASEBOARD_FAB2(SCH_1):PWRGD_P12V_HSC_DLY

RES  I88  R8E9   [RES_0402-33.2,1%,1/16W,CHIP,G2A]
    2  SPI_PCH_TPM_CLK_R      B  @BASEBOARD_FAB2_LIB.BASEBOARD_FAB2(SCH_1):SPI_PCH_TPM_CLK_R
    1  SPI_PCH_CLK        A  @BASEBOARD_FAB2_LIB.BASEBOARD_FAB2(SCH_1):SPI_PCH_CLK

RES  I95  R8E10  [RES_0402-33.2,1%,1/16W,CHIP,G2A]
    2  SPI_PCH_TPM_MOSI_R      B  @BASEBOARD_FAB2_LIB.BASEBOARD_FAB2(SCH_1):SPI_PCH_TPM_MOSI_R
    1  SPI_PCH_MOSI       A  @BASEBOARD_FAB2_LIB.BASEBOARD_FAB2(SCH_1):SPI_PCH_MOSI

RES  I279  R8E11  [RES_0402-0.0,5%,1/16W,EMPTY,G2A]
    1  FM_MEM_THERM_EVENT_LVT3_N      A  @BASEBOARD_FAB2_LIB.BASEBOARD_FAB2(SCH_1):FM_MEM_THERM_EVENT_LVT3_N
    2  FM_ADR_SMI_GPIO_N      B  @BASEBOARD_FAB2_LIB.BASEBOARD_FAB2(SCH_1):FM_ADR_SMI_GPIO_N

RES  I78  R8E12  [RES_0402-4.75K,1%,1/16W,EMPTY,A]
    1  P3V3_STBY          A  @BASEBOARD_FAB2_LIB.BASEBOARD_FAB2(SCH_1):P3V3_STBY
    2  FM_CTNR_PS_ON      B  @BASEBOARD_FAB2_LIB.BASEBOARD_FAB2(SCH_1):FM_CTNR_PS_ON

RES  I93  R8E13  [RES_0402-33.2,1%,1/16W,CHIP,G2A]
    2  SPI_PCH_TPM_MISO_R      B  @BASEBOARD_FAB2_LIB.BASEBOARD_FAB2(SCH_1):SPI_PCH_TPM_MISO_R
    1  SPI_PCH_MISO       A  @BASEBOARD_FAB2_LIB.BASEBOARD_FAB2(SCH_1):SPI_PCH_MISO

RES  I133  R8E14  [RES_0402-4.75K,1%,1/16W,CHIP,GA]
    2  RST_PLTRST_TOP_SWAP      B  @BASEBOARD_FAB2_LIB.BASEBOARD_FAB2(SCH_1):RST_PLTRST_TOP_SWAP
    1  P3V3_STBY          A  @BASEBOARD_FAB2_LIB.BASEBOARD_FAB2(SCH_1):P3V3_STBY

RES  I140  R8E16  [RES_0402-20.0K,1%,1/16W,CHIP,GA]
    2  GND                B  @BASEBOARD_FAB2_LIB.BASEBOARD_FAB2(SCH_1):GND
    1  FM_BIOS_TOP_SWAP      A  @BASEBOARD_FAB2_LIB.BASEBOARD_FAB2(SCH_1):FM_BIOS_TOP_SWAP

RES  I2   R8E17  [RES_0402-33.2,1%,1/16W,CHIP,G2A]
    1  IRQ_LVC3_WAKE_R_N      A  @BASEBOARD_FAB2_LIB.BASEBOARD_FAB2(SCH_1):IRQ_LVC3_WAKE_R_N
    2  IRQ_LVC3_WAKE_N      B  @BASEBOARD_FAB2_LIB.BASEBOARD_FAB2(SCH_1):IRQ_LVC3_WAKE_N

RES  I9   R8E18  [RES_0402-1.0K,0.1%,1/16W,CHIP,A]
    1  P5V_STBY           A  @BASEBOARD_FAB2_LIB.BASEBOARD_FAB2(SCH_1):P5V_STBY
    2  GND                B  @BASEBOARD_FAB2_LIB.BASEBOARD_FAB2(SCH_1):GND

RES  I361  R8E19  [RES_0402-4.75K,1%,1/16W,EMPTY,A]
    1  P3V3_STBY          A  @BASEBOARD_FAB2_LIB.BASEBOARD_FAB2(SCH_1):P3V3_STBY
    2  FM_BIOS_TOP_SWAP      B  @BASEBOARD_FAB2_LIB.BASEBOARD_FAB2(SCH_1):FM_BIOS_TOP_SWAP

RES  I126  R8E20  [RES_0402-33.2,1%,1/16W,CHIP,G2A]
    1  FM_BIOS_TOP_SWAP_SPKR_R      A  @BASEBOARD_FAB2_LIB.BASEBOARD_FAB2(SCH_1):FM_BIOS_TOP_SWAP_SPKR_R
    2  FM_BIOS_TOP_SWAP_SPKR      B  @BASEBOARD_FAB2_LIB.BASEBOARD_FAB2(SCH_1):FM_BIOS_TOP_SWAP_SPKR

RES  I33  R8E21  [RES_0402-0.0,5%,1/16W,CHIP,G21A]
    1  FM_PE_SPRV_WAKE_N      A  @BASEBOARD_FAB2_LIB.BASEBOARD_FAB2(SCH_1):FM_PE_SPRV_WAKE_N
    2  FM_ALL_WAKE_N      B  @BASEBOARD_FAB2_LIB.BASEBOARD_FAB2(SCH_1):FM_ALL_WAKE_N

RES  I215  R8E22  [RES_0402-4.75K,1%,1/16W,CHIP,GA]
    1  P3V3_STBY          A  @BASEBOARD_FAB2_LIB.BASEBOARD_FAB2(SCH_1):P3V3_STBY
    2  IRQ_BMC_PCH_NMI_STBY_N      B  @BASEBOARD_FAB2_LIB.BASEBOARD_FAB2(SCH_1):IRQ_BMC_PCH_NMI_STBY_N

RES  I3   R8E23  [RES_0402-4.75K,1%,1/16W,CHIP,GA]
    1  PU_TRI_STATE_EN      A  @BASEBOARD_FAB2_LIB.BASEBOARD_FAB2(SCH_1):PU_TRI_STATE_EN
    2  P3V3_STBY          B  @BASEBOARD_FAB2_LIB.BASEBOARD_FAB2(SCH_1):P3V3_STBY

RES  I214  R8E24  [RES_0402-33.2,1%,1/16W,CHIP,G2A]
    2  IRQ_BMC_PCH_NMI_STBY_R_N      B  @BASEBOARD_FAB2_LIB.BASEBOARD_FAB2(SCH_1):IRQ_BMC_PCH_NMI_STBY_R_N
    1  IRQ_BMC_PCH_NMI_STBY_N      A  @BASEBOARD_FAB2_LIB.BASEBOARD_FAB2(SCH_1):IRQ_BMC_PCH_NMI_STBY_N

RES  I144  R8E25  [RES_0402-0.0,5%,1/16W,CHIP,G21A]
    2  VSENSE_P3V3_STBY      B  @BASEBOARD_FAB2_LIB.BASEBOARD_FAB2(SCH_1):VSENSE_P3V3_STBY
    1  P3V3_STBY          A  @BASEBOARD_FAB2_LIB.BASEBOARD_FAB2(SCH_1):P3V3_STBY

RES  I30  R8E26  [RES_0402-0.0,5%,1/16W,CHIP,G21A]
    1  FM_PE_OCP_WAKE_N      A  @BASEBOARD_FAB2_LIB.BASEBOARD_FAB2(SCH_1):FM_PE_OCP_WAKE_N
    2  FM_ALL_WAKE_N      B  @BASEBOARD_FAB2_LIB.BASEBOARD_FAB2(SCH_1):FM_ALL_WAKE_N

RES  I32  R8E27  [RES_0402-0.0,5%,1/16W,CHIP,G21A]
    1  FM_PE_M2_WAKE_N      A  @BASEBOARD_FAB2_LIB.BASEBOARD_FAB2(SCH_1):FM_PE_M2_WAKE_N
    2  FM_ALL_WAKE_N      B  @BASEBOARD_FAB2_LIB.BASEBOARD_FAB2(SCH_1):FM_ALL_WAKE_N

RES  I31  R8E28  [RES_0402-0.0,5%,1/16W,CHIP,G21A]
    1  FM_PE_SLOTX24_WAKE_N      A  @BASEBOARD_FAB2_LIB.BASEBOARD_FAB2(SCH_1):FM_PE_SLOTX24_WAKE_N
    2  FM_ALL_WAKE_N      B  @BASEBOARD_FAB2_LIB.BASEBOARD_FAB2(SCH_1):FM_ALL_WAKE_N

RES  I18  R8E29  [RES_0402-0.0,5%,1/16W,EMPTY,G2A]
    1  FM_PE_BMC_WAKE_N      A  @BASEBOARD_FAB2_LIB.BASEBOARD_FAB2(SCH_1):FM_PE_BMC_WAKE_N
    2  FM_ALL_WAKE_N      B  @BASEBOARD_FAB2_LIB.BASEBOARD_FAB2(SCH_1):FM_ALL_WAKE_N

RES  I23  R8E30  [RES_0402-10.0K,1%,1/16W,CHIP,GA]
    1  P3V3_STBY          A  @BASEBOARD_FAB2_LIB.BASEBOARD_FAB2(SCH_1):P3V3_STBY
    2  FM_ALL_WAKE_N      B  @BASEBOARD_FAB2_LIB.BASEBOARD_FAB2(SCH_1):FM_ALL_WAKE_N

RES  I143  R8E31  [RES_0402-23.2K,1%,1/16W,CHIP,GA]
    2  VSENSE_VOUT_P3V3_STBY      B  @BASEBOARD_FAB2_LIB.BASEBOARD_FAB2(SCH_1):VSENSE_VOUT_P3V3_STBY
    1  VSENSE_P3V3_STBY      A  @BASEBOARD_FAB2_LIB.BASEBOARD_FAB2(SCH_1):VSENSE_P3V3_STBY

RES  I385  R8E32  [RES_0402-4.75K,1%,1/16W,CHIP,GA]
    1  P3V3_STBY          A  @BASEBOARD_FAB2_LIB.BASEBOARD_FAB2(SCH_1):P3V3_STBY
    2  FP_NMI_BTN_OUT_R_N      B  @BASEBOARD_FAB2_LIB.BASEBOARD_FAB2(SCH_1):FP_NMI_BTN_OUT_R_N

RES  I91  R8E33  [RES_0402-0.0,5%,1/16W,CHIP,G21A]
    2  VR_P5V_STBY_EN      B  @BASEBOARD_FAB2_LIB.BASEBOARD_FAB2(SCH_1):VR_P5V_STBY_EN
    1  PWRGD_P12V_HSC_DLY      A  @BASEBOARD_FAB2_LIB.BASEBOARD_FAB2(SCH_1):PWRGD_P12V_HSC_DLY

RES  I142  R8E34  [RES_0402-10.0K,1%,1/16W,CHIP,GA]
    1  VSENSE_VOUT_P3V3_STBY      A  @BASEBOARD_FAB2_LIB.BASEBOARD_FAB2(SCH_1):VSENSE_VOUT_P3V3_STBY
    2  AGND_P3V3_STBY      B  @BASEBOARD_FAB2_LIB.BASEBOARD_FAB2(SCH_1):AGND_P3V3_STBY

RES  I127  R8E35  [RES_0402-0.0,5%,1/16W,CHIP,G21A]
    2  VR_P3V3_STBY_BOOT_R      B  @BASEBOARD_FAB2_LIB.BASEBOARD_FAB2(SCH_1):VR_P3V3_STBY_BOOT_R
    1  VR_P3V3_STBY_BOOT      A  @BASEBOARD_FAB2_LIB.BASEBOARD_FAB2(SCH_1):VR_P3V3_STBY_BOOT

RES  I28  R8E36  [RES_0402-10.0K,1%,1/16W,CHIP,GA]
    1  P3V3_STBY          A  @BASEBOARD_FAB2_LIB.BASEBOARD_FAB2(SCH_1):P3V3_STBY
    2  FM_PE_SLOTX24_WAKE_N      B  @BASEBOARD_FAB2_LIB.BASEBOARD_FAB2(SCH_1):FM_PE_SLOTX24_WAKE_N

RES  I78  R8E37  [RES_0402-0.0,5%,1/16W,CHIP,G21A]
    1  VR_P5V_STBY_VSENSE_R      A  @BASEBOARD_FAB2_LIB.BASEBOARD_FAB2(SCH_1):VR_P5V_STBY_VSENSE_R
    2  P5V_STBY           B  @BASEBOARD_FAB2_LIB.BASEBOARD_FAB2(SCH_1):P5V_STBY

RES  I140  R8E38  [RES_0402-0.0,5%,1/16W,CHIP,G21A]
    1  VSENSE_RGND_P3V3_STBY      A  @BASEBOARD_FAB2_LIB.BASEBOARD_FAB2(SCH_1):VSENSE_RGND_P3V3_STBY
    2  AGND_P3V3_STBY      B  @BASEBOARD_FAB2_LIB.BASEBOARD_FAB2(SCH_1):AGND_P3V3_STBY

RES  I54  R8E39  [RES_0402-24.9K,1%,1/16W,CHIP,GA]
    2  VR_P5V_STBY_RC_COMP      B  @BASEBOARD_FAB2_LIB.BASEBOARD_FAB2(SCH_1):VR_P5V_STBY_RC_COMP
    1  VR_P5V_STBY_COMP      A  @BASEBOARD_FAB2_LIB.BASEBOARD_FAB2(SCH_1):VR_P5V_STBY_COMP

RES  I177  R8E40  [RES_0402-100.0K,1%,1/16W,EMPTYA]
    2  VR_P3V3_STBY_EN      B  @BASEBOARD_FAB2_LIB.BASEBOARD_FAB2(SCH_1):VR_P3V3_STBY_EN
    1  P3V3_STBY          A  @BASEBOARD_FAB2_LIB.BASEBOARD_FAB2(SCH_1):P3V3_STBY

RES  I111  R8F1   [RES_0402-10.0K,1%,1/16W,EMPTY,A]
    1  PWRGD_P5V_STBY      A  @BASEBOARD_FAB2_LIB.BASEBOARD_FAB2(SCH_1):PWRGD_P5V_STBY
    2  GND                B  @BASEBOARD_FAB2_LIB.BASEBOARD_FAB2(SCH_1):GND

RES  I176  R8F2   [RES_0402-0.0,5%,1/16W,CHIP,G21A]
    2  VR_P3V3_STBY_EN      B  @BASEBOARD_FAB2_LIB.BASEBOARD_FAB2(SCH_1):VR_P3V3_STBY_EN
    1  PWRGD_P5V_STBY      A  @BASEBOARD_FAB2_LIB.BASEBOARD_FAB2(SCH_1):PWRGD_P5V_STBY

RES  I148  R8F3   [RES_0402-2.2,5%,1/16W,EMPTY,G2A]
    1  VR_P3V3_STBY_SNUB      A  @BASEBOARD_FAB2_LIB.BASEBOARD_FAB2(SCH_1):VR_P3V3_STBY_SNUB
    2  GND                B  @BASEBOARD_FAB2_LIB.BASEBOARD_FAB2(SCH_1):GND

RES  I117  R8F5   [RES_0402-1.00K,1%,1/16W,CHIP,GA]
    2  PWRGD_P3V3_STBY_R      B  @BASEBOARD_FAB2_LIB.BASEBOARD_FAB2(SCH_1):PWRGD_P3V3_STBY_R
    1  P3V3_STBY          A  @BASEBOARD_FAB2_LIB.BASEBOARD_FAB2(SCH_1):P3V3_STBY

RES  I119  R8F6   [RES_0402-0.0,5%,1/16W,CHIP,G21A]
    2  SPI_PCH_MISO_R      B  @BASEBOARD_FAB2_LIB.BASEBOARD_FAB2(SCH_1):SPI_PCH_MISO_R
    1  SPI_PCH_MISO       A  @BASEBOARD_FAB2_LIB.BASEBOARD_FAB2(SCH_1):SPI_PCH_MISO

RES  I167  R8F7   [RES_0402-33.2,1%,1/16W,CHIP,G2A]
    1  SPI_SWITCH_CLK      A  @BASEBOARD_FAB2_LIB.BASEBOARD_FAB2(SCH_1):SPI_SWITCH_CLK
    2  SPI_CLK_R1         B  @BASEBOARD_FAB2_LIB.BASEBOARD_FAB2(SCH_1):SPI_CLK_R1

RES  I166  R8F8   [RES_0402-33.2,1%,1/16W,CHIP,G2A]
    1  SPI_SWITCH_CLK      A  @BASEBOARD_FAB2_LIB.BASEBOARD_FAB2(SCH_1):SPI_SWITCH_CLK
    2  SPI_CLK_R0         B  @BASEBOARD_FAB2_LIB.BASEBOARD_FAB2(SCH_1):SPI_CLK_R0

RES  I106  R8F9   [RES_0402-64.9K,1%,1/16W,CHIP,GA]
    1  VR_P3V3_STBY_OCSELECT      A  @BASEBOARD_FAB2_LIB.BASEBOARD_FAB2(SCH_1):VR_P3V3_STBY_OCSELECT
    2  AGND_P3V3_STBY      B  @BASEBOARD_FAB2_LIB.BASEBOARD_FAB2(SCH_1):AGND_P3V3_STBY

RES  I171  R8F10  [RES_0402-22.1,1.0%,1/16W,CHIP,A]
    1  PWRGD_P3V3_STBY_R      A  @BASEBOARD_FAB2_LIB.BASEBOARD_FAB2(SCH_1):PWRGD_P3V3_STBY_R
    2  PWRGD_P3V3_STBY      B  @BASEBOARD_FAB2_LIB.BASEBOARD_FAB2(SCH_1):PWRGD_P3V3_STBY

RES  I146  R8F11  [RES_0402-0.0,5%,1/16W,CHIP,G21A]
    1  GND                A  @BASEBOARD_FAB2_LIB.BASEBOARD_FAB2(SCH_1):GND
    2  AGND_P3V3_STBY      B  @BASEBOARD_FAB2_LIB.BASEBOARD_FAB2(SCH_1):AGND_P3V3_STBY

RES  I13  R8F12  [RES_0402-33.2,1%,1/16W,CHIP,G2A]
    2  SPI_BMC_BT_DI_R      B  @BASEBOARD_FAB2_LIB.BASEBOARD_FAB2(SCH_1):SPI_BMC_BT_DI_R
    1  SPI_BMC_BT_DI      A  @BASEBOARD_FAB2_LIB.BASEBOARD_FAB2(SCH_1):SPI_BMC_BT_DI

RES  I23  R8F13  [RES_0402-4.75K,1%,1/16W,CHIP,GA]
    2  SPI_BMC_BT_CS_N      B  @BASEBOARD_FAB2_LIB.BASEBOARD_FAB2(SCH_1):SPI_BMC_BT_CS_N
    1  P3V3_STBY          A  @BASEBOARD_FAB2_LIB.BASEBOARD_FAB2(SCH_1):P3V3_STBY

RES  I9   R8F14  [RES_0402-4.75K,1%,1/16W,CHIP,GA]
    2  PU_SPI_BMC_BT_HOLD_N      B  @BASEBOARD_FAB2_LIB.BASEBOARD_FAB2(SCH_1):PU_SPI_BMC_BT_HOLD_N
    1  P3V3_STBY          A  @BASEBOARD_FAB2_LIB.BASEBOARD_FAB2(SCH_1):P3V3_STBY

RES  I8   R8F16  [RES_0402-4.75K,1%,1/16W,EMPTY,A]
    2  PU_SPI_FLASH_RESET_2_N      B  @BASEBOARD_FAB2_LIB.BASEBOARD_FAB2(SCH_1):PU_SPI_FLASH_RESET_2_N
    1  P3V3_STBY          A  @BASEBOARD_FAB2_LIB.BASEBOARD_FAB2(SCH_1):P3V3_STBY

RES  I105  R8F18  [RES_0402-0.0,5%,1/16W,CHIP,G21A]
    1  P3E_PCH_RX_0_DP      A  @BASEBOARD_FAB2_LIB.BASEBOARD_FAB2(SCH_1):P3E_PCH_RX_0_DP
    2  P3E_PCH_M2_SATA6G_RX_R_DP      B  @BASEBOARD_FAB2_LIB.BASEBOARD_FAB2(SCH_1):P3E_PCH_M2_SATA6G_RX_R_DP

RES  I106  R8F21  [RES_0402-0.0,5%,1/16W,CHIP,G21A]
    1  P3E_PCH_RX_0_DN      A  @BASEBOARD_FAB2_LIB.BASEBOARD_FAB2(SCH_1):P3E_PCH_RX_0_DN
    2  P3E_PCH_M2_SATA6G_RX_R_DN      B  @BASEBOARD_FAB2_LIB.BASEBOARD_FAB2(SCH_1):P3E_PCH_M2_SATA6G_RX_R_DN

RES  I296  R8F23  [RES_0402-2.21K,1%,1/16W,CHIP,GA]
    1  P3V3_STBY          A  @BASEBOARD_FAB2_LIB.BASEBOARD_FAB2(SCH_1):P3V3_STBY
    2  IRQ_MEZZ_LAN_ALERT_N      B  @BASEBOARD_FAB2_LIB.BASEBOARD_FAB2(SCH_1):IRQ_MEZZ_LAN_ALERT_N

RES  I316  R8F24  [RES_0402-4.75K,1%,1/16W,CHIP,GA]
    1  P3V3_STBY          A  @BASEBOARD_FAB2_LIB.BASEBOARD_FAB2(SCH_1):P3V3_STBY
    2  FP_NMI_BTN_N       B  @BASEBOARD_FAB2_LIB.BASEBOARD_FAB2(SCH_1):FP_NMI_BTN_N

RES  I28  R8F25  [RES_0402-475.0,1%,1/16W,CHIP,GA]
    2  GND                B  @BASEBOARD_FAB2_LIB.BASEBOARD_FAB2(SCH_1):GND
    1  A_COMP_CKMNG       A  @BASEBOARD_FAB2_LIB.BASEBOARD_FAB2(SCH_1):A_COMP_CKMNG

RES  I211  R8F26  [RES_0402-10.0K,1%,1/16W,CHIP,GA]
    1  P3V3_STBY          A  @BASEBOARD_FAB2_LIB.BASEBOARD_FAB2(SCH_1):P3V3_STBY
    2  FM_PCH_PWRBTN_R_N      B  @BASEBOARD_FAB2_LIB.BASEBOARD_FAB2(SCH_1):FM_PCH_PWRBTN_R_N

RES  I129  R8F27  [RES_0402-22.1,1.0%,1/16W,CHIP,A]
    1  CLK_32K_SUSCLK_PLD_R      A  @BASEBOARD_FAB2_LIB.BASEBOARD_FAB2(SCH_1):CLK_32K_SUSCLK_PLD_R
    2  CLK_32K_SUSCLK_PLD      B  @BASEBOARD_FAB2_LIB.BASEBOARD_FAB2(SCH_1):CLK_32K_SUSCLK_PLD

RES  I125  R8F28  [RES_0402-22.1,1.0%,1/16W,CHIP,A]
    1  RMII_BMC_OCP_TXD1_R      A  @BASEBOARD_FAB2_LIB.BASEBOARD_FAB2(SCH_1):RMII_BMC_OCP_TXD1_R
    2  RMII_BMC_OCP_TXD1      B  @BASEBOARD_FAB2_LIB.BASEBOARD_FAB2(SCH_1):RMII_BMC_OCP_TXD1

RES  I20  R8F29  [RES_0402-33.2,1%,1/16W,CHIP,G2A]
    1  CLK_25M_BMC_R      A  @BASEBOARD_FAB2_LIB.BASEBOARD_FAB2(SCH_1):CLK_25M_BMC_R
    2  CLK_25M_BMC        B  @BASEBOARD_FAB2_LIB.BASEBOARD_FAB2(SCH_1):CLK_25M_BMC

RES  I154  R8F30  [RES_0402-22.1,1.0%,1/16W,CHIP,A]
    1  RMII_BMC_OCP_TXEN_R      A  @BASEBOARD_FAB2_LIB.BASEBOARD_FAB2(SCH_1):RMII_BMC_OCP_TXEN_R
    2  RMII_BMC_OCP_TXEN      B  @BASEBOARD_FAB2_LIB.BASEBOARD_FAB2(SCH_1):RMII_BMC_OCP_TXEN

RES  I126  R8F31  [RES_0402-22.1,1.0%,1/16W,CHIP,A]
    1  RMII_BMC_OCP_TXD0_R      A  @BASEBOARD_FAB2_LIB.BASEBOARD_FAB2(SCH_1):RMII_BMC_OCP_TXD0_R
    2  RMII_BMC_OCP_TXD0      B  @BASEBOARD_FAB2_LIB.BASEBOARD_FAB2(SCH_1):RMII_BMC_OCP_TXD0

RES  I118  R8F32  [RES_0402-10.0K,1%,1/16W,CHIP,GA]
    2  RMII_BMC_PCH_SPRNGVLLE_TXD1      B  @BASEBOARD_FAB2_LIB.BASEBOARD_FAB2(SCH_1):RMII_BMC_PCH_SPRNGVLLE_TXD1
    1  P3V3_STBY          A  @BASEBOARD_FAB2_LIB.BASEBOARD_FAB2(SCH_1):P3V3_STBY

RES  I116  R8F33  [RES_0402-22.1,1.0%,1/16W,CHIP,A]
    1  RMII_BMC_SPRNGVLLE_TXEN_R      A  @BASEBOARD_FAB2_LIB.BASEBOARD_FAB2(SCH_1):RMII_BMC_SPRNGVLLE_TXEN_R
    2  RMII_BMC_PCH_SPRNGVLLE_TXEN      B  @BASEBOARD_FAB2_LIB.BASEBOARD_FAB2(SCH_1):RMII_BMC_PCH_SPRNGVLLE_TXEN

RES  I22  R8F34  [RES_0402-4.75K,1%,1/16W,CHIP,GA]
    2  PU_SPI_BMC_BT_WP_N      B  @BASEBOARD_FAB2_LIB.BASEBOARD_FAB2(SCH_1):PU_SPI_BMC_BT_WP_N
    1  P3V3_STBY          A  @BASEBOARD_FAB2_LIB.BASEBOARD_FAB2(SCH_1):P3V3_STBY

RES  I24  R8F35  [RES_0402-1.00K,1%,1/16W,EMPTY,A]
    1  PU_SPI_BMC_BT_WP_N      A  @BASEBOARD_FAB2_LIB.BASEBOARD_FAB2(SCH_1):PU_SPI_BMC_BT_WP_N
    2  GND                B  @BASEBOARD_FAB2_LIB.BASEBOARD_FAB2(SCH_1):GND

RES  I136  R8F36  [RES_0402-10.0K,1%,1/16W,CHIP,GA]
    2  PU_M2_CLK_REQ_N      B  @BASEBOARD_FAB2_LIB.BASEBOARD_FAB2(SCH_1):PU_M2_CLK_REQ_N
    1  P3V3               A  @BASEBOARD_FAB2_LIB.BASEBOARD_FAB2(SCH_1):P3V3

RES  I131  R8F37  [RES_0402-0.0,5%,1/16W,EMPTY,G2A]
    2  FM_CPU_ERR0_PCH_N      B  @BASEBOARD_FAB2_LIB.BASEBOARD_FAB2(SCH_1):FM_CPU_ERR0_PCH_N
    1  FM_CPU_ERR0_LVT3_N      A  @BASEBOARD_FAB2_LIB.BASEBOARD_FAB2(SCH_1):FM_CPU_ERR0_LVT3_N

RES  I119  R8F38  [RES_0402-0.0,5%,1/16W,CHIP,G21A]
    1  FM_CPU_ERR0_LVT3_N      A  @BASEBOARD_FAB2_LIB.BASEBOARD_FAB2(SCH_1):FM_CPU_ERR0_LVT3_N
    2  FM_CPU_ERR0_LVT3_BMC_N      B  @BASEBOARD_FAB2_LIB.BASEBOARD_FAB2(SCH_1):FM_CPU_ERR0_LVT3_BMC_N

RES  I133  R8G1   [RES_0402-33.2,1%,1/16W,CHIP,G2A]
    1  CLK_50M_CKMNG_BMC_2_R      A  @BASEBOARD_FAB2_LIB.BASEBOARD_FAB2(SCH_1):CLK_50M_CKMNG_BMC_2_R
    2  CLK_50M_CKMNG_BMC_2      B  @BASEBOARD_FAB2_LIB.BASEBOARD_FAB2(SCH_1):CLK_50M_CKMNG_BMC_2

RES  I267  R8G2   [RES_0402-4.75K,1%,1/16W,CHIP,GA]
    1  P3V3_STBY          A  @BASEBOARD_FAB2_LIB.BASEBOARD_FAB2(SCH_1):P3V3_STBY
    2  FM_PCH_PWRBTN_OUT_N      B  @BASEBOARD_FAB2_LIB.BASEBOARD_FAB2(SCH_1):FM_PCH_PWRBTN_OUT_N

RES  I210  R8G3   [RES_0402-2.26K,1.0%,1/16W,EMPTA]
    2  SMB_OCP_LAN_STBY_LVC3_SCL_R      B  @BASEBOARD_FAB2_LIB.BASEBOARD_FAB2(SCH_1):SMB_OCP_LAN_STBY_LVC3_SCL_R
    1  P3V3_STBY          A  @BASEBOARD_FAB2_LIB.BASEBOARD_FAB2(SCH_1):P3V3_STBY

RES  I229  R8G4   [RES_0402-20.0,1%,1/16W,CHIP,G2A]
    1  SMB_OCP_LAN_STBY_LVC3_SCL_R      A  @BASEBOARD_FAB2_LIB.BASEBOARD_FAB2(SCH_1):SMB_OCP_LAN_STBY_LVC3_SCL_R
    2  SMB_OCP_LAN_STBY_LVC3_SCL      B  @BASEBOARD_FAB2_LIB.BASEBOARD_FAB2(SCH_1):SMB_OCP_LAN_STBY_LVC3_SCL

RES  I228  R8G5   [RES_0402-20.0,1%,1/16W,CHIP,G2A]
    1  SMB_OCP_LAN_STBY_LVC3_SDA_R      A  @BASEBOARD_FAB2_LIB.BASEBOARD_FAB2(SCH_1):SMB_OCP_LAN_STBY_LVC3_SDA_R
    2  SMB_OCP_LAN_STBY_LVC3_SDA      B  @BASEBOARD_FAB2_LIB.BASEBOARD_FAB2(SCH_1):SMB_OCP_LAN_STBY_LVC3_SDA

RES  I212  R8G6   [RES_0402-2.26K,1.0%,1/16W,EMPTA]
    2  SMB_OCP_LAN_STBY_LVC3_SDA_R      B  @BASEBOARD_FAB2_LIB.BASEBOARD_FAB2(SCH_1):SMB_OCP_LAN_STBY_LVC3_SDA_R
    1  P3V3_STBY          A  @BASEBOARD_FAB2_LIB.BASEBOARD_FAB2(SCH_1):P3V3_STBY

RES  I18  R8G7   [RES_0402-0.0,5%,1/16W,CHIP,G21A]
    2  JTAG_TDI           B  @BASEBOARD_FAB2_LIB.BASEBOARD_FAB2(SCH_1):JTAG_TDI
    1  JTAG_PLD_TDI       A  @BASEBOARD_FAB2_LIB.BASEBOARD_FAB2(SCH_1):JTAG_PLD_TDI

RES  I17  R8G8   [RES_0402-0.0,5%,1/16W,CHIP,G21A]
    2  JTAG_TDI           B  @BASEBOARD_FAB2_LIB.BASEBOARD_FAB2(SCH_1):JTAG_TDI
    1  JTAG_BMC_TDI       A  @BASEBOARD_FAB2_LIB.BASEBOARD_FAB2(SCH_1):JTAG_BMC_TDI

RES  I9   R8G9   [RES_0402-0.0,5%,1/16W,EMPTY,G2A]
    2  JTAG_TRST_N        B  @BASEBOARD_FAB2_LIB.BASEBOARD_FAB2(SCH_1):JTAG_TRST_N
    1  JTAG_PCH_GBE_TRST_N      A  @BASEBOARD_FAB2_LIB.BASEBOARD_FAB2(SCH_1):JTAG_PCH_GBE_TRST_N

RES  I7   R8G10  [RES_0402-0.0,5%,1/16W,CHIP,G21A]
    2  JTAG_TRST_N        B  @BASEBOARD_FAB2_LIB.BASEBOARD_FAB2(SCH_1):JTAG_TRST_N
    1  JTAG_BMC_TRST_N      A  @BASEBOARD_FAB2_LIB.BASEBOARD_FAB2(SCH_1):JTAG_BMC_TRST_N

RES  I19  R8G11  [RES_0402-0.0,5%,1/16W,EMPTY,G2A]
    2  JTAG_TMS           B  @BASEBOARD_FAB2_LIB.BASEBOARD_FAB2(SCH_1):JTAG_TMS
    1  JTAG_PCH_PLD_TMS      A  @BASEBOARD_FAB2_LIB.BASEBOARD_FAB2(SCH_1):JTAG_PCH_PLD_TMS

RES  I21  R8G12  [RES_0402-0.0,5%,1/16W,EMPTY,G2A]
    2  JTAG_TMS           B  @BASEBOARD_FAB2_LIB.BASEBOARD_FAB2(SCH_1):JTAG_TMS
    1  JTAG_PCH_GBE_TMS      A  @BASEBOARD_FAB2_LIB.BASEBOARD_FAB2(SCH_1):JTAG_PCH_GBE_TMS

RES  I23  R8G13  [RES_0402-0.0,5%,1/16W,CHIP,G21A]
    2  JTAG_TMS           B  @BASEBOARD_FAB2_LIB.BASEBOARD_FAB2(SCH_1):JTAG_TMS
    1  JTAG_PLD_TMS       A  @BASEBOARD_FAB2_LIB.BASEBOARD_FAB2(SCH_1):JTAG_PLD_TMS

RES  I20  R8G14  [RES_0402-0.0,5%,1/16W,CHIP,G21A]
    2  JTAG_TMS           B  @BASEBOARD_FAB2_LIB.BASEBOARD_FAB2(SCH_1):JTAG_TMS
    1  JTAG_BMC_TMS       A  @BASEBOARD_FAB2_LIB.BASEBOARD_FAB2(SCH_1):JTAG_BMC_TMS

RES  I24  R8G15  [RES_0402-0.0,5%,1/16W,EMPTY,G2A]
    2  JTAG_TCK           B  @BASEBOARD_FAB2_LIB.BASEBOARD_FAB2(SCH_1):JTAG_TCK
    1  JTAG_PCH_GBE_CLK      A  @BASEBOARD_FAB2_LIB.BASEBOARD_FAB2(SCH_1):JTAG_PCH_GBE_CLK

RES  I22  R8G16  [RES_0402-0.0,5%,1/16W,EMPTY,G2A]
    2  JTAG_TCK           B  @BASEBOARD_FAB2_LIB.BASEBOARD_FAB2(SCH_1):JTAG_TCK
    1  JTAG_PCH_PLD_TCK      A  @BASEBOARD_FAB2_LIB.BASEBOARD_FAB2(SCH_1):JTAG_PCH_PLD_TCK

RES  I25  R8G17  [RES_0402-0.0,5%,1/16W,CHIP,G21A]
    2  JTAG_TCK           B  @BASEBOARD_FAB2_LIB.BASEBOARD_FAB2(SCH_1):JTAG_TCK
    1  JTAG_BMC_TCK       A  @BASEBOARD_FAB2_LIB.BASEBOARD_FAB2(SCH_1):JTAG_BMC_TCK

RES  I26  R8G18  [RES_0402-0.0,5%,1/16W,CHIP,G21A]
    2  JTAG_TCK           B  @BASEBOARD_FAB2_LIB.BASEBOARD_FAB2(SCH_1):JTAG_TCK
    1  JTAG_PLD_TCK       A  @BASEBOARD_FAB2_LIB.BASEBOARD_FAB2(SCH_1):JTAG_PLD_TCK

RES  I64  R8G19  [RES_0402-0.0,5%,1/16W,CHIP,G21A]
    2  JTAG_TDI_R         B  @BASEBOARD_FAB2_LIB.BASEBOARD_FAB2(SCH_1):JTAG_TDI_R
    1  JTAG_TDI           A  @BASEBOARD_FAB2_LIB.BASEBOARD_FAB2(SCH_1):JTAG_TDI

RES  I50  R8G20  [RES_0402-10.0K,1%,1/16W,CHIP,GA]
    1  P3V3_STBY          A  @BASEBOARD_FAB2_LIB.BASEBOARD_FAB2(SCH_1):P3V3_STBY
    2  JTAG_TMS_R         B  @BASEBOARD_FAB2_LIB.BASEBOARD_FAB2(SCH_1):JTAG_TMS_R

RES  I65  R8G21  [RES_0402-0.0,5%,1/16W,CHIP,G21A]
    2  JTAG_TMS_R         B  @BASEBOARD_FAB2_LIB.BASEBOARD_FAB2(SCH_1):JTAG_TMS_R
    1  JTAG_TMS           A  @BASEBOARD_FAB2_LIB.BASEBOARD_FAB2(SCH_1):JTAG_TMS

RES  I66  R8G22  [RES_0402-0.0,5%,1/16W,CHIP,G21A]
    2  JTAG_TCK_R         B  @BASEBOARD_FAB2_LIB.BASEBOARD_FAB2(SCH_1):JTAG_TCK_R
    1  JTAG_TCK           A  @BASEBOARD_FAB2_LIB.BASEBOARD_FAB2(SCH_1):JTAG_TCK

RES  I56  R8G23  [RES_0402-4.75K,1%,1/16W,CHIP,GA]
    1  JTAG_TCK_R         A  @BASEBOARD_FAB2_LIB.BASEBOARD_FAB2(SCH_1):JTAG_TCK_R
    2  GND                B  @BASEBOARD_FAB2_LIB.BASEBOARD_FAB2(SCH_1):GND

RES  I132  R8G24  [RES_0402-33.2,1%,1/16W,CHIP,G2A]
    1  CLK_50M_CKMNG_PCH_10GBE_R      A  @BASEBOARD_FAB2_LIB.BASEBOARD_FAB2(SCH_1):CLK_50M_CKMNG_PCH_10GBE_R
    2  CLK_50M_CKMNG_PCH_10GBE      B  @BASEBOARD_FAB2_LIB.BASEBOARD_FAB2(SCH_1):CLK_50M_CKMNG_PCH_10GBE

RES  I131  R8G25  [RES_0402-33.2,1%,1/16W,CHIP,G2A]
    1  CLK_50M_CKMNG_SPRVLLE_R      A  @BASEBOARD_FAB2_LIB.BASEBOARD_FAB2(SCH_1):CLK_50M_CKMNG_SPRVLLE_R
    2  CLK_50M_CKMNG_SPRVLLE      B  @BASEBOARD_FAB2_LIB.BASEBOARD_FAB2(SCH_1):CLK_50M_CKMNG_SPRVLLE

RES  I157  R8N1   [RES_0402-1.8K,1%,1/16W,CHIP,G2A]
    1  P3V3_STBY          A  @BASEBOARD_FAB2_LIB.BASEBOARD_FAB2(SCH_1):P3V3_STBY
    2  FM_CPU1_PROC_ID1      B  @BASEBOARD_FAB2_LIB.BASEBOARD_FAB2(SCH_1):FM_CPU1_PROC_ID1

RES  I161  R8N2   [RES_0402-10.0K,1%,1/16W,CHIP,GA]
    1  P3V3_STBY          A  @BASEBOARD_FAB2_LIB.BASEBOARD_FAB2(SCH_1):P3V3_STBY
    2  FM_CPU1_PKGID0      B  @BASEBOARD_FAB2_LIB.BASEBOARD_FAB2(SCH_1):FM_CPU1_PKGID0

RES  I159  R8N3   [RES_0402-10.0K,1%,1/16W,CHIP,GA]
    1  P3V3_STBY          A  @BASEBOARD_FAB2_LIB.BASEBOARD_FAB2(SCH_1):P3V3_STBY
    2  FM_CPU1_PKGID2      B  @BASEBOARD_FAB2_LIB.BASEBOARD_FAB2(SCH_1):FM_CPU1_PKGID2

RES  I158  R8N4   [RES_0402-1.8K,1%,1/16W,CHIP,G2A]
    1  P3V3_STBY          A  @BASEBOARD_FAB2_LIB.BASEBOARD_FAB2(SCH_1):P3V3_STBY
    2  FM_CPU1_PROC_ID0      B  @BASEBOARD_FAB2_LIB.BASEBOARD_FAB2(SCH_1):FM_CPU1_PROC_ID0

RES  I160  R8N5   [RES_0402-10.0K,1%,1/16W,CHIP,GA]
    1  P3V3_STBY          A  @BASEBOARD_FAB2_LIB.BASEBOARD_FAB2(SCH_1):P3V3_STBY
    2  FM_CPU1_PKGID1      B  @BASEBOARD_FAB2_LIB.BASEBOARD_FAB2(SCH_1):FM_CPU1_PKGID1

RES  I85  R8P1   [RES_0402-49.9,1%,1/16W,CHIP,G2A]
    1  PD_CPU1_TEST14      A  @BASEBOARD_FAB2_LIB.BASEBOARD_FAB2(SCH_1):PD_CPU1_TEST14
    2  GND                B  @BASEBOARD_FAB2_LIB.BASEBOARD_FAB2(SCH_1):GND

RES  I86  R8P2   [RES_0402-49.9,1%,1/16W,CHIP,G2A]
    1  PD_CPU1_TEST13      A  @BASEBOARD_FAB2_LIB.BASEBOARD_FAB2(SCH_1):PD_CPU1_TEST13
    2  GND                B  @BASEBOARD_FAB2_LIB.BASEBOARD_FAB2(SCH_1):GND

RES  I173  R8P3   [RES_0402-49.9,1%,1/16W,CHIP,G2A]
    1  PD_CPU1_RSVD_TEST_2      A  @BASEBOARD_FAB2_LIB.BASEBOARD_FAB2(SCH_1):PD_CPU1_RSVD_TEST_2
    2  GND                B  @BASEBOARD_FAB2_LIB.BASEBOARD_FAB2(SCH_1):GND

RES  I174  R8R1   [RES_0402-49.9,1%,1/16W,CHIP,G2A]
    1  PD_CPU1_RSVD_TEST_1      A  @BASEBOARD_FAB2_LIB.BASEBOARD_FAB2(SCH_1):PD_CPU1_RSVD_TEST_1
    2  GND                B  @BASEBOARD_FAB2_LIB.BASEBOARD_FAB2(SCH_1):GND

RES  I95  R9A1   [RES_0402-1.00K,1%,1/16W,EMPTY,A]
    2  XDP_CPU_TCK_BUF      B  @BASEBOARD_FAB2_LIB.BASEBOARD_FAB2(SCH_1):XDP_CPU_TCK_BUF
    1  P3V3               A  @BASEBOARD_FAB2_LIB.BASEBOARD_FAB2(SCH_1):P3V3

RES  I83  R9A2   [RES_0402-33.2,1%,1/16W,EMPTY,GA]
    1  XDP_PCH_CPU_TCK0      A  @BASEBOARD_FAB2_LIB.BASEBOARD_FAB2(SCH_1):XDP_PCH_CPU_TCK0
    2  XDP_CPU_GTL_TCK_R2      B  @BASEBOARD_FAB2_LIB.BASEBOARD_FAB2(SCH_1):XDP_CPU_GTL_TCK_R2

RES  I74  R9A3   [RES_0402-0.0,5%,1/16W,CHIP,G21A]
    1  XDP_PCH_CPU_TCK0      A  @BASEBOARD_FAB2_LIB.BASEBOARD_FAB2(SCH_1):XDP_PCH_CPU_TCK0
    2  XDP_CPU_TCK0       B  @BASEBOARD_FAB2_LIB.BASEBOARD_FAB2(SCH_1):XDP_CPU_TCK0

RES  I55  R9A4   [RES_0402-475.0,1%,1/16W,CHIP,GA]
    1  XDP_PRESENT_N      A  @BASEBOARD_FAB2_LIB.BASEBOARD_FAB2(SCH_1):XDP_PRESENT_N
    2  PVCCIO_CPU0        B  @BASEBOARD_FAB2_LIB.BASEBOARD_FAB2(SCH_1):PVCCIO_CPU0

RES  I136  R9A5   [RES_0402-20.0K,1%,1/16W,CHIP,GA]
    1  P5V_STBY           A  @BASEBOARD_FAB2_LIB.BASEBOARD_FAB2(SCH_1):P5V_STBY
    2  FM_UART_SWITCH_N      B  @BASEBOARD_FAB2_LIB.BASEBOARD_FAB2(SCH_1):FM_UART_SWITCH_N

RES  I191  R9A6   [RES_0402-20.0K,1%,1/16W,EMPTY,A]
    2  SPA_5V_SIN_SW      B  @BASEBOARD_FAB2_LIB.BASEBOARD_FAB2(SCH_1):SPA_5V_SIN_SW
    1  P5V_STBY           A  @BASEBOARD_FAB2_LIB.BASEBOARD_FAB2(SCH_1):P5V_STBY

RES  I80  R9A7   [RES_0402-2.21K,1%,1/16W,CHIP,GA]
    2  SPA_SIN_SW_R       B  @BASEBOARD_FAB2_LIB.BASEBOARD_FAB2(SCH_1):SPA_SIN_SW_R
    1  P3V3_STBY          A  @BASEBOARD_FAB2_LIB.BASEBOARD_FAB2(SCH_1):P3V3_STBY

RES  I53  R9A8   [RES_0402-0.0,5%,1/16W,CHIP,G21A]
    1  SPA_SIN_SW_R       A  @BASEBOARD_FAB2_LIB.BASEBOARD_FAB2(SCH_1):SPA_SIN_SW_R
    2  SPA_MID_DBG_RX      B  @BASEBOARD_FAB2_LIB.BASEBOARD_FAB2(SCH_1):SPA_MID_DBG_RX

RES  I35  R9A9   [RES_0402-100.0,1%,1/16W,CHIP,GA]
    2  RST_SYSTEM_BTN_N      B  @BASEBOARD_FAB2_LIB.BASEBOARD_FAB2(SCH_1):RST_SYSTEM_BTN_N
    1  RST_SYSTEM_BTN_BUF_N      A  @BASEBOARD_FAB2_LIB.BASEBOARD_FAB2(SCH_1):RST_SYSTEM_BTN_BUF_N

RES  I78  R9A11  [RES_0402-150.0,1%,1/16W,CHIP,GA]
    2  XDP_TDO            B  @BASEBOARD_FAB2_LIB.BASEBOARD_FAB2(SCH_1):XDP_TDO
    1  P1V05_PCH_STBY      A  @BASEBOARD_FAB2_LIB.BASEBOARD_FAB2(SCH_1):P1V05_PCH_STBY

RES  I117  R9A12  [RES_0402-2.21K,1%,1/16W,CHIP,GA]
    2  P3V3_STBY          B  @BASEBOARD_FAB2_LIB.BASEBOARD_FAB2(SCH_1):P3V3_STBY
    1  FM_PCH_SATA_RAID_KEY_R      A  @BASEBOARD_FAB2_LIB.BASEBOARD_FAB2(SCH_1):FM_PCH_SATA_RAID_KEY_R

RES  I118  R9A13  [RES_0402-33.2,1%,1/16W,CHIP,G2A]
    1  FM_PCH_SATA_RAID_KEY_R      A  @BASEBOARD_FAB2_LIB.BASEBOARD_FAB2(SCH_1):FM_PCH_SATA_RAID_KEY_R
    2  FM_PCH_SATA_RAID_KEY      B  @BASEBOARD_FAB2_LIB.BASEBOARD_FAB2(SCH_1):FM_PCH_SATA_RAID_KEY

RES  I11  R9A14  [RES_0402-1.00K,1%,1/16W,CHIP,GA]
    1  XDP_RST_CO_N       A  @BASEBOARD_FAB2_LIB.BASEBOARD_FAB2(SCH_1):XDP_RST_CO_N
    2  P3V3_STBY          B  @BASEBOARD_FAB2_LIB.BASEBOARD_FAB2(SCH_1):P3V3_STBY

RES  I60  R9A15  [RES_0402-1.00K,1%,1/16W,CHIP,GA]
    2  XDP_RSMRST_N       B  @BASEBOARD_FAB2_LIB.BASEBOARD_FAB2(SCH_1):XDP_RSMRST_N
    1  RST_RSMRST_N       A  @BASEBOARD_FAB2_LIB.BASEBOARD_FAB2(SCH_1):RST_RSMRST_N

RES  I129  R9A16  [RES_0402-2.21K,1%,1/16W,CHIP,GA]
    1  PU_KEY_CONN_PIN2_R      A  @BASEBOARD_FAB2_LIB.BASEBOARD_FAB2(SCH_1):PU_KEY_CONN_PIN2_R
    2  P3V3_STBY          B  @BASEBOARD_FAB2_LIB.BASEBOARD_FAB2(SCH_1):P3V3_STBY

RES  I57  R9A17  [RES_0402-1.00K,1%,1/16W,CHIP,GA]
    1  XDP_ITP_PMODE      A  @BASEBOARD_FAB2_LIB.BASEBOARD_FAB2(SCH_1):XDP_ITP_PMODE
    2  P1V05_PCH_STBY      B  @BASEBOARD_FAB2_LIB.BASEBOARD_FAB2(SCH_1):P1V05_PCH_STBY

RES  I183  R9A18  [RES_0402-4.75K,1%,1/16W,CHIP,GA]
    1  P3V3_STBY          A  @BASEBOARD_FAB2_LIB.BASEBOARD_FAB2(SCH_1):P3V3_STBY
    2  FM_PWR_LED         B  @BASEBOARD_FAB2_LIB.BASEBOARD_FAB2(SCH_1):FM_PWR_LED

RES  I178  R9A20  [RES_0402-221,1.0%,1/16W,CHIP,GA]
    2  P3V3_STBY          B  @BASEBOARD_FAB2_LIB.BASEBOARD_FAB2(SCH_1):P3V3_STBY
    1  FM_PWR_LED_A       A  @BASEBOARD_FAB2_LIB.BASEBOARD_FAB2(SCH_1):FM_PWR_LED_A

RES  I186  R9A21  [RES_0402-4.75K,1%,1/16W,CHIP,GA]
    1  P3V3_STBY          A  @BASEBOARD_FAB2_LIB.BASEBOARD_FAB2(SCH_1):P3V3_STBY
    2  FM_PWR_LED_N       B  @BASEBOARD_FAB2_LIB.BASEBOARD_FAB2(SCH_1):FM_PWR_LED_N

RES  I6   R9B4   [RES_0402-49.9,1%,1/16W,CHIP,G2A]
    1  ISENSE_TMP421_1_E      A  @BASEBOARD_FAB2_LIB.BASEBOARD_FAB2(SCH_1):ISENSE_TMP421_1_E
    2  ISENSE_TMP421_1_DXP      B  @BASEBOARD_FAB2_LIB.BASEBOARD_FAB2(SCH_1):ISENSE_TMP421_1_DXP

RES  I5   R9B5   [RES_0402-49.9,1%,1/16W,CHIP,G2A]
    2  ISENSE_TMP421_1_DXN      B  @BASEBOARD_FAB2_LIB.BASEBOARD_FAB2(SCH_1):ISENSE_TMP421_1_DXN
    1  ISENSE_TMP421_1_BC      A  @BASEBOARD_FAB2_LIB.BASEBOARD_FAB2(SCH_1):ISENSE_TMP421_1_BC

RES  I35  R9B6   [RES_0402-1.00K,1%,1/16W,CHIP,GA]
    2  PU_TMP421_1_A1      B  @BASEBOARD_FAB2_LIB.BASEBOARD_FAB2(SCH_1):PU_TMP421_1_A1
    1  P3V3_STBY          A  @BASEBOARD_FAB2_LIB.BASEBOARD_FAB2(SCH_1):P3V3_STBY

RES  I222  R9B7   [RES_0402-100.0,1%,1/16W,CHIP,GA]
    1  GND                A  @BASEBOARD_FAB2_LIB.BASEBOARD_FAB2(SCH_1):GND
    2  FM_MEZZA_PRSNT1_N      B  @BASEBOARD_FAB2_LIB.BASEBOARD_FAB2(SCH_1):FM_MEZZA_PRSNT1_N

RES  I10  R9B8   [RES_0402-1.00K,1%,1/16W,CHIP,GA]
    1  PD_TMP421_1_A0      A  @BASEBOARD_FAB2_LIB.BASEBOARD_FAB2(SCH_1):PD_TMP421_1_A0
    2  GND                B  @BASEBOARD_FAB2_LIB.BASEBOARD_FAB2(SCH_1):GND

RES  I179  R9B9   [RES_0402-1.00K,1%,1/16W,CHIP,GA]
    1  JTAG_MCP_TCK       A  @BASEBOARD_FAB2_LIB.BASEBOARD_FAB2(SCH_1):JTAG_MCP_TCK
    2  GND                B  @BASEBOARD_FAB2_LIB.BASEBOARD_FAB2(SCH_1):GND

RES  I180  R9B10  [RES_0402-49.9,1%,1/16W,CHIP,G2A]
    2  JTAG_MCP_TCK_R      B  @BASEBOARD_FAB2_LIB.BASEBOARD_FAB2(SCH_1):JTAG_MCP_TCK_R
    1  JTAG_MCP_TCK       A  @BASEBOARD_FAB2_LIB.BASEBOARD_FAB2(SCH_1):JTAG_MCP_TCK

RES  I239  R9B11  [RES_0402-0.0,5%,1/16W,CHIP,G21A]
    2  JTAG_MCP_TCK_R      B  @BASEBOARD_FAB2_LIB.BASEBOARD_FAB2(SCH_1):JTAG_MCP_TCK_R
    1  JTAG_MCP_TCK       A  @BASEBOARD_FAB2_LIB.BASEBOARD_FAB2(SCH_1):JTAG_MCP_TCK

RES  I203  R9B12  [RES_0402-1.00K,1%,1/16W,CHIP,GA]
    1  P1V8_MCP_CPU0      A  @BASEBOARD_FAB2_LIB.BASEBOARD_FAB2(SCH_1):P1V8_MCP_CPU0
    2  JTAG_MCP_MUX_TDO      B  @BASEBOARD_FAB2_LIB.BASEBOARD_FAB2(SCH_1):JTAG_MCP_MUX_TDO

RES  I240  R9B13  [RES_0402-0.0,5%,1/16W,CHIP,G21A]
    2  JTAG_MCP_TMS_R      B  @BASEBOARD_FAB2_LIB.BASEBOARD_FAB2(SCH_1):JTAG_MCP_TMS_R
    1  JTAG_MCP_TMS       A  @BASEBOARD_FAB2_LIB.BASEBOARD_FAB2(SCH_1):JTAG_MCP_TMS

RES  I168  R9B14  [RES_0402-1.00K,1%,1/16W,CHIP,GA]
    2  PWRGD_CPU0_G_R      B  @BASEBOARD_FAB2_LIB.BASEBOARD_FAB2(SCH_1):PWRGD_CPU0_G_R
    1  PWRGD_CPU0_G       A  @BASEBOARD_FAB2_LIB.BASEBOARD_FAB2(SCH_1):PWRGD_CPU0_G

RES  I179  R9E1   [RES_0402-10.0K,1%,1/16W,CHIP,GA]
    2  PU_JTAG_SPRV_TDI      B  @BASEBOARD_FAB2_LIB.BASEBOARD_FAB2(SCH_1):PU_JTAG_SPRV_TDI
    1  P3V3_STBY          A  @BASEBOARD_FAB2_LIB.BASEBOARD_FAB2(SCH_1):P3V3_STBY

RES  I177  R9E2   [RES_0402-10.0K,1%,1/16W,CHIP,GA]
    2  PU_JTAG_SPRV_TCK      B  @BASEBOARD_FAB2_LIB.BASEBOARD_FAB2(SCH_1):PU_JTAG_SPRV_TCK
    1  P3V3_STBY          A  @BASEBOARD_FAB2_LIB.BASEBOARD_FAB2(SCH_1):P3V3_STBY

RES  I178  R9E3   [RES_0402-10.0K,1%,1/16W,CHIP,GA]
    2  PU_JTAG_SPRV_TMS      B  @BASEBOARD_FAB2_LIB.BASEBOARD_FAB2(SCH_1):PU_JTAG_SPRV_TMS
    1  P3V3_STBY          A  @BASEBOARD_FAB2_LIB.BASEBOARD_FAB2(SCH_1):P3V3_STBY

RES  I200  R9E4   [RES_0402-10.0K,1%,1/16W,CHIP,GA]
    2  RST_PLTRST_SPRV_R_N      B  @BASEBOARD_FAB2_LIB.BASEBOARD_FAB2(SCH_1):RST_PLTRST_SPRV_R_N
    1  P3V3_STBY          A  @BASEBOARD_FAB2_LIB.BASEBOARD_FAB2(SCH_1):P3V3_STBY

RES  I129  R9E5   [RES_0402-33.2,1%,1/16W,CHIP,G2A]
    1  SPI_NIC_CS_R_N      A  @BASEBOARD_FAB2_LIB.BASEBOARD_FAB2(SCH_1):SPI_NIC_CS_R_N
    2  SPI_NIC_CS_N       B  @BASEBOARD_FAB2_LIB.BASEBOARD_FAB2(SCH_1):SPI_NIC_CS_N

RES  I17  R9E6   [RES_0402-33.2,1%,1/16W,CHIP,G2A]
    1  SPI_NIC_MISO_R      A  @BASEBOARD_FAB2_LIB.BASEBOARD_FAB2(SCH_1):SPI_NIC_MISO_R
    2  SPI_NIC_MISO       B  @BASEBOARD_FAB2_LIB.BASEBOARD_FAB2(SCH_1):SPI_NIC_MISO

RES  I193  R9E7   [RES_0402-3.32K,1%,1/16W,CHIP,GA]
    1  P3V3_STBY          A  @BASEBOARD_FAB2_LIB.BASEBOARD_FAB2(SCH_1):P3V3_STBY
    2  IRQ_LOM_ALERT_N      B  @BASEBOARD_FAB2_LIB.BASEBOARD_FAB2(SCH_1):IRQ_LOM_ALERT_N

RES  I130  R9E8   [RES_0402-33.2,1%,1/16W,CHIP,G2A]
    1  SPI_NIC_SCLK_R      A  @BASEBOARD_FAB2_LIB.BASEBOARD_FAB2(SCH_1):SPI_NIC_SCLK_R
    2  SPI_NIC_SCLK       B  @BASEBOARD_FAB2_LIB.BASEBOARD_FAB2(SCH_1):SPI_NIC_SCLK

RES  I128  R9E9   [RES_0402-33.2,1%,1/16W,CHIP,G2A]
    1  SPI_NIC_MOSI_R      A  @BASEBOARD_FAB2_LIB.BASEBOARD_FAB2(SCH_1):SPI_NIC_MOSI_R
    2  SPI_NIC_MOSI       B  @BASEBOARD_FAB2_LIB.BASEBOARD_FAB2(SCH_1):SPI_NIC_MOSI

RES  I145  R9E10  [RES_0402-200.0,1%,1/16W,CHIP,GA]
    1  RST_PCIE_CPU_DEV1_R_N      A  @BASEBOARD_FAB2_LIB.BASEBOARD_FAB2(SCH_1):RST_PCIE_CPU_DEV1_R_N
    2  RST_PCIE_CPU_DEV1_N      B  @BASEBOARD_FAB2_LIB.BASEBOARD_FAB2(SCH_1):RST_PCIE_CPU_DEV1_N

RES  I150  R9E11  [RES_0402-200.0,1%,1/16W,CHIP,GA]
    1  RST_PCIE_CPU_DEV2_R_N      A  @BASEBOARD_FAB2_LIB.BASEBOARD_FAB2(SCH_1):RST_PCIE_CPU_DEV2_R_N
    2  RST_PCIE_CPU_DEV2_N      B  @BASEBOARD_FAB2_LIB.BASEBOARD_FAB2(SCH_1):RST_PCIE_CPU_DEV2_N

RES  I153  R9E12  [RES_0402-200.0,1%,1/16W,CHIP,GA]
    1  RST_PCIE_CPU_DEV3_R_N      A  @BASEBOARD_FAB2_LIB.BASEBOARD_FAB2(SCH_1):RST_PCIE_CPU_DEV3_R_N
    2  RST_PCIE_CPU_DEV3_N      B  @BASEBOARD_FAB2_LIB.BASEBOARD_FAB2(SCH_1):RST_PCIE_CPU_DEV3_N

RES  I212  R9E13  [RES_0402-10.0K,1%,1/16W,CHIP,GA]
    1  RMII_BMC_PCH_SPRNGVLLE_TXEN      A  @BASEBOARD_FAB2_LIB.BASEBOARD_FAB2(SCH_1):RMII_BMC_PCH_SPRNGVLLE_TXEN
    2  GND                B  @BASEBOARD_FAB2_LIB.BASEBOARD_FAB2(SCH_1):GND

RES  I379  R9E14  [RES_0402-0.0,5%,1/16W,CHIP,G21A]
    1  RST_BMC_SRST_N      A  @BASEBOARD_FAB2_LIB.BASEBOARD_FAB2(SCH_1):RST_BMC_SRST_N
    2  FM_BMC_ENABLE_N      B  @BASEBOARD_FAB2_LIB.BASEBOARD_FAB2(SCH_1):FM_BMC_ENABLE_N

RES  I114  R9E15  [RES_0402-0.0,5%,1/16W,EMPTY,G2A]
    1  FM_ROMA<0>         A  @BASEBOARD_FAB2_LIB.BASEBOARD_FAB2(SCH_1):FM_ROMA<0>
    2  FM_BMC_ENABLE_N      B  @BASEBOARD_FAB2_LIB.BASEBOARD_FAB2(SCH_1):FM_BMC_ENABLE_N

RES  I235  R9E16  [RES_0402-33.2,1%,1/16W,CHIP,G2A]
    1  RMII_PCH_SPRNGVLLE_ARB_IN_R      A  @BASEBOARD_FAB2_LIB.BASEBOARD_FAB2(SCH_1):RMII_PCH_SPRNGVLLE_ARB_IN_R
    2  RMII_PCH_SPRNGVLLE_ARB_IN      B  @BASEBOARD_FAB2_LIB.BASEBOARD_FAB2(SCH_1):RMII_PCH_SPRNGVLLE_ARB_IN

RES  I229  R9E17  [RES_0402-22.1,1.0%,1/16W,CHIP,A]
    1  RMII_SPRNGVLLE_BMC_PCH_RXD0_R      A  @BASEBOARD_FAB2_LIB.BASEBOARD_FAB2(SCH_1):RMII_SPRNGVLLE_BMC_PCH_RXD0_R
    2  RMII_SPRNGVLLE_BMC_PCH_RXD0      B  @BASEBOARD_FAB2_LIB.BASEBOARD_FAB2(SCH_1):RMII_SPRNGVLLE_BMC_PCH_RXD0

RES  I201  R9E18  [RES_0402-0.0,5%,1/16W,CHIP,G21A]
    1  XTAL_25MHZ_OUT_R      A  @BASEBOARD_FAB2_LIB.BASEBOARD_FAB2(SCH_1):XTAL_25MHZ_OUT_R
    2  XTAL_25MHZ_OUT      B  @BASEBOARD_FAB2_LIB.BASEBOARD_FAB2(SCH_1):XTAL_25MHZ_OUT

RES  I228  R9E19  [RES_0402-22.1,1.0%,1/16W,CHIP,A]
    1  RMII_SPRNGVLLE_BMC_PCH_RXD1_R      A  @BASEBOARD_FAB2_LIB.BASEBOARD_FAB2(SCH_1):RMII_SPRNGVLLE_BMC_PCH_RXD1_R
    2  RMII_SPRNGVLLE_BMC_PCH_RXD1      B  @BASEBOARD_FAB2_LIB.BASEBOARD_FAB2(SCH_1):RMII_SPRNGVLLE_BMC_PCH_RXD1

RES  I110  R9E20  [RES_0402-0.0,5%,1/16W,CHIP,G21A]
    2  XTAL_25MHZ_IN_R      B  @BASEBOARD_FAB2_LIB.BASEBOARD_FAB2(SCH_1):XTAL_25MHZ_IN_R
    1  XTAL_25MHZ_IN      A  @BASEBOARD_FAB2_LIB.BASEBOARD_FAB2(SCH_1):XTAL_25MHZ_IN

RES  I137  R9E21  [RES_0402-4.75K,1%,1/16W,CHIP,GA]
    1  P3V3_STBY          A  @BASEBOARD_FAB2_LIB.BASEBOARD_FAB2(SCH_1):P3V3_STBY
    2  FM_HEARTBEAT_LED      B  @BASEBOARD_FAB2_LIB.BASEBOARD_FAB2(SCH_1):FM_HEARTBEAT_LED

RES  I181  R9E22  [RES_0402-10.0K,1%,1/16W,CHIP,GA]
    1  PU_JTAG_SPRV_TDO      A  @BASEBOARD_FAB2_LIB.BASEBOARD_FAB2(SCH_1):PU_JTAG_SPRV_TDO
    2  P3V3_STBY          B  @BASEBOARD_FAB2_LIB.BASEBOARD_FAB2(SCH_1):P3V3_STBY

RES  I174  R9E23  [RES_0402-4.99K,1%,1/16W,CHIP,GA]
    1  PD_SPRV_RSET       A  @BASEBOARD_FAB2_LIB.BASEBOARD_FAB2(SCH_1):PD_SPRV_RSET
    2  GND                B  @BASEBOARD_FAB2_LIB.BASEBOARD_FAB2(SCH_1):GND

RES  I57  R9E24  [RES_0402-221,1.0%,1/16W,CHIP,GA]
    2  P3V3_STBY          B  @BASEBOARD_FAB2_LIB.BASEBOARD_FAB2(SCH_1):P3V3_STBY
    1  FM_HEARTBEAT_LED_A      A  @BASEBOARD_FAB2_LIB.BASEBOARD_FAB2(SCH_1):FM_HEARTBEAT_LED_A

RES  I225  R9F1   [RES_0402-22.1,1.0%,1/16W,CHIP,A]
    1  RMII_BMC_PCH_SPRNGVLLE_CRSDV_R      A  @BASEBOARD_FAB2_LIB.BASEBOARD_FAB2(SCH_1):RMII_BMC_PCH_SPRNGVLLE_CRSDV_R
    2  RMII_BMC_PCH_SPRNGVLLE_CRSDV      B  @BASEBOARD_FAB2_LIB.BASEBOARD_FAB2(SCH_1):RMII_BMC_PCH_SPRNGVLLE_CRSDV

RES  I65  R9F3   [RES_0402-4.75K,1%,1/16W,CHIP,GA]
    1  P3V3_STBY          A  @BASEBOARD_FAB2_LIB.BASEBOARD_FAB2(SCH_1):P3V3_STBY
    2  FM_FAST_PROCHOT_EN      B  @BASEBOARD_FAB2_LIB.BASEBOARD_FAB2(SCH_1):FM_FAST_PROCHOT_EN

RES  I208  R9F4   [RES_0402-100.0K,1%,1/16W,CHIP,A]
    1  RST_PLTRST_BUF_N      A  @BASEBOARD_FAB2_LIB.BASEBOARD_FAB2(SCH_1):RST_PLTRST_BUF_N
    2  GND                B  @BASEBOARD_FAB2_LIB.BASEBOARD_FAB2(SCH_1):GND

RES  I173  R9F5   [RES_0402-3.32K,1%,1/16W,CHIP,GA]
    2  PU_SPRV_LAN_PWR_GOOD      B  @BASEBOARD_FAB2_LIB.BASEBOARD_FAB2(SCH_1):PU_SPRV_LAN_PWR_GOOD
    1  P3V3_STBY          A  @BASEBOARD_FAB2_LIB.BASEBOARD_FAB2(SCH_1):P3V3_STBY

RES  I17  R9F6   [RES_0402-5.76K,1%,1/16W,CHIP,GA]
    2  VR_P1V26_BMC_STBY_FB      B  @BASEBOARD_FAB2_LIB.BASEBOARD_FAB2(SCH_1):VR_P1V26_BMC_STBY_FB
    1  P1V26_BMC_STBY      A  @BASEBOARD_FAB2_LIB.BASEBOARD_FAB2(SCH_1):P1V26_BMC_STBY

RES  I405  R9F7   [RES_0402-0.0,5%,1/16W,CHIP,G21A]
    1  RST_PLTRST_BUF_N      A  @BASEBOARD_FAB2_LIB.BASEBOARD_FAB2(SCH_1):RST_PLTRST_BUF_N
    2  RST_BMC_LVC3_N      B  @BASEBOARD_FAB2_LIB.BASEBOARD_FAB2(SCH_1):RST_BMC_LVC3_N

RES  I14  R9F8   [RES_0402-10.0K,1%,1/16W,CHIP,GA]
    2  VR_P1V26_BMC_STBY_FB      B  @BASEBOARD_FAB2_LIB.BASEBOARD_FAB2(SCH_1):VR_P1V26_BMC_STBY_FB
    1  GND                A  @BASEBOARD_FAB2_LIB.BASEBOARD_FAB2(SCH_1):GND

RES  I52  R9F9   [RES_0402-4.75K,1%,1/16W,CHIP,GA]
    2  P3V3_STBY          B  @BASEBOARD_FAB2_LIB.BASEBOARD_FAB2(SCH_1):P3V3_STBY
    1  FM_ROMA<14>        A  @BASEBOARD_FAB2_LIB.BASEBOARD_FAB2(SCH_1):FM_ROMA<14>

RES  I60  R9F10  [RES_0402-4.75K,1%,1/16W,EMPTY,A]
    2  P3V3_STBY          B  @BASEBOARD_FAB2_LIB.BASEBOARD_FAB2(SCH_1):P3V3_STBY
    1  FM_ROMA<6>         A  @BASEBOARD_FAB2_LIB.BASEBOARD_FAB2(SCH_1):FM_ROMA<6>

RES  I41  R9F11  [RES_0402-22.1,1.0%,1/16W,CHIP,A]
    1  PWRGD_P1V26_BMC_STBY_R      A  @BASEBOARD_FAB2_LIB.BASEBOARD_FAB2(SCH_1):PWRGD_P1V26_BMC_STBY_R
    2  PWRGD_P1V26_BMC_STBY      B  @BASEBOARD_FAB2_LIB.BASEBOARD_FAB2(SCH_1):PWRGD_P1V26_BMC_STBY

RES  I6   R9F12  [RES_0402-10.0K,1%,1/16W,CHIP,GA]
    2  PWRGD_P1V538_BMC_STBY_R      B  @BASEBOARD_FAB2_LIB.BASEBOARD_FAB2(SCH_1):PWRGD_P1V538_BMC_STBY_R
    1  P3V3_STBY          A  @BASEBOARD_FAB2_LIB.BASEBOARD_FAB2(SCH_1):P3V3_STBY

RES  I21  R9F13  [RES_0402-10.0K,1%,1/16W,CHIP,GA]
    2  PWRGD_P1V26_BMC_STBY_R      B  @BASEBOARD_FAB2_LIB.BASEBOARD_FAB2(SCH_1):PWRGD_P1V26_BMC_STBY_R
    1  P3V3_STBY          A  @BASEBOARD_FAB2_LIB.BASEBOARD_FAB2(SCH_1):P3V3_STBY

RES  I47  R9F14  [RES_0402-4.75K,1%,1/16W,CHIP,GA]
    2  P3V3_STBY          B  @BASEBOARD_FAB2_LIB.BASEBOARD_FAB2(SCH_1):P3V3_STBY
    1  FM_ROMA<19>        A  @BASEBOARD_FAB2_LIB.BASEBOARD_FAB2(SCH_1):FM_ROMA<19>

RES  I111  R9F15  [RES_0402-4.75K,1%,1/16W,CHIP,GA]
    2  P3V3_STBY          B  @BASEBOARD_FAB2_LIB.BASEBOARD_FAB2(SCH_1):P3V3_STBY
    1  FM_ROMA<8>         A  @BASEBOARD_FAB2_LIB.BASEBOARD_FAB2(SCH_1):FM_ROMA<8>

RES  I56  R9F16  [RES_0402-4.75K,1%,1/16W,CHIP,GA]
    2  P3V3_STBY          B  @BASEBOARD_FAB2_LIB.BASEBOARD_FAB2(SCH_1):P3V3_STBY
    1  FM_ROMA<10>        A  @BASEBOARD_FAB2_LIB.BASEBOARD_FAB2(SCH_1):FM_ROMA<10>

RES  I46  R9F17  [RES_0402-4.75K,1%,1/16W,EMPTY,A]
    2  P3V3_STBY          B  @BASEBOARD_FAB2_LIB.BASEBOARD_FAB2(SCH_1):P3V3_STBY
    1  FM_ROMA<20>        A  @BASEBOARD_FAB2_LIB.BASEBOARD_FAB2(SCH_1):FM_ROMA<20>

RES  I62  R9F18  [RES_0402-4.75K,1%,1/16W,EMPTY,A]
    2  P3V3_STBY          B  @BASEBOARD_FAB2_LIB.BASEBOARD_FAB2(SCH_1):P3V3_STBY
    1  FM_ROMA<4>         A  @BASEBOARD_FAB2_LIB.BASEBOARD_FAB2(SCH_1):FM_ROMA<4>

RES  I63  R9F19  [RES_0402-4.75K,1%,1/16W,EMPTY,A]
    2  P3V3_STBY          B  @BASEBOARD_FAB2_LIB.BASEBOARD_FAB2(SCH_1):P3V3_STBY
    1  FM_ROMA<3>         A  @BASEBOARD_FAB2_LIB.BASEBOARD_FAB2(SCH_1):FM_ROMA<3>

RES  I133  R9F20  [RES_0402-348,1%,1/16W,EMPTY,G2A]
    1  PECI_BMC           A  @BASEBOARD_FAB2_LIB.BASEBOARD_FAB2(SCH_1):PECI_BMC
    2  GND                B  @BASEBOARD_FAB2_LIB.BASEBOARD_FAB2(SCH_1):GND

RES  I109  R9F21  [RES_0402-33.2,1%,1/16W,CHIP,G2A]
    1  SPI_BMC_BT_CLK_R      A  @BASEBOARD_FAB2_LIB.BASEBOARD_FAB2(SCH_1):SPI_BMC_BT_CLK_R
    2  SPI_BMC_BT_CLK      B  @BASEBOARD_FAB2_LIB.BASEBOARD_FAB2(SCH_1):SPI_BMC_BT_CLK

RES  I52  R9F22  [RES_0402-20.0,1%,1/16W,CHIP,G2A]
    1  SMB_LAN_STBY_LVC3_SCL_R      A  @BASEBOARD_FAB2_LIB.BASEBOARD_FAB2(SCH_1):SMB_LAN_STBY_LVC3_SCL_R
    2  SMB_LAN_STBY_LVC3_SCL      B  @BASEBOARD_FAB2_LIB.BASEBOARD_FAB2(SCH_1):SMB_LAN_STBY_LVC3_SCL

RES  I51  R9F23  [RES_0402-20.0,1%,1/16W,CHIP,G2A]
    1  SMB_LAN_STBY_LVC3_SDA_R      A  @BASEBOARD_FAB2_LIB.BASEBOARD_FAB2(SCH_1):SMB_LAN_STBY_LVC3_SDA_R
    2  SMB_LAN_STBY_LVC3_SDA      B  @BASEBOARD_FAB2_LIB.BASEBOARD_FAB2(SCH_1):SMB_LAN_STBY_LVC3_SDA

RES  I100  R9F24  [RES_0402-0.0,5%,1/16W,EMPTY,G2A]
    1  SPA_MID_DBG_RX      A  @BASEBOARD_FAB2_LIB.BASEBOARD_FAB2(SCH_1):SPA_MID_DBG_RX
    2  SP2_BMC_CM_UART_RX      B  @BASEBOARD_FAB2_LIB.BASEBOARD_FAB2(SCH_1):SP2_BMC_CM_UART_RX

RES  I86  R9F25  [RES_0402-100.0,1%,1/16W,CHIP,GA]
    2  UART_MUX_IN_R      B  @BASEBOARD_FAB2_LIB.BASEBOARD_FAB2(SCH_1):UART_MUX_IN_R
    1  SPA_MID_DBG_RX      A  @BASEBOARD_FAB2_LIB.BASEBOARD_FAB2(SCH_1):SPA_MID_DBG_RX

RES  I99  R9F26  [RES_0402-0.0,5%,1/16W,EMPTY,G2A]
    2  SPA_MID_DBG_TX      B  @BASEBOARD_FAB2_LIB.BASEBOARD_FAB2(SCH_1):SPA_MID_DBG_TX
    1  SP2_BMC_CM_UART_TX      A  @BASEBOARD_FAB2_LIB.BASEBOARD_FAB2(SCH_1):SP2_BMC_CM_UART_TX

RES  I91  R9F27  [RES_0402-0.0,5%,1/16W,CHIP,G21A]
    1  UART_MUX_OUT_R      A  @BASEBOARD_FAB2_LIB.BASEBOARD_FAB2(SCH_1):UART_MUX_OUT_R
    2  SPA_MID_DBG_TX      B  @BASEBOARD_FAB2_LIB.BASEBOARD_FAB2(SCH_1):SPA_MID_DBG_TX

RES  I72  R9F28  [RES_0402-221,1.0%,1/16W,CHIP,GA]
    1  P3V3_STBY          A  @BASEBOARD_FAB2_LIB.BASEBOARD_FAB2(SCH_1):P3V3_STBY
    2  FM_RED_LED_ANODE      B  @BASEBOARD_FAB2_LIB.BASEBOARD_FAB2(SCH_1):FM_RED_LED_ANODE

RES  I71  R9F29  [RES_0402-4.75K,1%,1/16W,CHIP,GA]
    2  RST_BMC_DDR3_R_N      B  @BASEBOARD_FAB2_LIB.BASEBOARD_FAB2(SCH_1):RST_BMC_DDR3_R_N
    1  P1V538_BMC_STBY      A  @BASEBOARD_FAB2_LIB.BASEBOARD_FAB2(SCH_1):P1V538_BMC_STBY

RES  I76  R9F30  [RES_0402-4.75K,1%,1/16W,CHIP,GA]
    1  P3V3_STBY          A  @BASEBOARD_FAB2_LIB.BASEBOARD_FAB2(SCH_1):P3V3_STBY
    2  FM_BMC_FAULT_LED_N      B  @BASEBOARD_FAB2_LIB.BASEBOARD_FAB2(SCH_1):FM_BMC_FAULT_LED_N

RES  I14  R9F31  [RES_0402-12K,1%,1/16W,CHIP,G21A]
    2  VR_P1V538_BMC_STBY_FB      B  @BASEBOARD_FAB2_LIB.BASEBOARD_FAB2(SCH_1):VR_P1V538_BMC_STBY_FB
    1  P1V538_BMC_STBY      A  @BASEBOARD_FAB2_LIB.BASEBOARD_FAB2(SCH_1):P1V538_BMC_STBY

RES  I15  R9F32  [RES_0402-13K,1.0%,1/16W,CHIP,GA]
    2  VR_P1V538_BMC_STBY_FB      B  @BASEBOARD_FAB2_LIB.BASEBOARD_FAB2(SCH_1):VR_P1V538_BMC_STBY_FB
    1  GND                A  @BASEBOARD_FAB2_LIB.BASEBOARD_FAB2(SCH_1):GND

RES  I132  R9F33  [RES_0402-0.0,5%,1/16W,CHIP,G21A]
    2  PECI_BMC_R         B  @BASEBOARD_FAB2_LIB.BASEBOARD_FAB2(SCH_1):PECI_BMC_R
    1  PECI_BMC           A  @BASEBOARD_FAB2_LIB.BASEBOARD_FAB2(SCH_1):PECI_BMC

RES  I70  R9F34  [RES_0402-33.2,1%,1/16W,CHIP,G2A]
    1  RST_BMC_DDR3_R_N      A  @BASEBOARD_FAB2_LIB.BASEBOARD_FAB2(SCH_1):RST_BMC_DDR3_R_N
    2  RST_BMC_DDR3_N      B  @BASEBOARD_FAB2_LIB.BASEBOARD_FAB2(SCH_1):RST_BMC_DDR3_N

RES  I51  R9F35  [RES_0402-4.75K,1%,1/16W,CHIP,GA]
    2  P3V3_STBY          B  @BASEBOARD_FAB2_LIB.BASEBOARD_FAB2(SCH_1):P3V3_STBY
    1  FM_ROMA<15>        A  @BASEBOARD_FAB2_LIB.BASEBOARD_FAB2(SCH_1):FM_ROMA<15>

RES  I44  R9F36  [RES_0402-4.75K,1%,1/16W,EMPTY,A]
    2  P3V3_STBY          B  @BASEBOARD_FAB2_LIB.BASEBOARD_FAB2(SCH_1):P3V3_STBY
    1  FM_ROMA<22>        A  @BASEBOARD_FAB2_LIB.BASEBOARD_FAB2(SCH_1):FM_ROMA<22>

RES  I55  R9F37  [RES_0402-4.75K,1%,1/16W,EMPTY,A]
    2  P3V3_STBY          B  @BASEBOARD_FAB2_LIB.BASEBOARD_FAB2(SCH_1):P3V3_STBY
    1  FM_ROMA<11>        A  @BASEBOARD_FAB2_LIB.BASEBOARD_FAB2(SCH_1):FM_ROMA<11>

RES  I59  R9F38  [RES_0402-4.75K,1%,1/16W,EMPTY,A]
    2  P3V3_STBY          B  @BASEBOARD_FAB2_LIB.BASEBOARD_FAB2(SCH_1):P3V3_STBY
    1  FM_ROMA<7>         A  @BASEBOARD_FAB2_LIB.BASEBOARD_FAB2(SCH_1):FM_ROMA<7>

RES  I64  R9F39  [RES_0402-4.75K,1%,1/16W,EMPTY,A]
    2  P3V3_STBY          B  @BASEBOARD_FAB2_LIB.BASEBOARD_FAB2(SCH_1):P3V3_STBY
    1  FM_ROMA<2>         A  @BASEBOARD_FAB2_LIB.BASEBOARD_FAB2(SCH_1):FM_ROMA<2>

RES  I65  R9F40  [RES_0402-4.75K,1%,1/16W,CHIP,GA]
    2  P3V3_STBY          B  @BASEBOARD_FAB2_LIB.BASEBOARD_FAB2(SCH_1):P3V3_STBY
    1  FM_ROMA<1>         A  @BASEBOARD_FAB2_LIB.BASEBOARD_FAB2(SCH_1):FM_ROMA<1>

RES  I108  R9F41  [RES_0402-33.2,1%,1/16W,CHIP,G2A]
    1  SPI_BMC_BT_DO_R      A  @BASEBOARD_FAB2_LIB.BASEBOARD_FAB2(SCH_1):SPI_BMC_BT_DO_R
    2  SPI_BMC_BT_DO      B  @BASEBOARD_FAB2_LIB.BASEBOARD_FAB2(SCH_1):SPI_BMC_BT_DO

RES  I214  R9F42  [RES_0402-100.0K,1%,1/16W,CHIP,A]
    1  P2E_SSB_BMC_TX_C_DP      A  @BASEBOARD_FAB2_LIB.BASEBOARD_FAB2(SCH_1):P2E_SSB_BMC_TX_C_DP
    2  GND                B  @BASEBOARD_FAB2_LIB.BASEBOARD_FAB2(SCH_1):GND

RES  I216  R9F43  [RES_0402-100.0K,1%,1/16W,CHIP,A]
    1  P2E_SSB_BMC_TX_C_DN      A  @BASEBOARD_FAB2_LIB.BASEBOARD_FAB2(SCH_1):P2E_SSB_BMC_TX_C_DN
    2  GND                B  @BASEBOARD_FAB2_LIB.BASEBOARD_FAB2(SCH_1):GND

RES  I211  R9F44  [RES_0402-100.0K,1%,1/16W,CHIP,A]
    2  GND                B  @BASEBOARD_FAB2_LIB.BASEBOARD_FAB2(SCH_1):GND
    1  CLK_100M_BMC_PE_R_DN      A  @BASEBOARD_FAB2_LIB.BASEBOARD_FAB2(SCH_1):CLK_100M_BMC_PE_R_DN

RES  I210  R9F45  [RES_0402-100.0K,1%,1/16W,CHIP,A]
    2  GND                B  @BASEBOARD_FAB2_LIB.BASEBOARD_FAB2(SCH_1):GND
    1  CLK_100M_BMC_PE_R_DP      A  @BASEBOARD_FAB2_LIB.BASEBOARD_FAB2(SCH_1):CLK_100M_BMC_PE_R_DP

RES  I218  R9F46  [RES_0402-100.0K,1%,1/16W,CHIP,A]
    2  GND                B  @BASEBOARD_FAB2_LIB.BASEBOARD_FAB2(SCH_1):GND
    1  FM_PE_BMC_WAKE_N      A  @BASEBOARD_FAB2_LIB.BASEBOARD_FAB2(SCH_1):FM_PE_BMC_WAKE_N

RES  I4   R9F47  [RES_0402-4.75K,1%,1/16W,CHIP,GA]
    2  PU_PI7C9X1172_I2C_SPI_N      B  @BASEBOARD_FAB2_LIB.BASEBOARD_FAB2(SCH_1):PU_PI7C9X1172_I2C_SPI_N
    1  P3V3_STBY          A  @BASEBOARD_FAB2_LIB.BASEBOARD_FAB2(SCH_1):P3V3_STBY

RES  I13  R9F48  [RES_0402-4.75K,1%,1/16W,EMPTY,A]
    1  P3V3_STBY          A  @BASEBOARD_FAB2_LIB.BASEBOARD_FAB2(SCH_1):P3V3_STBY
    2  FM_PI7C9X1172_A1      B  @BASEBOARD_FAB2_LIB.BASEBOARD_FAB2(SCH_1):FM_PI7C9X1172_A1

RES  I14  R9F49  [RES_0402-4.75K,1%,1/16W,EMPTY,A]
    1  P3V3_STBY          A  @BASEBOARD_FAB2_LIB.BASEBOARD_FAB2(SCH_1):P3V3_STBY
    2  FM_PI7C9X1172_A0      B  @BASEBOARD_FAB2_LIB.BASEBOARD_FAB2(SCH_1):FM_PI7C9X1172_A0

RES  I11  R9F50  [RES_0402-1.00K,1%,1/16W,CHIP,GA]
    2  GND                B  @BASEBOARD_FAB2_LIB.BASEBOARD_FAB2(SCH_1):GND
    1  FM_PI7C9X1172_A1      A  @BASEBOARD_FAB2_LIB.BASEBOARD_FAB2(SCH_1):FM_PI7C9X1172_A1

RES  I12  R9F51  [RES_0402-1.00K,1%,1/16W,CHIP,GA]
    2  GND                B  @BASEBOARD_FAB2_LIB.BASEBOARD_FAB2(SCH_1):GND
    1  FM_PI7C9X1172_A0      A  @BASEBOARD_FAB2_LIB.BASEBOARD_FAB2(SCH_1):FM_PI7C9X1172_A0

RES  I82  R9F52  [RES_0402-4.75K,1%,1/16W,CHIP,GA]
    1  P3V3_STBY          A  @BASEBOARD_FAB2_LIB.BASEBOARD_FAB2(SCH_1):P3V3_STBY
    2  FM_BMC_FAULT_LED      B  @BASEBOARD_FAB2_LIB.BASEBOARD_FAB2(SCH_1):FM_BMC_FAULT_LED

RES  I53  R9F53  [RES_0402-0.0,5%,1/16W,CHIP,G21A]
    2  UART_BRIDGE_RXD5      B  @BASEBOARD_FAB2_LIB.BASEBOARD_FAB2(SCH_1):UART_BRIDGE_RXD5
    1  UART_BMC_RXD5      A  @BASEBOARD_FAB2_LIB.BASEBOARD_FAB2(SCH_1):UART_BMC_RXD5

RES  I52  R9F54  [RES_0402-0.0,5%,1/16W,CHIP,G21A]
    2  SP1_HOST_BRIDGE_UART_RX      B  @BASEBOARD_FAB2_LIB.BASEBOARD_FAB2(SCH_1):SP1_HOST_BRIDGE_UART_RX
    1  SP1_BMC_HOST_UART_RX      A  @BASEBOARD_FAB2_LIB.BASEBOARD_FAB2(SCH_1):SP1_BMC_HOST_UART_RX

RES  I30  R9F55  [RES_0402-4.75K,1%,1/16W,CHIP,GA]
    1  P3V3_STBY          A  @BASEBOARD_FAB2_LIB.BASEBOARD_FAB2(SCH_1):P3V3_STBY
    2  FM_UART_ALERT_N      B  @BASEBOARD_FAB2_LIB.BASEBOARD_FAB2(SCH_1):FM_UART_ALERT_N

RES  I49  R9F56  [RES_0402-0.0,5%,1/16W,CHIP,G21A]
    1  SP1_HOST_BRIDGE_UART_TX      A  @BASEBOARD_FAB2_LIB.BASEBOARD_FAB2(SCH_1):SP1_HOST_BRIDGE_UART_TX
    2  SP1_BMC_HOST_UART_TX      B  @BASEBOARD_FAB2_LIB.BASEBOARD_FAB2(SCH_1):SP1_BMC_HOST_UART_TX

RES  I48  R9F57  [RES_0402-0.0,5%,1/16W,CHIP,G21A]
    1  UART_BRIDGE_TXD5      A  @BASEBOARD_FAB2_LIB.BASEBOARD_FAB2(SCH_1):UART_BRIDGE_TXD5
    2  UART_BMC_TXD5      B  @BASEBOARD_FAB2_LIB.BASEBOARD_FAB2(SCH_1):UART_BMC_TXD5

RES  I24  R9F58  [RES_0402-0.0,5%,1/16W,CHIP,G21A]
    1  XTAL_24MHZ_PI7C9X1172_IN      A  @BASEBOARD_FAB2_LIB.BASEBOARD_FAB2(SCH_1):XTAL_24MHZ_PI7C9X1172_IN
    2  XTAL_24MHZ_IN_R      B  @BASEBOARD_FAB2_LIB.BASEBOARD_FAB2(SCH_1):XTAL_24MHZ_IN_R

RES  I25  R9F59  [RES_0402-0.0,5%,1/16W,CHIP,G21A]
    1  XTAL_24MHZ_PI7C9X1172_OUT      A  @BASEBOARD_FAB2_LIB.BASEBOARD_FAB2(SCH_1):XTAL_24MHZ_PI7C9X1172_OUT
    2  XTAL_24MHZ_OUT_R      B  @BASEBOARD_FAB2_LIB.BASEBOARD_FAB2(SCH_1):XTAL_24MHZ_OUT_R

RES  I257  R9F60  [RES_0402-0.0,5%,1/16W,EMPTY,G2A]
    1  CLK_25M_BMC        A  @BASEBOARD_FAB2_LIB.BASEBOARD_FAB2(SCH_1):CLK_25M_BMC
    2  CLK_24M_25M_BMC_CLKIN      B  @BASEBOARD_FAB2_LIB.BASEBOARD_FAB2(SCH_1):CLK_24M_25M_BMC_CLKIN

RES  I252  R9F61  [RES_0402-10.0K,1%,1/16W,CHIP,GA]
    2  PU_24M_OSC_OE      B  @BASEBOARD_FAB2_LIB.BASEBOARD_FAB2(SCH_1):PU_24M_OSC_OE
    1  P3V3_STBY          A  @BASEBOARD_FAB2_LIB.BASEBOARD_FAB2(SCH_1):P3V3_STBY

RES  I256  R9F62  [RES_0402-0.0,5%,1/16W,CHIP,G21A]
    1  CLK_24M_BMC_CLKIN_R      A  @BASEBOARD_FAB2_LIB.BASEBOARD_FAB2(SCH_1):CLK_24M_BMC_CLKIN_R
    2  CLK_24M_25M_BMC_CLKIN      B  @BASEBOARD_FAB2_LIB.BASEBOARD_FAB2(SCH_1):CLK_24M_25M_BMC_CLKIN

RES  I271  R9F63  [RES_0402-0.0,5%,1/16W,CHIP,G21A]
    2  SPA_MID_DBG_RX_R      B  @BASEBOARD_FAB2_LIB.BASEBOARD_FAB2(SCH_1):SPA_MID_DBG_RX_R
    1  SPA_MID_DBG_RX      A  @BASEBOARD_FAB2_LIB.BASEBOARD_FAB2(SCH_1):SPA_MID_DBG_RX

RES  I277  R9F64  [RES_0402-0.0,5%,1/16W,EMPTY,G2A]
    2  SPA_MID_DBG_RX_R      B  @BASEBOARD_FAB2_LIB.BASEBOARD_FAB2(SCH_1):SPA_MID_DBG_RX_R
    1  SP2_BMC_CM_UART_TX_R1      A  @BASEBOARD_FAB2_LIB.BASEBOARD_FAB2(SCH_1):SP2_BMC_CM_UART_TX_R1

RES  I145  R9F65  [RES_0402-0.0,5%,1/16W,EMPTY,G2A]
    1  SP2_BMC_CM_UART_TX_R1      A  @BASEBOARD_FAB2_LIB.BASEBOARD_FAB2(SCH_1):SP2_BMC_CM_UART_TX_R1
    2  SP2_BMC_CM_UART_TX_R      B  @BASEBOARD_FAB2_LIB.BASEBOARD_FAB2(SCH_1):SP2_BMC_CM_UART_TX_R

RES  I138  R9F66  [RES_0402-0.0,5%,1/16W,CHIP,G21A]
    2  SP2_BMC_CM_UART_TX_R      B  @BASEBOARD_FAB2_LIB.BASEBOARD_FAB2(SCH_1):SP2_BMC_CM_UART_TX_R
    1  SP2_BMC_CM_UART_TX      A  @BASEBOARD_FAB2_LIB.BASEBOARD_FAB2(SCH_1):SP2_BMC_CM_UART_TX

RES  I276  R9F67  [RES_0402-0.0,5%,1/16W,EMPTY,G2A]
    2  SPA_MID_DBG_TX_R      B  @BASEBOARD_FAB2_LIB.BASEBOARD_FAB2(SCH_1):SPA_MID_DBG_TX_R
    1  SP2_BMC_CM_UART_RX_R1      A  @BASEBOARD_FAB2_LIB.BASEBOARD_FAB2(SCH_1):SP2_BMC_CM_UART_RX_R1

RES  I141  R9F68  [RES_0402-0.0,5%,1/16W,CHIP,G21A]
    1  SP2_BMC_CM_UART_RX_R      A  @BASEBOARD_FAB2_LIB.BASEBOARD_FAB2(SCH_1):SP2_BMC_CM_UART_RX_R
    2  SP2_BMC_CM_UART_RX      B  @BASEBOARD_FAB2_LIB.BASEBOARD_FAB2(SCH_1):SP2_BMC_CM_UART_RX

RES  I146  R9F69  [RES_0402-0.0,5%,1/16W,EMPTY,G2A]
    2  SP2_BMC_CM_UART_RX_R1      B  @BASEBOARD_FAB2_LIB.BASEBOARD_FAB2(SCH_1):SP2_BMC_CM_UART_RX_R1
    1  SP2_BMC_CM_UART_RX_R      A  @BASEBOARD_FAB2_LIB.BASEBOARD_FAB2(SCH_1):SP2_BMC_CM_UART_RX_R

RES  I270  R9F70  [RES_0402-0.0,5%,1/16W,CHIP,G21A]
    2  SPA_MID_DBG_TX_R      B  @BASEBOARD_FAB2_LIB.BASEBOARD_FAB2(SCH_1):SPA_MID_DBG_TX_R
    1  SPA_MID_DBG_TX      A  @BASEBOARD_FAB2_LIB.BASEBOARD_FAB2(SCH_1):SPA_MID_DBG_TX

RES  I54  R9G1   [RES_0402-150.0,1%,1/16W,CHIP,GA]
    2  LED_LAN_1_R_N      B  @BASEBOARD_FAB2_LIB.BASEBOARD_FAB2(SCH_1):LED_LAN_1_R_N
    1  LED_LAN_1_N        A  @BASEBOARD_FAB2_LIB.BASEBOARD_FAB2(SCH_1):LED_LAN_1_N

RES  I30  R9G2   [RES_0402-150.0,1%,1/16W,CHIP,GA]
    1  LED_LAN_2_R_N      A  @BASEBOARD_FAB2_LIB.BASEBOARD_FAB2(SCH_1):LED_LAN_2_R_N
    2  LED_LAN_2_N        B  @BASEBOARD_FAB2_LIB.BASEBOARD_FAB2(SCH_1):LED_LAN_2_N

RES  I28  R9G3   [RES_0402-150.0,1%,1/16W,CHIP,GA]
    1  LED_LAN_0_R_N      A  @BASEBOARD_FAB2_LIB.BASEBOARD_FAB2(SCH_1):LED_LAN_0_R_N
    2  LED_LAN_0_N        B  @BASEBOARD_FAB2_LIB.BASEBOARD_FAB2(SCH_1):LED_LAN_0_N

RES  I56  R9G4   [RES_0402-0.0,5%,1/16W,CHIP,G21A]
    2  P3V3_STBY          B  @BASEBOARD_FAB2_LIB.BASEBOARD_FAB2(SCH_1):P3V3_STBY
    1  NIC_LED_ACT_ANODE_R      A  @BASEBOARD_FAB2_LIB.BASEBOARD_FAB2(SCH_1):NIC_LED_ACT_ANODE_R

RES  I516  R9G5   [RES_0402-0.0,5%,1/16W,EMPTY,G2A]
    1  PD_USB_BMC_P1_DN      A  @BASEBOARD_FAB2_LIB.BASEBOARD_FAB2(SCH_1):PD_USB_BMC_P1_DN
    2  GND                B  @BASEBOARD_FAB2_LIB.BASEBOARD_FAB2(SCH_1):GND

RES  I517  R9G6   [RES_0402-0.0,5%,1/16W,EMPTY,G2A]
    1  PD_USB_BMC_P1_DP      A  @BASEBOARD_FAB2_LIB.BASEBOARD_FAB2(SCH_1):PD_USB_BMC_P1_DP
    2  GND                B  @BASEBOARD_FAB2_LIB.BASEBOARD_FAB2(SCH_1):GND

RES  I78  R9G7   [RES_0402-49.9K,1%,1/16W,CHIP,GA]
    1  PD_ADCREXT         A  @BASEBOARD_FAB2_LIB.BASEBOARD_FAB2(SCH_1):PD_ADCREXT
    2  GND                B  @BASEBOARD_FAB2_LIB.BASEBOARD_FAB2(SCH_1):GND

RES  I457  R9G8   [RES_0402-2.7K,1%,1/16W,CHIP,G2A]
    2  GND                B  @BASEBOARD_FAB2_LIB.BASEBOARD_FAB2(SCH_1):GND
    1  A_DACRSET          A  @BASEBOARD_FAB2_LIB.BASEBOARD_FAB2(SCH_1):A_DACRSET

RES  I75  R9G9   [RES_0402-0.0,5%,1/16W,CHIP,G21A]
    1  NIC_SER_P_MDI_3_DP      A  @BASEBOARD_FAB2_LIB.BASEBOARD_FAB2(SCH_1):NIC_SER_P_MDI_3_DP
    2  NIC_MDI_SPRV_RJ45_3_R_DP      B  @BASEBOARD_FAB2_LIB.BASEBOARD_FAB2(SCH_1):NIC_MDI_SPRV_RJ45_3_R_DP

RES  I187  R9G10  [RES_0402-33.2,1%,1/16W,CHIP,G2A]
    2  FM_CPU1_FIVR_FAULT_LVT3_R_N      B  @BASEBOARD_FAB2_LIB.BASEBOARD_FAB2(SCH_1):FM_CPU1_FIVR_FAULT_LVT3_R_N
    1  FM_CPU1_FIVR_FAULT_LVT3_N      A  @BASEBOARD_FAB2_LIB.BASEBOARD_FAB2(SCH_1):FM_CPU1_FIVR_FAULT_LVT3_N

RES  I76  R9G11  [RES_0402-0.0,5%,1/16W,CHIP,G21A]
    1  NIC_SER_N_MDI_3_DN      A  @BASEBOARD_FAB2_LIB.BASEBOARD_FAB2(SCH_1):NIC_SER_N_MDI_3_DN
    2  NIC_MDI_SPRV_RJ45_3_R_DN      B  @BASEBOARD_FAB2_LIB.BASEBOARD_FAB2(SCH_1):NIC_MDI_SPRV_RJ45_3_R_DN

RES  I224  R9G12  [RES_0402-20.0,1%,1/16W,CHIP,G2A]
    2  SMB_SPRINGVILLE_STBY_LVC3_SDA      B  @BASEBOARD_FAB2_LIB.BASEBOARD_FAB2(SCH_1):SMB_SPRINGVILLE_STBY_LVC3_SDA
    1  SMB_OCP_LAN_STBY_LVC3_SDA      A  @BASEBOARD_FAB2_LIB.BASEBOARD_FAB2(SCH_1):SMB_OCP_LAN_STBY_LVC3_SDA

RES  I227  R9G13  [RES_0402-20.0,1%,1/16W,CHIP,G2A]
    2  SMB_SPRINGVILLE_STBY_LVC3_SCL      B  @BASEBOARD_FAB2_LIB.BASEBOARD_FAB2(SCH_1):SMB_SPRINGVILLE_STBY_LVC3_SCL
    1  SMB_OCP_LAN_STBY_LVC3_SCL      A  @BASEBOARD_FAB2_LIB.BASEBOARD_FAB2(SCH_1):SMB_OCP_LAN_STBY_LVC3_SCL

RES  I77  R9G14  [RES_0402-20.0,1%,1/16W,CHIP,G2A]
    2  SMB_SENSOR_STBY_LVC3_SCL      B  @BASEBOARD_FAB2_LIB.BASEBOARD_FAB2(SCH_1):SMB_SENSOR_STBY_LVC3_SCL
    1  SMB_SENSOR_BMC_STBY_LVC3_SCL      A  @BASEBOARD_FAB2_LIB.BASEBOARD_FAB2(SCH_1):SMB_SENSOR_BMC_STBY_LVC3_SCL

RES  I58  R9G15  [RES_0402-20.0,1%,1/16W,CHIP,G2A]
    2  SMB_SENSOR_STBY_LVC3_SDA      B  @BASEBOARD_FAB2_LIB.BASEBOARD_FAB2(SCH_1):SMB_SENSOR_STBY_LVC3_SDA
    1  SMB_SENSOR_BMC_STBY_LVC3_SDA      A  @BASEBOARD_FAB2_LIB.BASEBOARD_FAB2(SCH_1):SMB_SENSOR_BMC_STBY_LVC3_SDA

RES  I188  R9G16  [RES_0402-33.2,1%,1/16W,CHIP,G2A]
    2  FM_CPU0_FIVR_FAULT_LVT3_R_N      B  @BASEBOARD_FAB2_LIB.BASEBOARD_FAB2(SCH_1):FM_CPU0_FIVR_FAULT_LVT3_R_N
    1  FM_CPU0_FIVR_FAULT_LVT3_N      A  @BASEBOARD_FAB2_LIB.BASEBOARD_FAB2(SCH_1):FM_CPU0_FIVR_FAULT_LVT3_N

RES  I78  R9G17  [RES_0402-0.0,5%,1/16W,CHIP,G21A]
    1  NIC_SET_N_MDI_2_DN      A  @BASEBOARD_FAB2_LIB.BASEBOARD_FAB2(SCH_1):NIC_SET_N_MDI_2_DN
    2  NIC_MDI_SPRV_RJ45_2_R_DN      B  @BASEBOARD_FAB2_LIB.BASEBOARD_FAB2(SCH_1):NIC_MDI_SPRV_RJ45_2_R_DN

RES  I77  R9G18  [RES_0402-0.0,5%,1/16W,CHIP,G21A]
    1  NIC_SET_P_MDI_2_DP      A  @BASEBOARD_FAB2_LIB.BASEBOARD_FAB2(SCH_1):NIC_SET_P_MDI_2_DP
    2  NIC_MDI_SPRV_RJ45_2_R_DP      B  @BASEBOARD_FAB2_LIB.BASEBOARD_FAB2(SCH_1):NIC_MDI_SPRV_RJ45_2_R_DP

RES  I79  R9G19  [RES_0402-0.0,5%,1/16W,CHIP,G21A]
    2  NIC_MDI_SPRV_RJ45_1_R_DP      B  @BASEBOARD_FAB2_LIB.BASEBOARD_FAB2(SCH_1):NIC_MDI_SPRV_RJ45_1_R_DP
    1  NIC_MDI_SPRV_RJ45_1_DP      A  @BASEBOARD_FAB2_LIB.BASEBOARD_FAB2(SCH_1):NIC_MDI_SPRV_RJ45_1_DP

RES  I80  R9G20  [RES_0402-0.0,5%,1/16W,CHIP,G21A]
    2  NIC_MDI_SPRV_RJ45_1_R_DN      B  @BASEBOARD_FAB2_LIB.BASEBOARD_FAB2(SCH_1):NIC_MDI_SPRV_RJ45_1_R_DN
    1  NIC_MDI_SPRV_RJ45_1_DN      A  @BASEBOARD_FAB2_LIB.BASEBOARD_FAB2(SCH_1):NIC_MDI_SPRV_RJ45_1_DN

RES  I69  R9G21  [RES_0402-4.75K,1%,1/16W,CHIP,GA]
    1  P3V3_STBY          A  @BASEBOARD_FAB2_LIB.BASEBOARD_FAB2(SCH_1):P3V3_STBY
    2  IRQ_VM_INT_R_N      B  @BASEBOARD_FAB2_LIB.BASEBOARD_FAB2(SCH_1):IRQ_VM_INT_R_N

RES  I82  R9G22  [RES_0402-0.0,5%,1/16W,CHIP,G21A]
    2  NIC_MDI_SPRV_RJ45_0_R_DN      B  @BASEBOARD_FAB2_LIB.BASEBOARD_FAB2(SCH_1):NIC_MDI_SPRV_RJ45_0_R_DN
    1  NIC_MDI_SPRV_RJ45_0_DN      A  @BASEBOARD_FAB2_LIB.BASEBOARD_FAB2(SCH_1):NIC_MDI_SPRV_RJ45_0_DN

RES  I57  R9G23  [RES_0402-4.75K,1%,1/16W,EMPTY,A]
    1  P3V3_STBY          A  @BASEBOARD_FAB2_LIB.BASEBOARD_FAB2(SCH_1):P3V3_STBY
    2  FM_ADC128_A0       B  @BASEBOARD_FAB2_LIB.BASEBOARD_FAB2(SCH_1):FM_ADC128_A0

RES  I81  R9G24  [RES_0402-0.0,5%,1/16W,CHIP,G21A]
    2  NIC_MDI_SPRV_RJ45_0_R_DP      B  @BASEBOARD_FAB2_LIB.BASEBOARD_FAB2(SCH_1):NIC_MDI_SPRV_RJ45_0_R_DP
    1  NIC_MDI_SPRV_RJ45_0_DP      A  @BASEBOARD_FAB2_LIB.BASEBOARD_FAB2(SCH_1):NIC_MDI_SPRV_RJ45_0_DP

RES  I58  R9G25  [RES_0402-4.75K,1%,1/16W,EMPTY,A]
    1  P3V3_STBY          A  @BASEBOARD_FAB2_LIB.BASEBOARD_FAB2(SCH_1):P3V3_STBY
    2  FM_ADC128_A1       B  @BASEBOARD_FAB2_LIB.BASEBOARD_FAB2(SCH_1):FM_ADC128_A1

RES  I106  R9G26  [RES_0402-100.0K,1%,1/16W,CHIP,A]
    2  GND                B  @BASEBOARD_FAB2_LIB.BASEBOARD_FAB2(SCH_1):GND
    1  A_P3V_BAT_SCALED      A  @BASEBOARD_FAB2_LIB.BASEBOARD_FAB2(SCH_1):A_P3V_BAT_SCALED

RES  I47  R9G27  [RES_0402-0.0,5%,1/16W,EMPTY,G2A]
    2  H_CPU0_MEMDEF_MEMHOT_LVT3_K_N      B  @BASEBOARD_FAB2_LIB.BASEBOARD_FAB2(SCH_1):H_CPU0_MEMDEF_MEMHOT_LVT3_K_N
    1  H_CPU0_MEMDEF_MEMHOT_G_PCH_N      A  @BASEBOARD_FAB2_LIB.BASEBOARD_FAB2(SCH_1):H_CPU0_MEMDEF_MEMHOT_G_PCH_N

RES  I71  R9G28  [RES_0402-0.0,5%,1/16W,CHIP,G21A]
    2  H_CPU1_MEMKLM_MEMHOT_LVT3_K_N      B  @BASEBOARD_FAB2_LIB.BASEBOARD_FAB2(SCH_1):H_CPU1_MEMKLM_MEMHOT_LVT3_K_N
    1  H_CPU1_KLM_MEMHOT_LVT3_R_N      A  @BASEBOARD_FAB2_LIB.BASEBOARD_FAB2(SCH_1):H_CPU1_KLM_MEMHOT_LVT3_R_N

RES  I92  R9G29  [RES_0402-0.0,5%,1/16W,CHIP,G21A]
    1  H_CPU0_MEMDEF_MEMHOT_LVT3_N      A  @BASEBOARD_FAB2_LIB.BASEBOARD_FAB2(SCH_1):H_CPU0_MEMDEF_MEMHOT_LVT3_N
    2  H_CPU0_MEMDEF_MEMHOT_LVT3_BMC_N      B  @BASEBOARD_FAB2_LIB.BASEBOARD_FAB2(SCH_1):H_CPU0_MEMDEF_MEMHOT_LVT3_BMC_N

RES  I98  R9G30  [RES_0402-0.0,5%,1/16W,EMPTY,G2A]
    2  H_CPU0_MEMDEF_MEMHOT_PCH_N      B  @BASEBOARD_FAB2_LIB.BASEBOARD_FAB2(SCH_1):H_CPU0_MEMDEF_MEMHOT_PCH_N
    1  H_CPU0_MEMDEF_MEMHOT_LVT3_N      A  @BASEBOARD_FAB2_LIB.BASEBOARD_FAB2(SCH_1):H_CPU0_MEMDEF_MEMHOT_LVT3_N

RES  I14  R9G31  [RES_0402-33.2,1%,1/16W,CHIP,G2A]
    2  H_CPU0_MEMDEF_MEMHOT_LVT3_N      B  @BASEBOARD_FAB2_LIB.BASEBOARD_FAB2(SCH_1):H_CPU0_MEMDEF_MEMHOT_LVT3_N
    1  H_CPU0_MEMDEF_MEMHOT_LVT3_K_N      A  @BASEBOARD_FAB2_LIB.BASEBOARD_FAB2(SCH_1):H_CPU0_MEMDEF_MEMHOT_LVT3_K_N

RES  I72  R9G32  [RES_0402-0.0,5%,1/16W,CHIP,G21A]
    2  H_CPU1_MEMGHJ_MEMHOT_LVT3_K_N      B  @BASEBOARD_FAB2_LIB.BASEBOARD_FAB2(SCH_1):H_CPU1_MEMGHJ_MEMHOT_LVT3_K_N
    1  H_CPU1_GHJ_MEMHOT_LVT3_R_N      A  @BASEBOARD_FAB2_LIB.BASEBOARD_FAB2(SCH_1):H_CPU1_GHJ_MEMHOT_LVT3_R_N

RES  I73  R9G33  [RES_0402-0.0,5%,1/16W,CHIP,G21A]
    2  H_CPU0_MEMDEF_MEMHOT_LVT3_K_N      B  @BASEBOARD_FAB2_LIB.BASEBOARD_FAB2(SCH_1):H_CPU0_MEMDEF_MEMHOT_LVT3_K_N
    1  H_CPU0_DEF_MEMHOT_LVT3_R_N      A  @BASEBOARD_FAB2_LIB.BASEBOARD_FAB2(SCH_1):H_CPU0_DEF_MEMHOT_LVT3_R_N

RES  I45  R9G34  [RES_0402-0.0,5%,1/16W,CHIP,G21A]
    2  H_CPU0_MEMABC_MEMHOT_G_R_N      B  @BASEBOARD_FAB2_LIB.BASEBOARD_FAB2(SCH_1):H_CPU0_MEMABC_MEMHOT_G_R_N
    1  H_CPU0_MEMABC_MEMHOT_G_N      A  @BASEBOARD_FAB2_LIB.BASEBOARD_FAB2(SCH_1):H_CPU0_MEMABC_MEMHOT_G_N

RES  I164  R9G35  [RES_0402-2.7K,1%,1/16W,CHIP,G2A]
    1  P3V3_STBY          A  @BASEBOARD_FAB2_LIB.BASEBOARD_FAB2(SCH_1):P3V3_STBY
    2  FM_BATTERY_SENSE_EN_N      B  @BASEBOARD_FAB2_LIB.BASEBOARD_FAB2(SCH_1):FM_BATTERY_SENSE_EN_N

RES  I40  R9L1   [RES_0402-1.00K,1%,1/16W,CHIP,GA]
    1  M_M_VREF           A  @BASEBOARD_FAB2_LIB.BASEBOARD_FAB2(SCH_1):M_M_VREF
    2  GND                B  @BASEBOARD_FAB2_LIB.BASEBOARD_FAB2(SCH_1):GND

RES  I38  R9L2   [RES_0402-1.00K,1%,1/16W,CHIP,GA]
    1  PVDDQ_KLM          A  @BASEBOARD_FAB2_LIB.BASEBOARD_FAB2(SCH_1):PVDDQ_KLM
    2  M_M_VREF           B  @BASEBOARD_FAB2_LIB.BASEBOARD_FAB2(SCH_1):M_M_VREF

RES  I45  R9L3   [RES_0402-2,1.0%,1/16W,CHIP,G21A]
    2  M_M_VREF           B  @BASEBOARD_FAB2_LIB.BASEBOARD_FAB2(SCH_1):M_M_VREF
    1  M_M_CPU_VREF       A  @BASEBOARD_FAB2_LIB.BASEBOARD_FAB2(SCH_1):M_M_CPU_VREF

RES  I76  R9L4   [RES_0402-1.0,1%,1/16W,CHIP,G21A]
    1  VR_PVDDQ_KLM_PH2_VCIN      A  @BASEBOARD_FAB2_LIB.BASEBOARD_FAB2(SCH_1):VR_PVDDQ_KLM_PH2_VCIN
    2  P5V_STBY           B  @BASEBOARD_FAB2_LIB.BASEBOARD_FAB2(SCH_1):P5V_STBY

RES  I24  R9L6   [RES_0402-1.00K,1%,1/16W,CHIP,GA]
    1  M_L_VREF           A  @BASEBOARD_FAB2_LIB.BASEBOARD_FAB2(SCH_1):M_L_VREF
    2  GND                B  @BASEBOARD_FAB2_LIB.BASEBOARD_FAB2(SCH_1):GND

RES  I22  R9L7   [RES_0402-1.00K,1%,1/16W,CHIP,GA]
    1  PVDDQ_KLM          A  @BASEBOARD_FAB2_LIB.BASEBOARD_FAB2(SCH_1):PVDDQ_KLM
    2  M_L_VREF           B  @BASEBOARD_FAB2_LIB.BASEBOARD_FAB2(SCH_1):M_L_VREF

RES  I29  R9L8   [RES_0402-2,1.0%,1/16W,CHIP,G21A]
    2  M_L_VREF           B  @BASEBOARD_FAB2_LIB.BASEBOARD_FAB2(SCH_1):M_L_VREF
    1  M_L_CPU_VREF       A  @BASEBOARD_FAB2_LIB.BASEBOARD_FAB2(SCH_1):M_L_CPU_VREF

RES  I52  R9L9   [RES_0402-1.0,1%,1/16W,CHIP,G21A]
    1  VR_PVDDQ_KLM_PH1_VCIN      A  @BASEBOARD_FAB2_LIB.BASEBOARD_FAB2(SCH_1):VR_PVDDQ_KLM_PH1_VCIN
    2  P5V_STBY           B  @BASEBOARD_FAB2_LIB.BASEBOARD_FAB2(SCH_1):P5V_STBY

RES  I4   R9L11  [RES_0402-1.00K,1%,1/16W,CHIP,GA]
    1  M_K_VREF           A  @BASEBOARD_FAB2_LIB.BASEBOARD_FAB2(SCH_1):M_K_VREF
    2  GND                B  @BASEBOARD_FAB2_LIB.BASEBOARD_FAB2(SCH_1):GND

RES  I11  R9M1   [RES_0402-1.00K,1%,1/16W,CHIP,GA]
    1  PVDDQ_KLM          A  @BASEBOARD_FAB2_LIB.BASEBOARD_FAB2(SCH_1):PVDDQ_KLM
    2  M_K_VREF           B  @BASEBOARD_FAB2_LIB.BASEBOARD_FAB2(SCH_1):M_K_VREF

RES  I13  R9M2   [RES_0402-2,1.0%,1/16W,CHIP,G21A]
    2  M_K_VREF           B  @BASEBOARD_FAB2_LIB.BASEBOARD_FAB2(SCH_1):M_K_VREF
    1  M_K_CPU_VREF       A  @BASEBOARD_FAB2_LIB.BASEBOARD_FAB2(SCH_1):M_K_CPU_VREF

RES  I30  R9M3   [RES_0402-0.0,5%,1/16W,CHIP,G21A]
    2  VR_PVDDQ_KLM_VDD      B  @BASEBOARD_FAB2_LIB.BASEBOARD_FAB2(SCH_1):VR_PVDDQ_KLM_VDD
    1  P3V3_STBY          A  @BASEBOARD_FAB2_LIB.BASEBOARD_FAB2(SCH_1):P3V3_STBY

RES  I142  R9M4   [RES_1206-0.002,1%,1W,CHIP,G521A]
    2  P12V_STBY          B  @BASEBOARD_FAB2_LIB.BASEBOARD_FAB2(SCH_1):P12V_STBY
    1  P12V_NVDIMM_KLM      A  @BASEBOARD_FAB2_LIB.BASEBOARD_FAB2(SCH_1):P12V_NVDIMM_KLM

RES  I85  R9M5   [RES_0402-100.0K,1%,1/16W,EMPTYA]
    2  VR_PVDDQ_KLM_VREN      B  @BASEBOARD_FAB2_LIB.BASEBOARD_FAB2(SCH_1):VR_PVDDQ_KLM_VREN
    1  P3V3_STBY          A  @BASEBOARD_FAB2_LIB.BASEBOARD_FAB2(SCH_1):P3V3_STBY

RES  I50  R9M6   [RES_0402-49.9,1%,1/16W,CHIP,G2A]
    2  SVID_CLK1_CPU1_R      B  @BASEBOARD_FAB2_LIB.BASEBOARD_FAB2(SCH_1):SVID_CLK1_CPU1_R
    1  PVCCIO_CPU1        A  @BASEBOARD_FAB2_LIB.BASEBOARD_FAB2(SCH_1):PVCCIO_CPU1

RES  I8   R9M7   [RES_0402-100.0,1%,1/16W,EMPTY,A]
    2  SVID_DIO1_CPU1_R      B  @BASEBOARD_FAB2_LIB.BASEBOARD_FAB2(SCH_1):SVID_DIO1_CPU1_R
    1  PVCCIO_CPU1        A  @BASEBOARD_FAB2_LIB.BASEBOARD_FAB2(SCH_1):PVCCIO_CPU1

RES  I57  R9M8   [RES_0402-100.0K,1%,1/16W,CHIP,B]
    2  VR_PVDDQ_KLM_VINSEN      B  @BASEBOARD_FAB2_LIB.BASEBOARD_FAB2(SCH_1):VR_PVDDQ_KLM_VINSEN
    1  VR_FET_SW_P12V_STBY_PVDDQ_KLM      A  @BASEBOARD_FAB2_LIB.BASEBOARD_FAB2(SCH_1):VR_FET_SW_P12V_STBY_PVDDQ_KLM

RES  I84  R9M9   [RES_0402-0.0,5%,1/16W,CHIP,G21A]
    2  VR_PVDDQ_KLM_VREN      B  @BASEBOARD_FAB2_LIB.BASEBOARD_FAB2(SCH_1):VR_PVDDQ_KLM_VREN
    1  FM_PVDDQ_KLM_EN      A  @BASEBOARD_FAB2_LIB.BASEBOARD_FAB2(SCH_1):FM_PVDDQ_KLM_EN

RES  I88  R9M10  [RES_0402-0.0,5%,1/16W,CHIP,G21A]
    1  VR_PVDDQ_KLM_VD12      A  @BASEBOARD_FAB2_LIB.BASEBOARD_FAB2(SCH_1):VR_PVDDQ_KLM_VD12
    2  VR_PVDDQ_KLM_AIREF2      B  @BASEBOARD_FAB2_LIB.BASEBOARD_FAB2(SCH_1):VR_PVDDQ_KLM_AIREF2

RES  I87  R9M11  [RES_0402-0.0,5%,1/16W,CHIP,G21A]
    1  VR_PVDDQ_KLM_VD12      A  @BASEBOARD_FAB2_LIB.BASEBOARD_FAB2(SCH_1):VR_PVDDQ_KLM_VD12
    2  VR_PVDDQ_KLM_AIREF1      B  @BASEBOARD_FAB2_LIB.BASEBOARD_FAB2(SCH_1):VR_PVDDQ_KLM_AIREF1

RES  I24  R9M12  [RES_0402-20.0,1%,1/16W,CHIP,G2A]
    2  SMB_SLOTX24_BMC_STBY_LVC3_SDA      B  @BASEBOARD_FAB2_LIB.BASEBOARD_FAB2(SCH_1):SMB_SLOTX24_BMC_STBY_LVC3_SDA
    1  SMB_PEHPCPU1_STBY_LVC3_R_SDA      A  @BASEBOARD_FAB2_LIB.BASEBOARD_FAB2(SCH_1):SMB_PEHPCPU1_STBY_LVC3_R_SDA

RES  I21  R9M13  [RES_0402-20.0,1%,1/16W,CHIP,G2A]
    2  SMB_PEHPCPU1_STBY_LVC3_SDA      B  @BASEBOARD_FAB2_LIB.BASEBOARD_FAB2(SCH_1):SMB_PEHPCPU1_STBY_LVC3_SDA
    1  SMB_PEHPCPU1_STBY_LVC3_R_SDA      A  @BASEBOARD_FAB2_LIB.BASEBOARD_FAB2(SCH_1):SMB_PEHPCPU1_STBY_LVC3_R_SDA

RES  I20  R9M14  [RES_0402-20.0,1%,1/16W,CHIP,G2A]
    2  SMB_PEHPCPU1_STBY_LVC3_SCL      B  @BASEBOARD_FAB2_LIB.BASEBOARD_FAB2(SCH_1):SMB_PEHPCPU1_STBY_LVC3_SCL
    1  SMB_PEHPCPU1_STBY_LVC3_R_SCL      A  @BASEBOARD_FAB2_LIB.BASEBOARD_FAB2(SCH_1):SMB_PEHPCPU1_STBY_LVC3_R_SCL

RES  I25  R9M15  [RES_0402-20.0,1%,1/16W,CHIP,G2A]
    2  SMB_SLOTX24_BMC_STBY_LVC3_SCL      B  @BASEBOARD_FAB2_LIB.BASEBOARD_FAB2(SCH_1):SMB_SLOTX24_BMC_STBY_LVC3_SCL
    1  SMB_PEHPCPU1_STBY_LVC3_R_SCL      A  @BASEBOARD_FAB2_LIB.BASEBOARD_FAB2(SCH_1):SMB_PEHPCPU1_STBY_LVC3_R_SCL

RES  I16  R9M16  [RES_0402-2.0K,1%,1/16W,CHIP,G2A]
    2  SMB_PEHPCPU1_STBY_LVC3_R_SDA      B  @BASEBOARD_FAB2_LIB.BASEBOARD_FAB2(SCH_1):SMB_PEHPCPU1_STBY_LVC3_R_SDA
    1  P3V3_STBY          A  @BASEBOARD_FAB2_LIB.BASEBOARD_FAB2(SCH_1):P3V3_STBY

RES  I15  R9M17  [RES_0402-2.0K,1%,1/16W,CHIP,G2A]
    2  SMB_PEHPCPU1_STBY_LVC3_R_SCL      B  @BASEBOARD_FAB2_LIB.BASEBOARD_FAB2(SCH_1):SMB_PEHPCPU1_STBY_LVC3_R_SCL
    1  P3V3_STBY          A  @BASEBOARD_FAB2_LIB.BASEBOARD_FAB2(SCH_1):P3V3_STBY

RES  I6   R9M18  [RES_0402-240,1.0%,1/16W,CHIP,GA]
    2  SMB_CPU1_PE_HP_GTL_R_SDA      B  @BASEBOARD_FAB2_LIB.BASEBOARD_FAB2(SCH_1):SMB_CPU1_PE_HP_GTL_R_SDA
    1  PVCCIO_CPU1        A  @BASEBOARD_FAB2_LIB.BASEBOARD_FAB2(SCH_1):PVCCIO_CPU1

RES  I7   R9M19  [RES_0402-240,1.0%,1/16W,CHIP,GA]
    2  SMB_CPU1_PE_HP_GTL_R_SCL      B  @BASEBOARD_FAB2_LIB.BASEBOARD_FAB2(SCH_1):SMB_CPU1_PE_HP_GTL_R_SCL
    1  PVCCIO_CPU1        A  @BASEBOARD_FAB2_LIB.BASEBOARD_FAB2(SCH_1):PVCCIO_CPU1

RES  I323  R9M20  [RES_0402-0.0,5%,1/16W,CHIP,G21A]
    2  SMB_PIROM_CPU1_SCL      B  @BASEBOARD_FAB2_LIB.BASEBOARD_FAB2(SCH_1):SMB_PIROM_CPU1_SCL
    1  SMB_LAN_STBY_LVC3_SCL      A  @BASEBOARD_FAB2_LIB.BASEBOARD_FAB2(SCH_1):SMB_LAN_STBY_LVC3_SCL

RES  I321  R9M21  [RES_0402-0.0,5%,1/16W,CHIP,G21A]
    2  SMB_PIROM_CPU1_SDA      B  @BASEBOARD_FAB2_LIB.BASEBOARD_FAB2(SCH_1):SMB_PIROM_CPU1_SDA
    1  SMB_LAN_STBY_LVC3_SDA      A  @BASEBOARD_FAB2_LIB.BASEBOARD_FAB2(SCH_1):SMB_LAN_STBY_LVC3_SDA

RES  I4   R9N1   [RES_0402-49.9,1%,1/16W,CHIP,G2A]
    2  SVID_ALERT1_CPU1_R_N      B  @BASEBOARD_FAB2_LIB.BASEBOARD_FAB2(SCH_1):SVID_ALERT1_CPU1_R_N
    1  PVCCIO_CPU1        A  @BASEBOARD_FAB2_LIB.BASEBOARD_FAB2(SCH_1):PVCCIO_CPU1

RES  I7   R9N2   [RES_0402-100.0,1%,1/16W,CHIP,GA]
    2  SVID_DIO1_CPU1_R      B  @BASEBOARD_FAB2_LIB.BASEBOARD_FAB2(SCH_1):SVID_DIO1_CPU1_R
    1  PVCCIO_CPU1        A  @BASEBOARD_FAB2_LIB.BASEBOARD_FAB2(SCH_1):PVCCIO_CPU1

RES  I20  R9N3   [RES_0402-1.0,1%,1/16W,CHIP,G21A]
    1  VR_PVSA_CPU1_VCIN      A  @BASEBOARD_FAB2_LIB.BASEBOARD_FAB2(SCH_1):VR_PVSA_CPU1_VCIN
    2  P5V_STBY           B  @BASEBOARD_FAB2_LIB.BASEBOARD_FAB2(SCH_1):P5V_STBY

RES  I45  R9N4   [RES_0402-51.1,1.0%,1/16W,CHIP,A]
    1  PVSA_CPU1          A  @BASEBOARD_FAB2_LIB.BASEBOARD_FAB2(SCH_1):PVSA_CPU1
    2  GND                B  @BASEBOARD_FAB2_LIB.BASEBOARD_FAB2(SCH_1):GND

RES  I128  R9N5   [RES_0402-0.0,5%,1/16W,CHIP,G21A]
    2  VR_PVSA_CPU1_BIREF1      B  @BASEBOARD_FAB2_LIB.BASEBOARD_FAB2(SCH_1):VR_PVSA_CPU1_BIREF1
    1  VR_PVCCIN_CPU1_VD12      A  @BASEBOARD_FAB2_LIB.BASEBOARD_FAB2(SCH_1):VR_PVCCIN_CPU1_VD12

RES  I111  R9N7   [RES_0402-3.16K,1%,1/16W,CHIP,GA]
    1  VR_PVCCIN_CPU1_XADDR2      A  @BASEBOARD_FAB2_LIB.BASEBOARD_FAB2(SCH_1):VR_PVCCIN_CPU1_XADDR2
    2  GND                B  @BASEBOARD_FAB2_LIB.BASEBOARD_FAB2(SCH_1):GND

RES  I112  R9N8   [RES_0402-4.02K,1%,1/16W,CHIP,GA]
    1  VR_PVCCIN_CPU1_XADDR1      A  @BASEBOARD_FAB2_LIB.BASEBOARD_FAB2(SCH_1):VR_PVCCIN_CPU1_XADDR1
    2  GND                B  @BASEBOARD_FAB2_LIB.BASEBOARD_FAB2(SCH_1):GND

RES  I126  R9N9   [RES_0402-0.0,5%,1/16W,CHIP,G21A]
    1  VR_PVCCIN_CPU1_VD12      A  @BASEBOARD_FAB2_LIB.BASEBOARD_FAB2(SCH_1):VR_PVCCIN_CPU1_VD12
    2  VR_PVCCIN_CPU1_AIREF5      B  @BASEBOARD_FAB2_LIB.BASEBOARD_FAB2(SCH_1):VR_PVCCIN_CPU1_AIREF5

RES  I125  R9N10  [RES_0402-0.0,5%,1/16W,CHIP,G21A]
    1  VR_PVCCIN_CPU1_VD12      A  @BASEBOARD_FAB2_LIB.BASEBOARD_FAB2(SCH_1):VR_PVCCIN_CPU1_VD12
    2  VR_PVCCIN_CPU1_AIREF4      B  @BASEBOARD_FAB2_LIB.BASEBOARD_FAB2(SCH_1):VR_PVCCIN_CPU1_AIREF4

RES  I124  R9N12  [RES_0402-0.0,5%,1/16W,CHIP,G21A]
    1  VR_PVCCIN_CPU1_VD12      A  @BASEBOARD_FAB2_LIB.BASEBOARD_FAB2(SCH_1):VR_PVCCIN_CPU1_VD12
    2  VR_PVCCIN_CPU1_AIREF3      B  @BASEBOARD_FAB2_LIB.BASEBOARD_FAB2(SCH_1):VR_PVCCIN_CPU1_AIREF3

RES  I120  R9N14  [RES_0402-1.00K,1%,1/16W,CHIP,GA]
    2  VR_PVCCIN_CPU1_VREN      B  @BASEBOARD_FAB2_LIB.BASEBOARD_FAB2(SCH_1):VR_PVCCIN_CPU1_VREN
    1  PVCCIO_CPU1        A  @BASEBOARD_FAB2_LIB.BASEBOARD_FAB2(SCH_1):PVCCIO_CPU1

RES  I122  R9N15  [RES_0402-0.0,5%,1/16W,CHIP,G21A]
    1  VR_PVCCIN_CPU1_VD12      A  @BASEBOARD_FAB2_LIB.BASEBOARD_FAB2(SCH_1):VR_PVCCIN_CPU1_VD12
    2  VR_PVCCIN_CPU1_AIREF1      B  @BASEBOARD_FAB2_LIB.BASEBOARD_FAB2(SCH_1):VR_PVCCIN_CPU1_AIREF1

RES  I119  R9N16  [RES_0402-0.0,5%,1/16W,CHIP,G21A]
    2  VR_PVCCIN_CPU1_VREN      B  @BASEBOARD_FAB2_LIB.BASEBOARD_FAB2(SCH_1):VR_PVCCIN_CPU1_VREN
    1  FM_PVCCIN_PVCCSA_CPU1_EN_LVC1      A  @BASEBOARD_FAB2_LIB.BASEBOARD_FAB2(SCH_1):FM_PVCCIN_PVCCSA_CPU1_EN_LVC1

RES  I123  R9N17  [RES_0402-0.0,5%,1/16W,CHIP,G21A]
    1  VR_PVCCIN_CPU1_VD12      A  @BASEBOARD_FAB2_LIB.BASEBOARD_FAB2(SCH_1):VR_PVCCIN_CPU1_VD12
    2  VR_PVCCIN_CPU1_AIREF2      B  @BASEBOARD_FAB2_LIB.BASEBOARD_FAB2(SCH_1):VR_PVCCIN_CPU1_AIREF2

RES  I4   R9P1   [RES_0402-100.0,1%,1/16W,CHIP,GA]
    2  SVID_DIO0_CPU1_R      B  @BASEBOARD_FAB2_LIB.BASEBOARD_FAB2(SCH_1):SVID_DIO0_CPU1_R
    1  PVCCIO_CPU1        A  @BASEBOARD_FAB2_LIB.BASEBOARD_FAB2(SCH_1):PVCCIO_CPU1

RES  I53  R9P2   [RES_0402-49.9,1%,1/16W,CHIP,G2A]
    2  SVID_CLK0_CPU1_R      B  @BASEBOARD_FAB2_LIB.BASEBOARD_FAB2(SCH_1):SVID_CLK0_CPU1_R
    1  PVCCIO_CPU1        A  @BASEBOARD_FAB2_LIB.BASEBOARD_FAB2(SCH_1):PVCCIO_CPU1

RES  I117  R9P3   [RES_0402-33.2,1%,1/16W,CHIP,G2A]
    1  IRQ_PVCCIN_CPU1_VRHOT_LVC3_R_N      A  @BASEBOARD_FAB2_LIB.BASEBOARD_FAB2(SCH_1):IRQ_PVCCIN_CPU1_VRHOT_LVC3_R_N
    2  IRQ_PVCCIN_CPU1_VRHOT_LVC3_N      B  @BASEBOARD_FAB2_LIB.BASEBOARD_FAB2(SCH_1):IRQ_PVCCIN_CPU1_VRHOT_LVC3_N

RES  I210  R9P4   [RES_0402-2.7K,1%,1/16W,CHIP,G2A]
    1  P3V3_STBY          A  @BASEBOARD_FAB2_LIB.BASEBOARD_FAB2(SCH_1):P3V3_STBY
    2  IRQ_UV_DETECT_N      B  @BASEBOARD_FAB2_LIB.BASEBOARD_FAB2(SCH_1):IRQ_UV_DETECT_N

RES  I215  R9P5   [RES_0402-10.0K,1%,1/16W,CHIP,GA]
    1  P3V3_STBY          A  @BASEBOARD_FAB2_LIB.BASEBOARD_FAB2(SCH_1):P3V3_STBY
    2  FM_DISABLE_FAN_N      B  @BASEBOARD_FAB2_LIB.BASEBOARD_FAB2(SCH_1):FM_DISABLE_FAN_N

RES  I149  R9P6   [RES_0402-10.0K,1%,1/16W,CHIP,GA]
    1  P3V3_STBY          A  @BASEBOARD_FAB2_LIB.BASEBOARD_FAB2(SCH_1):P3V3_STBY
    2  FM_UV_ADR_TRIGGER_N      B  @BASEBOARD_FAB2_LIB.BASEBOARD_FAB2(SCH_1):FM_UV_ADR_TRIGGER_N

RES  I145  R9P7   [RES_0402-249K,1.0%,1/16W,CHIP,A]
    1  P12V_STBY          A  @BASEBOARD_FAB2_LIB.BASEBOARD_FAB2(SCH_1):P12V_STBY
    2  A_P12V_STBY_ADR_TRIGGER      B  @BASEBOARD_FAB2_LIB.BASEBOARD_FAB2(SCH_1):A_P12V_STBY_ADR_TRIGGER

RES  I49  R9P8   [RES_0402-1.0,1%,1/16W,CHIP,G21A]
    1  VR_PVCCIN_CPU1_PH4_VCIN      A  @BASEBOARD_FAB2_LIB.BASEBOARD_FAB2(SCH_1):VR_PVCCIN_CPU1_PH4_VCIN
    2  P5V_STBY           B  @BASEBOARD_FAB2_LIB.BASEBOARD_FAB2(SCH_1):P5V_STBY

RES  I146  R9P9   [RES_0402-10.0K,1%,1/16W,CHIP,GA]
    1  A_P12V_STBY_ADR_TRIGGER      A  @BASEBOARD_FAB2_LIB.BASEBOARD_FAB2(SCH_1):A_P12V_STBY_ADR_TRIGGER
    2  AGND_HSC           B  @BASEBOARD_FAB2_LIB.BASEBOARD_FAB2(SCH_1):AGND_HSC

RES  I192  R9P10  [RES_0402-10.0K,1%,1/16W,CHIP,GA]
    1  P3V3_STBY          A  @BASEBOARD_FAB2_LIB.BASEBOARD_FAB2(SCH_1):P3V3_STBY
    2  A_P12V_STBY_FPH_GATE      B  @BASEBOARD_FAB2_LIB.BASEBOARD_FAB2(SCH_1):A_P12V_STBY_FPH_GATE

RES  I108  R9P11  [RES_0402-10.0K,1%,1/16W,CHIP,GA]
    1  A_P12V_STBY_FP_TRIGGER      A  @BASEBOARD_FAB2_LIB.BASEBOARD_FAB2(SCH_1):A_P12V_STBY_FP_TRIGGER
    2  AGND_HSC           B  @BASEBOARD_FAB2_LIB.BASEBOARD_FAB2(SCH_1):AGND_HSC

RES  I218  R9P12  [RES_0402-4.99K,1%,1/16W,CHIP,GA]
    1  A_HSC_INAP         A  @BASEBOARD_FAB2_LIB.BASEBOARD_FAB2(SCH_1):A_HSC_INAP
    2  AGND_HSC           B  @BASEBOARD_FAB2_LIB.BASEBOARD_FAB2(SCH_1):AGND_HSC

RES  I107  R9P13  [RES_0402-274K,1.0%,1/16W,CHIP,A]
    1  P12V_STBY          A  @BASEBOARD_FAB2_LIB.BASEBOARD_FAB2(SCH_1):P12V_STBY
    2  A_P12V_STBY_FP_TRIGGER      B  @BASEBOARD_FAB2_LIB.BASEBOARD_FAB2(SCH_1):A_P12V_STBY_FP_TRIGGER

RES  I198  R9P15  [RES_0402-0.0,5%,1/16W,EMPTY,G2A]
    2  IRQ_OC_DETECT_N      B  @BASEBOARD_FAB2_LIB.BASEBOARD_FAB2(SCH_1):IRQ_OC_DETECT_N
    1  A_HSC_LOW_DRAIN      A  @BASEBOARD_FAB2_LIB.BASEBOARD_FAB2(SCH_1):A_HSC_LOW_DRAIN

RES  I36  R9P16  [RES_0402-0.0,5%,1/16W,CHIP,G21A]
    1  FM_P12V_HSC_ADR2      A  @BASEBOARD_FAB2_LIB.BASEBOARD_FAB2(SCH_1):FM_P12V_HSC_ADR2
    2  AGND_HSC           B  @BASEBOARD_FAB2_LIB.BASEBOARD_FAB2(SCH_1):AGND_HSC

RES  I33  R9P17  [RES_0402-150.0K,1%,1/16W,CHIP,A]
    1  FM_P12V_HSC_ADR1      A  @BASEBOARD_FAB2_LIB.BASEBOARD_FAB2(SCH_1):FM_P12V_HSC_ADR1
    2  AGND_HSC           B  @BASEBOARD_FAB2_LIB.BASEBOARD_FAB2(SCH_1):AGND_HSC

RES  I41  R9P18  [RES_0402-15.0K,1%,1/16W,CHIP,GA]
    2  PWRGD_P12V_R       B  @BASEBOARD_FAB2_LIB.BASEBOARD_FAB2(SCH_1):PWRGD_P12V_R
    1  P12V_STBY          A  @BASEBOARD_FAB2_LIB.BASEBOARD_FAB2(SCH_1):P12V_STBY

RES  I70  R9P19  [RES_0402-10.0K,1%,1/16W,EMPTY,A]
    1  A_HSC_TIMER_R      A  @BASEBOARD_FAB2_LIB.BASEBOARD_FAB2(SCH_1):A_HSC_TIMER_R
    2  AGND_HSC           B  @BASEBOARD_FAB2_LIB.BASEBOARD_FAB2(SCH_1):AGND_HSC

RES  I86  R9P20  [RES_0402-2.7K,1%,1/16W,CHIP,G2A]
    1  P3V3_STBY          A  @BASEBOARD_FAB2_LIB.BASEBOARD_FAB2(SCH_1):P3V3_STBY
    2  FM_HSC_TIMER_EXP_N      B  @BASEBOARD_FAB2_LIB.BASEBOARD_FAB2(SCH_1):FM_HSC_TIMER_EXP_N

RES  I71  R9P21  [RES_0402-0.0,5%,1/16W,CHIP,G21A]
    2  A_HSC_TIMER_R      B  @BASEBOARD_FAB2_LIB.BASEBOARD_FAB2(SCH_1):A_HSC_TIMER_R
    1  A_HSC_TIMER        A  @BASEBOARD_FAB2_LIB.BASEBOARD_FAB2(SCH_1):A_HSC_TIMER

RES  I36  R9P22  [RES_0402-1.0,1%,1/16W,CHIP,G21A]
    1  VR_PVCCIN_CPU1_PH3_VCIN      A  @BASEBOARD_FAB2_LIB.BASEBOARD_FAB2(SCH_1):VR_PVCCIN_CPU1_PH3_VCIN
    2  P5V_STBY           B  @BASEBOARD_FAB2_LIB.BASEBOARD_FAB2(SCH_1):P5V_STBY

RES  I54  R9P23  [RES_0402-100.0K,1%,1/16W,CHIP,A]
    1  P12V_STBY          A  @BASEBOARD_FAB2_LIB.BASEBOARD_FAB2(SCH_1):P12V_STBY
    2  A_HSC_PWGIN        B  @BASEBOARD_FAB2_LIB.BASEBOARD_FAB2(SCH_1):A_HSC_PWGIN

RES  I55  R9P24  [RES_0402-12.1K,1%,1/16W,CHIP,GA]
    1  A_HSC_PWGIN        A  @BASEBOARD_FAB2_LIB.BASEBOARD_FAB2(SCH_1):A_HSC_PWGIN
    2  AGND_HSC           B  @BASEBOARD_FAB2_LIB.BASEBOARD_FAB2(SCH_1):AGND_HSC

RES  I51  R9P26  [RES_0402-10.0,1%,1/16W,CHIP,G2A]
    1  P12V_HSC_SENN1      A  @BASEBOARD_FAB2_LIB.BASEBOARD_FAB2(SCH_1):P12V_HSC_SENN1
    2  A_HSC_HSN          B  @BASEBOARD_FAB2_LIB.BASEBOARD_FAB2(SCH_1):A_HSC_HSN

RES  I47  R9P27  [RES_0402-10.0,1%,1/16W,CHIP,G2A]
    1  P12V_HSC_SENP1      A  @BASEBOARD_FAB2_LIB.BASEBOARD_FAB2(SCH_1):P12V_HSC_SENP1
    2  A_HSC_HSP          B  @BASEBOARD_FAB2_LIB.BASEBOARD_FAB2(SCH_1):A_HSC_HSP

RES  I6   R9P28  [RES_0402-100.0K,1%,1/16W,CHIP,A]
    1  P12V_PSU           A  @BASEBOARD_FAB2_LIB.BASEBOARD_FAB2(SCH_1):P12V_PSU
    2  A_HSC_OV           B  @BASEBOARD_FAB2_LIB.BASEBOARD_FAB2(SCH_1):A_HSC_OV

RES  I12  R9P29  [RES_0402-100.0K,1%,1/16W,CHIP,A]
    1  P12V_PSU           A  @BASEBOARD_FAB2_LIB.BASEBOARD_FAB2(SCH_1):P12V_PSU
    2  A_HSC_UV           B  @BASEBOARD_FAB2_LIB.BASEBOARD_FAB2(SCH_1):A_HSC_UV

RES  I2   R9P30  [RES_0603-10.0,1%,1/10W,CHIP,G2A]
    1  P12V_PSU           A  @BASEBOARD_FAB2_LIB.BASEBOARD_FAB2(SCH_1):P12V_PSU
    2  P12V_HSC_VCC       B  @BASEBOARD_FAB2_LIB.BASEBOARD_FAB2(SCH_1):P12V_HSC_VCC

RES  I24  R9P32  [RES_0402-1.0,1%,1/16W,CHIP,G21A]
    1  VR_PVCCIN_CPU1_PH5_VCIN      A  @BASEBOARD_FAB2_LIB.BASEBOARD_FAB2(SCH_1):VR_PVCCIN_CPU1_PH5_VCIN
    2  P5V_STBY           B  @BASEBOARD_FAB2_LIB.BASEBOARD_FAB2(SCH_1):P5V_STBY

RES  I222  R9P33  [RES_0402-100.0K,1%,1/16W,CHIP,A]
    1  P12V_STBY          A  @BASEBOARD_FAB2_LIB.BASEBOARD_FAB2(SCH_1):P12V_STBY
    2  A_HSC_INAP         B  @BASEBOARD_FAB2_LIB.BASEBOARD_FAB2(SCH_1):A_HSC_INAP

RES_PWR_6PAD  I49  R9R1   [RES_PWR_6PAD-0.001,1%,3W,CHIP,A]
    5  P12V_PSU           5  @BASEBOARD_FAB2_LIB.BASEBOARD_FAB2(SCH_1):P12V_PSU
    1  P12V_PSU           1  @BASEBOARD_FAB2_LIB.BASEBOARD_FAB2(SCH_1):P12V_PSU
    6  P12V_MB0_SW        6  @BASEBOARD_FAB2_LIB.BASEBOARD_FAB2(SCH_1):P12V_MB0_SW
    2  P12V_MB0_SW        2  @BASEBOARD_FAB2_LIB.BASEBOARD_FAB2(SCH_1):P12V_MB0_SW
    3  P12V_HSC_SENP1      3  @BASEBOARD_FAB2_LIB.BASEBOARD_FAB2(SCH_1):P12V_HSC_SENP1
    4  P12V_HSC_SENN1      4  @BASEBOARD_FAB2_LIB.BASEBOARD_FAB2(SCH_1):P12V_HSC_SENN1

RES  I26  R9R2   [RES_0402-1.0,1%,1/16W,CHIP,G21A]
    1  VR_PVCCIN_CPU1_PH1_VCIN      A  @BASEBOARD_FAB2_LIB.BASEBOARD_FAB2(SCH_1):VR_PVCCIN_CPU1_PH1_VCIN
    2  P5V_STBY           B  @BASEBOARD_FAB2_LIB.BASEBOARD_FAB2(SCH_1):P5V_STBY

RES  I58  R9R4   [RES_0402-10.0,1%,1/16W,CHIP,G2A]
    2  A_HSC_GATE2_R      B  @BASEBOARD_FAB2_LIB.BASEBOARD_FAB2(SCH_1):A_HSC_GATE2_R
    1  A_HSC_GATE         A  @BASEBOARD_FAB2_LIB.BASEBOARD_FAB2(SCH_1):A_HSC_GATE

RES  I25  R9R5   [RES_0402-49.9,1%,1/16W,CHIP,G2A]
    1  ISENSE_TMP421_2_E      A  @BASEBOARD_FAB2_LIB.BASEBOARD_FAB2(SCH_1):ISENSE_TMP421_2_E
    2  ISENSE_TMP421_2_DXP      B  @BASEBOARD_FAB2_LIB.BASEBOARD_FAB2(SCH_1):ISENSE_TMP421_2_DXP

RES  I26  R9R6   [RES_0402-49.9,1%,1/16W,CHIP,G2A]
    2  ISENSE_TMP421_2_DXN      B  @BASEBOARD_FAB2_LIB.BASEBOARD_FAB2(SCH_1):ISENSE_TMP421_2_DXN
    1  ISENSE_TMP421_2_BC      A  @BASEBOARD_FAB2_LIB.BASEBOARD_FAB2(SCH_1):ISENSE_TMP421_2_BC

RES  I75  R9R7   [RES_0402-20.0,1%,1/16W,CHIP,G2A]
    1  SMB_SENSOR_TMP421_2_SCL      A  @BASEBOARD_FAB2_LIB.BASEBOARD_FAB2(SCH_1):SMB_SENSOR_TMP421_2_SCL
    2  SMB_SENSOR_STBY_LVC3_SCL      B  @BASEBOARD_FAB2_LIB.BASEBOARD_FAB2(SCH_1):SMB_SENSOR_STBY_LVC3_SCL

RES  I76  R9R8   [RES_0402-20.0,1%,1/16W,CHIP,G2A]
    1  SMB_SENSOR_TMP421_2_SDA      A  @BASEBOARD_FAB2_LIB.BASEBOARD_FAB2(SCH_1):SMB_SENSOR_TMP421_2_SDA
    2  SMB_SENSOR_STBY_LVC3_SDA      B  @BASEBOARD_FAB2_LIB.BASEBOARD_FAB2(SCH_1):SMB_SENSOR_STBY_LVC3_SDA

RES  I254  R9R9   [RES_0402-0.0,5%,1/16W,CHIP,G21A]
    2  FAN_TACH3_R        B  @BASEBOARD_FAB2_LIB.BASEBOARD_FAB2(SCH_1):FAN_TACH3_R
    1  FAN_TACH3          A  @BASEBOARD_FAB2_LIB.BASEBOARD_FAB2(SCH_1):FAN_TACH3

RES  I256  R9R10  [RES_0402-0.0,5%,1/16W,CHIP,G21A]
    2  FAN_TACH1_R        B  @BASEBOARD_FAB2_LIB.BASEBOARD_FAB2(SCH_1):FAN_TACH1_R
    1  FAN_TACH1          A  @BASEBOARD_FAB2_LIB.BASEBOARD_FAB2(SCH_1):FAN_TACH1

RES  I39  R9R11  [RES_0402-1.0,1%,1/16W,CHIP,G21A]
    1  VR_PVCCIN_CPU1_PH2_VCIN      A  @BASEBOARD_FAB2_LIB.BASEBOARD_FAB2(SCH_1):VR_PVCCIN_CPU1_PH2_VCIN
    2  P5V_STBY           B  @BASEBOARD_FAB2_LIB.BASEBOARD_FAB2(SCH_1):P5V_STBY

RES  I255  R9R12  [RES_0402-0.0,5%,1/16W,CHIP,G21A]
    2  FAN_TACH2_R        B  @BASEBOARD_FAB2_LIB.BASEBOARD_FAB2(SCH_1):FAN_TACH2_R
    1  FAN_TACH2          A  @BASEBOARD_FAB2_LIB.BASEBOARD_FAB2(SCH_1):FAN_TACH2

RES  I261  R9T1   [RES_0402-0.0,5%,1/16W,CHIP,G21A]
    2  FAN_PWM_OUT_SYS0_R1      B  @BASEBOARD_FAB2_LIB.BASEBOARD_FAB2(SCH_1):FAN_PWM_OUT_SYS0_R1
    1  FAN_PWM_OUT_SYS0_R      A  @BASEBOARD_FAB2_LIB.BASEBOARD_FAB2(SCH_1):FAN_PWM_OUT_SYS0_R

RES  I185  R9T3   [RES_0402-6.19K,1%,1/16W,CHIP,GA]
    2  GND                B  @BASEBOARD_FAB2_LIB.BASEBOARD_FAB2(SCH_1):GND
    1  FM_P12V_HOTSWAP0_EN      A  @BASEBOARD_FAB2_LIB.BASEBOARD_FAB2(SCH_1):FM_P12V_HOTSWAP0_EN

RES  I126  R9T4   [RES_0402-0.0,5%,1/16W,CHIP,G21A]
    1  VR_PVDDQ_GHJ_AIINSEN_R      A  @BASEBOARD_FAB2_LIB.BASEBOARD_FAB2(SCH_1):VR_PVDDQ_GHJ_AIINSEN_R
    2  VR_PVDDQ_GHJ_AIINSEN      B  @BASEBOARD_FAB2_LIB.BASEBOARD_FAB2(SCH_1):VR_PVDDQ_GHJ_AIINSEN

RES  I135  R9T5   [RES_0402-4.75K,1%,1/16W,CHIP,GA]
    1  P3V3_STBY          A  @BASEBOARD_FAB2_LIB.BASEBOARD_FAB2(SCH_1):P3V3_STBY
    2  FAN_TACH1          B  @BASEBOARD_FAB2_LIB.BASEBOARD_FAB2(SCH_1):FAN_TACH1

RES  I183  R9T6   [RES_0402-15.0K,1%,1/16W,CHIP,GA]
    1  P12V_PSU           A  @BASEBOARD_FAB2_LIB.BASEBOARD_FAB2(SCH_1):P12V_PSU
    2  FM_P12V_HOTSWAP0_EN      B  @BASEBOARD_FAB2_LIB.BASEBOARD_FAB2(SCH_1):FM_P12V_HOTSWAP0_EN

RES  I134  R9T7   [RES_0402-100.0,1%,1/16W,CHIP,GA]
    2  FAN_TACH1_CPU1_D2      B  @BASEBOARD_FAB2_LIB.BASEBOARD_FAB2(SCH_1):FAN_TACH1_CPU1_D2
    1  FAN_TACH1          A  @BASEBOARD_FAB2_LIB.BASEBOARD_FAB2(SCH_1):FAN_TACH1

RES  I249  R9T8   [RES_0402-0.0,5%,1/16W,EMPTY,G2A]
    2  GND                B  @BASEBOARD_FAB2_LIB.BASEBOARD_FAB2(SCH_1):GND
    1  FM_MATED_IN_N      A  @BASEBOARD_FAB2_LIB.BASEBOARD_FAB2(SCH_1):FM_MATED_IN_N

RES  I177  R9T9   [RES_0402-4.75K,1%,1/16W,CHIP,GA]
    1  P12V_PSU           A  @BASEBOARD_FAB2_LIB.BASEBOARD_FAB2(SCH_1):P12V_PSU
    2  FM_MATED_IN_N      B  @BASEBOARD_FAB2_LIB.BASEBOARD_FAB2(SCH_1):FM_MATED_IN_N

RES  I52  R9U1   [RES_0402-1.0,1%,1/16W,CHIP,G21A]
    1  VR_PVDDQ_GHJ_PH1_VCIN      A  @BASEBOARD_FAB2_LIB.BASEBOARD_FAB2(SCH_1):VR_PVDDQ_GHJ_PH1_VCIN
    2  P5V_STBY           B  @BASEBOARD_FAB2_LIB.BASEBOARD_FAB2(SCH_1):P5V_STBY

RES  I8   R9U3   [RES_0402-100.0,1%,1/16W,CHIP,GA]
    2  SVID_DIO1_CPU1_R      B  @BASEBOARD_FAB2_LIB.BASEBOARD_FAB2(SCH_1):SVID_DIO1_CPU1_R
    1  PVCCIO_CPU1        A  @BASEBOARD_FAB2_LIB.BASEBOARD_FAB2(SCH_1):PVCCIO_CPU1

RES  I50  R9U4   [RES_0402-49.9,1%,1/16W,EMPTY,GA]
    2  SVID_CLK1_CPU1_R      B  @BASEBOARD_FAB2_LIB.BASEBOARD_FAB2(SCH_1):SVID_CLK1_CPU1_R
    1  PVCCIO_CPU1        A  @BASEBOARD_FAB2_LIB.BASEBOARD_FAB2(SCH_1):PVCCIO_CPU1

RES  I84  R9U7   [RES_0402-0.0,5%,1/16W,CHIP,G21A]
    2  VR_PVDDQ_GHJ_VREN      B  @BASEBOARD_FAB2_LIB.BASEBOARD_FAB2(SCH_1):VR_PVDDQ_GHJ_VREN
    1  FM_PVDDQ_GHJ_EN      A  @BASEBOARD_FAB2_LIB.BASEBOARD_FAB2(SCH_1):FM_PVDDQ_GHJ_EN

RES  I85  R9U8   [RES_0402-100.0K,1%,1/16W,EMPTYA]
    2  VR_PVDDQ_GHJ_VREN      B  @BASEBOARD_FAB2_LIB.BASEBOARD_FAB2(SCH_1):VR_PVDDQ_GHJ_VREN
    1  P3V3_STBY          A  @BASEBOARD_FAB2_LIB.BASEBOARD_FAB2(SCH_1):P3V3_STBY

RES  I30  R9U10  [RES_0402-0.0,5%,1/16W,CHIP,G21A]
    2  VR_PVDDQ_GHJ_VDD      B  @BASEBOARD_FAB2_LIB.BASEBOARD_FAB2(SCH_1):VR_PVDDQ_GHJ_VDD
    1  P3V3_STBY          A  @BASEBOARD_FAB2_LIB.BASEBOARD_FAB2(SCH_1):P3V3_STBY

RES  I57  R9U11  [RES_0402-100.0K,1%,1/16W,CHIP,B]
    2  VR_PVDDQ_GHJ_VINSEN      B  @BASEBOARD_FAB2_LIB.BASEBOARD_FAB2(SCH_1):VR_PVDDQ_GHJ_VINSEN
    1  VR_FET_SW_P12V_STBY_PVDDQ_GHJ      A  @BASEBOARD_FAB2_LIB.BASEBOARD_FAB2(SCH_1):VR_FET_SW_P12V_STBY_PVDDQ_GHJ

RES  I76  R9U12  [RES_0402-1.0,1%,1/16W,CHIP,G21A]
    1  VR_PVDDQ_GHJ_PH2_VCIN      A  @BASEBOARD_FAB2_LIB.BASEBOARD_FAB2(SCH_1):VR_PVDDQ_GHJ_PH2_VCIN
    2  P5V_STBY           B  @BASEBOARD_FAB2_LIB.BASEBOARD_FAB2(SCH_1):P5V_STBY

CONN3_G98259001_PIP  I26  RM1E1  [CONN3_G98259001_PIP-CONN,G9825A]
    3  GND              IO3  @BASEBOARD_FAB2_LIB.BASEBOARD_FAB2(SCH_1):GND
    2  GND              IO2  @BASEBOARD_FAB2_LIB.BASEBOARD_FAB2(SCH_1):GND
    1  GND              IO1  @BASEBOARD_FAB2_LIB.BASEBOARD_FAB2(SCH_1):GND

CAPTIVE_SCREW_TH  I76  RM1G1  [CAPTIVE_SCREW_TH-HDW,H57868-001]

STANDOFF_TH1  I104  RM8D1  [STANDOFF_TH1-SO,H72821-001]
    1  GND              IO1  @BASEBOARD_FAB2_LIB.BASEBOARD_FAB2(SCH_1):GND

RES  I49  RT8P1  [RES_0603-100.0K,1%,1/10W,CHIP,A]
    2  VSENSE_VCCINR2PMAX_CPU1      B  @BASEBOARD_FAB2_LIB.BASEBOARD_FAB2(SCH_1):VSENSE_VCCINR2PMAX_CPU1
    1  PVCCIN_CPU1        A  @BASEBOARD_FAB2_LIB.BASEBOARD_FAB2(SCH_1):PVCCIN_CPU1

2D2R2F-GP_SMD-RG1  I69  RTI1   [2D2R2F-GP_SMD-RG1-2D2R2F-GP,64A]
    2  VR_PVCCIN_CPU0_PH1_BOOT_R      2  @BASEBOARD_FAB2_LIB.BASEBOARD_FAB2(SCH_1):VR_PVCCIN_CPU0_PH1_BOOT_R
    1  VR_PVCCIN_CPU0_PH1_BOOT      1  @BASEBOARD_FAB2_LIB.BASEBOARD_FAB2(SCH_1):VR_PVCCIN_CPU0_PH1_BOOT

3D01R5F-GP_SMD-RG5  I75  RTI2   [3D01R5F-GP_SMD-RG5-3D01R5F-GP,A]
    2  UNNAMED_202_3D01R5F-GP_I75_2      2  @BASEBOARD_FAB2_LIB.BASEBOARD_FAB2(SCH_1):UNNAMED_202_3D01R5F-GP_I75_2
    1  GND                1  @BASEBOARD_FAB2_LIB.BASEBOARD_FAB2(SCH_1):GND

2D2R2F-GP_SMD-RG1  I79  RTI3   [2D2R2F-GP_SMD-RG1-2D2R2F-GP,64A]
    2  VR_PVCCIN_CPU0_PH2_BOOT_R      2  @BASEBOARD_FAB2_LIB.BASEBOARD_FAB2(SCH_1):VR_PVCCIN_CPU0_PH2_BOOT_R
    1  VR_PVCCIN_CPU0_PH2_BOOT      1  @BASEBOARD_FAB2_LIB.BASEBOARD_FAB2(SCH_1):VR_PVCCIN_CPU0_PH2_BOOT

3D01R5F-GP_SMD-RG5  I83  RTI4   [3D01R5F-GP_SMD-RG5-3D01R5F-GP,A]
    2  UNNAMED_202_3D01R5F-GP_I83_2      2  @BASEBOARD_FAB2_LIB.BASEBOARD_FAB2(SCH_1):UNNAMED_202_3D01R5F-GP_I83_2
    1  GND                1  @BASEBOARD_FAB2_LIB.BASEBOARD_FAB2(SCH_1):GND

2D2R2F-GP_SMD-RG1  I108  RTI5   [2D2R2F-GP_SMD-RG1-2D2R2F-GP,64A]
    2  VR_PVDDQ_KLM_PH1_BOOT_R      2  @BASEBOARD_FAB2_LIB.BASEBOARD_FAB2(SCH_1):VR_PVDDQ_KLM_PH1_BOOT_R
    1  VR_PVDDQ_KLM_PH1_BOOT      1  @BASEBOARD_FAB2_LIB.BASEBOARD_FAB2(SCH_1):VR_PVDDQ_KLM_PH1_BOOT

3D01R5F-GP_SMD-RG5  I125  RTI6   [3D01R5F-GP_SMD-RG5-3D01R5F-GP,A]
    1  UNNAMED_227_3D01R5F-GP_I125_1      1  @BASEBOARD_FAB2_LIB.BASEBOARD_FAB2(SCH_1):UNNAMED_227_3D01R5F-GP_I125_1
    2  GND                2  @BASEBOARD_FAB2_LIB.BASEBOARD_FAB2(SCH_1):GND

3D01R5F-GP_SMD-RG5  I124  RTI7   [3D01R5F-GP_SMD-RG5-3D01R5F-GP,A]
    1  UNNAMED_227_3D01R5F-GP_I124_1      1  @BASEBOARD_FAB2_LIB.BASEBOARD_FAB2(SCH_1):UNNAMED_227_3D01R5F-GP_I124_1
    2  GND                2  @BASEBOARD_FAB2_LIB.BASEBOARD_FAB2(SCH_1):GND

2D2R2F-GP_SMD-RG1  I121  RTI8   [2D2R2F-GP_SMD-RG1-2D2R2F-GP,64A]
    2  VR_PVDDQ_KLM_PH2_BOOT_R      2  @BASEBOARD_FAB2_LIB.BASEBOARD_FAB2(SCH_1):VR_PVDDQ_KLM_PH2_BOOT_R
    1  VR_PVDDQ_KLM_PH2_BOOT      1  @BASEBOARD_FAB2_LIB.BASEBOARD_FAB2(SCH_1):VR_PVDDQ_KLM_PH2_BOOT

2D2R2F-GP_SMD-RG1  I61  RTI9   [2D2R2F-GP_SMD-RG1-2D2R2F-GP,64A]
    2  VR_PVCCIN_CPU1_PH5_BOOT_R      2  @BASEBOARD_FAB2_LIB.BASEBOARD_FAB2(SCH_1):VR_PVCCIN_CPU1_PH5_BOOT_R
    1  VR_PVCCIN_CPU1_PH5_BOOT      1  @BASEBOARD_FAB2_LIB.BASEBOARD_FAB2(SCH_1):VR_PVCCIN_CPU1_PH5_BOOT

3D01R5F-GP_SMD-RG5  I66  RTI10  [3D01R5F-GP_SMD-RG5-3D01R5F-GP,A]
    2  UNNAMED_209_3D01R5F-GP_I66_2      2  @BASEBOARD_FAB2_LIB.BASEBOARD_FAB2(SCH_1):UNNAMED_209_3D01R5F-GP_I66_2
    1  GND                1  @BASEBOARD_FAB2_LIB.BASEBOARD_FAB2(SCH_1):GND

2D2R2F-GP_SMD-RG1  I95  RTI11  [2D2R2F-GP_SMD-RG1-2D2R2F-GP,64A]
    2  VR_PVCCIN_CPU1_PH3_BOOT_R      2  @BASEBOARD_FAB2_LIB.BASEBOARD_FAB2(SCH_1):VR_PVCCIN_CPU1_PH3_BOOT_R
    1  VR_PVCCIN_CPU1_PH3_BOOT      1  @BASEBOARD_FAB2_LIB.BASEBOARD_FAB2(SCH_1):VR_PVCCIN_CPU1_PH3_BOOT

3D01R5F-GP_SMD-RG5  I86  RTI12  [3D01R5F-GP_SMD-RG5-3D01R5F-GP,A]
    2  UNNAMED_208_3D01R5F-GP_I86_2      2  @BASEBOARD_FAB2_LIB.BASEBOARD_FAB2(SCH_1):UNNAMED_208_3D01R5F-GP_I86_2
    1  GND                1  @BASEBOARD_FAB2_LIB.BASEBOARD_FAB2(SCH_1):GND

3D01R5F-GP_SMD-RG5  I94  RTI13  [3D01R5F-GP_SMD-RG5-3D01R5F-GP,A]
    2  UNNAMED_208_3D01R5F-GP_I94_2      2  @BASEBOARD_FAB2_LIB.BASEBOARD_FAB2(SCH_1):UNNAMED_208_3D01R5F-GP_I94_2
    1  GND                1  @BASEBOARD_FAB2_LIB.BASEBOARD_FAB2(SCH_1):GND

2D2R2F-GP_SMD-RG1  I89  RTI14  [2D2R2F-GP_SMD-RG1-2D2R2F-GP,64A]
    2  VR_PVCCIN_CPU1_PH4_BOOT_R      2  @BASEBOARD_FAB2_LIB.BASEBOARD_FAB2(SCH_1):VR_PVCCIN_CPU1_PH4_BOOT_R
    1  VR_PVCCIN_CPU1_PH4_BOOT      1  @BASEBOARD_FAB2_LIB.BASEBOARD_FAB2(SCH_1):VR_PVCCIN_CPU1_PH4_BOOT

2D2R2F-GP_SMD-RG1  I73  RTI15  [2D2R2F-GP_SMD-RG1-2D2R2F-GP,64A]
    2  VR_PVCCIN_CPU1_PH1_BOOT_R      2  @BASEBOARD_FAB2_LIB.BASEBOARD_FAB2(SCH_1):VR_PVCCIN_CPU1_PH1_BOOT_R
    1  VR_PVCCIN_CPU1_PH1_BOOT      1  @BASEBOARD_FAB2_LIB.BASEBOARD_FAB2(SCH_1):VR_PVCCIN_CPU1_PH1_BOOT

3D01R5F-GP_SMD-RG5  I76  RTI16  [3D01R5F-GP_SMD-RG5-3D01R5F-GP,A]
    2  UNNAMED_207_3D01R5F-GP_I76_2      2  @BASEBOARD_FAB2_LIB.BASEBOARD_FAB2(SCH_1):UNNAMED_207_3D01R5F-GP_I76_2
    1  GND                1  @BASEBOARD_FAB2_LIB.BASEBOARD_FAB2(SCH_1):GND

2D2R2F-GP_SMD-RG1  I79  RTI17  [2D2R2F-GP_SMD-RG1-2D2R2F-GP,64A]
    2  VR_PVCCIN_CPU1_PH2_BOOT_R      2  @BASEBOARD_FAB2_LIB.BASEBOARD_FAB2(SCH_1):VR_PVCCIN_CPU1_PH2_BOOT_R
    1  VR_PVCCIN_CPU1_PH2_BOOT      1  @BASEBOARD_FAB2_LIB.BASEBOARD_FAB2(SCH_1):VR_PVCCIN_CPU1_PH2_BOOT

3D01R5F-GP_SMD-RG5  I85  RTI18  [3D01R5F-GP_SMD-RG5-3D01R5F-GP,A]
    2  UNNAMED_207_3D01R5F-GP_I85_2      2  @BASEBOARD_FAB2_LIB.BASEBOARD_FAB2(SCH_1):UNNAMED_207_3D01R5F-GP_I85_2
    1  GND                1  @BASEBOARD_FAB2_LIB.BASEBOARD_FAB2(SCH_1):GND

2D2R2F-GP_SMD-RG1  I116  RTI19  [2D2R2F-GP_SMD-RG1-2D2R2F-GP,64A]
    2  VR_PVDDQ_GHJ_PH1_BOOT_R      2  @BASEBOARD_FAB2_LIB.BASEBOARD_FAB2(SCH_1):VR_PVDDQ_GHJ_PH1_BOOT_R
    1  VR_PVDDQ_GHJ_PH1_BOOT      1  @BASEBOARD_FAB2_LIB.BASEBOARD_FAB2(SCH_1):VR_PVDDQ_GHJ_PH1_BOOT

3D01R5F-GP_SMD-RG5  I119  RTI20  [3D01R5F-GP_SMD-RG5-3D01R5F-GP,A]
    2  UNNAMED_224_3D01R5F-GP_I119_2      2  @BASEBOARD_FAB2_LIB.BASEBOARD_FAB2(SCH_1):UNNAMED_224_3D01R5F-GP_I119_2
    1  GND                1  @BASEBOARD_FAB2_LIB.BASEBOARD_FAB2(SCH_1):GND

2D2R2F-GP_SMD-RG1  I126  RTI21  [2D2R2F-GP_SMD-RG1-2D2R2F-GP,64A]
    2  VR_PVDDQ_GHJ_PH2_BOOT_R      2  @BASEBOARD_FAB2_LIB.BASEBOARD_FAB2(SCH_1):VR_PVDDQ_GHJ_PH2_BOOT_R
    1  VR_PVDDQ_GHJ_PH2_BOOT      1  @BASEBOARD_FAB2_LIB.BASEBOARD_FAB2(SCH_1):VR_PVDDQ_GHJ_PH2_BOOT

3D01R5F-GP_SMD-RG5  I129  RTI22  [3D01R5F-GP_SMD-RG5-3D01R5F-GP,A]
    2  UNNAMED_224_3D01R5F-GP_I129_2      2  @BASEBOARD_FAB2_LIB.BASEBOARD_FAB2(SCH_1):UNNAMED_224_3D01R5F-GP_I129_2
    1  GND                1  @BASEBOARD_FAB2_LIB.BASEBOARD_FAB2(SCH_1):GND

2D2R2F-GP_SMD-RG1  I87  RTI23  [2D2R2F-GP_SMD-RG1-2D2R2F-GP,64A]
    2  VR_PVCCIN_CPU0_PH5_BOOT_R      2  @BASEBOARD_FAB2_LIB.BASEBOARD_FAB2(SCH_1):VR_PVCCIN_CPU0_PH5_BOOT_R
    1  VR_PVCCIN_CPU0_PH5_BOOT      1  @BASEBOARD_FAB2_LIB.BASEBOARD_FAB2(SCH_1):VR_PVCCIN_CPU0_PH5_BOOT

3D01R5F-GP_SMD-RG5  I91  RTI24  [3D01R5F-GP_SMD-RG5-3D01R5F-GP,A]
    2  UNNAMED_204_3D01R5F-GP_I91_2      2  @BASEBOARD_FAB2_LIB.BASEBOARD_FAB2(SCH_1):UNNAMED_204_3D01R5F-GP_I91_2
    1  GND                1  @BASEBOARD_FAB2_LIB.BASEBOARD_FAB2(SCH_1):GND

2D2R2F-GP_SMD-RG1  I98  RTI25  [2D2R2F-GP_SMD-RG1-2D2R2F-GP,64A]
    2  VR_PVCCIN_CPU0_PH3_BOOT_R      2  @BASEBOARD_FAB2_LIB.BASEBOARD_FAB2(SCH_1):VR_PVCCIN_CPU0_PH3_BOOT_R
    1  VR_PVCCIN_CPU0_PH3_BOOT      1  @BASEBOARD_FAB2_LIB.BASEBOARD_FAB2(SCH_1):VR_PVCCIN_CPU0_PH3_BOOT

3D01R5F-GP_SMD-RG5  I102  RTI26  [3D01R5F-GP_SMD-RG5-3D01R5F-GP,A]
    2  UNNAMED_203_3D01R5F-GP_I102_2      2  @BASEBOARD_FAB2_LIB.BASEBOARD_FAB2(SCH_1):UNNAMED_203_3D01R5F-GP_I102_2
    1  GND                1  @BASEBOARD_FAB2_LIB.BASEBOARD_FAB2(SCH_1):GND

3D01R5F-GP_SMD-RG5  I105  RTI27  [3D01R5F-GP_SMD-RG5-3D01R5F-GP,A]
    2  UNNAMED_203_3D01R5F-GP_I105_2      2  @BASEBOARD_FAB2_LIB.BASEBOARD_FAB2(SCH_1):UNNAMED_203_3D01R5F-GP_I105_2
    1  GND                1  @BASEBOARD_FAB2_LIB.BASEBOARD_FAB2(SCH_1):GND

2D2R2F-GP_SMD-RG1  I95  RTI28  [2D2R2F-GP_SMD-RG1-2D2R2F-GP,64A]
    2  VR_PVCCIN_CPU0_PH4_BOOT_R      2  @BASEBOARD_FAB2_LIB.BASEBOARD_FAB2(SCH_1):VR_PVCCIN_CPU0_PH4_BOOT_R
    1  VR_PVCCIN_CPU0_PH4_BOOT      1  @BASEBOARD_FAB2_LIB.BASEBOARD_FAB2(SCH_1):VR_PVCCIN_CPU0_PH4_BOOT

3D01R5F-GP_SMD-RG5  I126  RTI29  [3D01R5F-GP_SMD-RG5-3D01R5F-GP,A]
    2  UNNAMED_219_3D01R5F-GP_I126_2      2  @BASEBOARD_FAB2_LIB.BASEBOARD_FAB2(SCH_1):UNNAMED_219_3D01R5F-GP_I126_2
    1  GND                1  @BASEBOARD_FAB2_LIB.BASEBOARD_FAB2(SCH_1):GND

2D2R2F-GP_SMD-RG1  I118  RTI30  [2D2R2F-GP_SMD-RG1-2D2R2F-GP,64A]
    2  VR_PVDDQ_DEF_PH1_BOOT_R      2  @BASEBOARD_FAB2_LIB.BASEBOARD_FAB2(SCH_1):VR_PVDDQ_DEF_PH1_BOOT_R
    1  VR_PVDDQ_DEF_PH1_BOOT      1  @BASEBOARD_FAB2_LIB.BASEBOARD_FAB2(SCH_1):VR_PVDDQ_DEF_PH1_BOOT

2D2R2F-GP_SMD-RG1  I115  RTI31  [2D2R2F-GP_SMD-RG1-2D2R2F-GP,64A]
    2  VR_PVDDQ_DEF_PH2_BOOT_R      2  @BASEBOARD_FAB2_LIB.BASEBOARD_FAB2(SCH_1):VR_PVDDQ_DEF_PH2_BOOT_R
    1  VR_PVDDQ_DEF_PH2_BOOT      1  @BASEBOARD_FAB2_LIB.BASEBOARD_FAB2(SCH_1):VR_PVDDQ_DEF_PH2_BOOT

3D01R5F-GP_SMD-RG5  I123  RTI32  [3D01R5F-GP_SMD-RG5-3D01R5F-GP,A]
    2  UNNAMED_219_3D01R5F-GP_I123_2      2  @BASEBOARD_FAB2_LIB.BASEBOARD_FAB2(SCH_1):UNNAMED_219_3D01R5F-GP_I123_2
    1  GND                1  @BASEBOARD_FAB2_LIB.BASEBOARD_FAB2(SCH_1):GND

2D2R2F-GP_SMD-RG1  I110  RTI33  [2D2R2F-GP_SMD-RG1-2D2R2F-GP,64A]
    2  VR_PVDDQ_ABC_PH1_BOOT_R      2  @BASEBOARD_FAB2_LIB.BASEBOARD_FAB2(SCH_1):VR_PVDDQ_ABC_PH1_BOOT_R
    1  VR_PVDDQ_ABC_PH1_BOOT      1  @BASEBOARD_FAB2_LIB.BASEBOARD_FAB2(SCH_1):VR_PVDDQ_ABC_PH1_BOOT

3D01R5F-GP_SMD-RG5  I114  RTI34  [3D01R5F-GP_SMD-RG5-3D01R5F-GP,A]
    2  UNNAMED_216_3D01R5F-GP_I114_2      2  @BASEBOARD_FAB2_LIB.BASEBOARD_FAB2(SCH_1):UNNAMED_216_3D01R5F-GP_I114_2
    1  GND                1  @BASEBOARD_FAB2_LIB.BASEBOARD_FAB2(SCH_1):GND

3D01R5F-GP_SMD-RG5  I123  RTI35  [3D01R5F-GP_SMD-RG5-3D01R5F-GP,A]
    2  UNNAMED_216_3D01R5F-GP_I123_2      2  @BASEBOARD_FAB2_LIB.BASEBOARD_FAB2(SCH_1):UNNAMED_216_3D01R5F-GP_I123_2
    1  GND                1  @BASEBOARD_FAB2_LIB.BASEBOARD_FAB2(SCH_1):GND

2D2R2F-GP_SMD-RG1  I113  RTI36  [2D2R2F-GP_SMD-RG1-2D2R2F-GP,64A]
    2  VR_PVDDQ_ABC_PH2_BOOT_R      2  @BASEBOARD_FAB2_LIB.BASEBOARD_FAB2(SCH_1):VR_PVDDQ_ABC_PH2_BOOT_R
    1  VR_PVDDQ_ABC_PH2_BOOT      1  @BASEBOARD_FAB2_LIB.BASEBOARD_FAB2(SCH_1):VR_PVDDQ_ABC_PH2_BOOT

2D2R2F-GP_SMD-RG1  I56  RTI37  [2D2R2F-GP_SMD-RG1-2D2R2F-GP,64A]
    2  VR_PVSA_CPU1_BOOT_R      2  @BASEBOARD_FAB2_LIB.BASEBOARD_FAB2(SCH_1):VR_PVSA_CPU1_BOOT_R
    1  VR_PVSA_CPU1_BOOT      1  @BASEBOARD_FAB2_LIB.BASEBOARD_FAB2(SCH_1):VR_PVSA_CPU1_BOOT

3D01R5F-GP_SMD-RG5  I59  RTI38  [3D01R5F-GP_SMD-RG5-3D01R5F-GP,A]
    2  UNNAMED_210_3D01R5F-GP_I59_2      2  @BASEBOARD_FAB2_LIB.BASEBOARD_FAB2(SCH_1):UNNAMED_210_3D01R5F-GP_I59_2
    1  GND                1  @BASEBOARD_FAB2_LIB.BASEBOARD_FAB2(SCH_1):GND

3D01R5F-GP_SMD-RG5  I68  RTI39  [3D01R5F-GP_SMD-RG5-3D01R5F-GP,A]
    2  UNNAMED_205_3D01R5F-GP_I68_2      2  @BASEBOARD_FAB2_LIB.BASEBOARD_FAB2(SCH_1):UNNAMED_205_3D01R5F-GP_I68_2
    1  GND                1  @BASEBOARD_FAB2_LIB.BASEBOARD_FAB2(SCH_1):GND

2D2R2F-GP_SMD-RG1  I71  RTI40  [2D2R2F-GP_SMD-RG1-2D2R2F-GP,64A]
    2  VR_PVSA_CPU0_BOOT_R      2  @BASEBOARD_FAB2_LIB.BASEBOARD_FAB2(SCH_1):VR_PVSA_CPU0_BOOT_R
    1  VR_PVSA_CPU0_BOOT      1  @BASEBOARD_FAB2_LIB.BASEBOARD_FAB2(SCH_1):VR_PVSA_CPU0_BOOT

2D2R2F-GP_SMD-RG1  I138  RTI41  [2D2R2F-GP_SMD-RG1-2D2R2F-GP,64A]
    2  VR_PVCCIO_CPU1_PH1_BOOT_R      2  @BASEBOARD_FAB2_LIB.BASEBOARD_FAB2(SCH_1):VR_PVCCIO_CPU1_PH1_BOOT_R
    1  VR_PVCCIO_CPU1_PH1_BOOT      1  @BASEBOARD_FAB2_LIB.BASEBOARD_FAB2(SCH_1):VR_PVCCIO_CPU1_PH1_BOOT

3D01R5F-GP_SMD-RG5  I132  RTI42  [3D01R5F-GP_SMD-RG5-3D01R5F-GP,A]
    2  UNNAMED_214_3D01R5F-GP_I132_2      2  @BASEBOARD_FAB2_LIB.BASEBOARD_FAB2(SCH_1):UNNAMED_214_3D01R5F-GP_I132_2
    1  GND                1  @BASEBOARD_FAB2_LIB.BASEBOARD_FAB2(SCH_1):GND

3D01R5F-GP_SMD-RG5  I132  RTI43  [3D01R5F-GP_SMD-RG5-3D01R5F-GP,A]
    2  UNNAMED_236_3D01R5F-GP_I132_2      2  @BASEBOARD_FAB2_LIB.BASEBOARD_FAB2(SCH_1):UNNAMED_236_3D01R5F-GP_I132_2
    1  GND                1  @BASEBOARD_FAB2_LIB.BASEBOARD_FAB2(SCH_1):GND

2D2R2F-GP_SMD-RG1  I128  RTI44  [2D2R2F-GP_SMD-RG1-2D2R2F-GP,64A]
    2  VR_PVNN_PCH_PH1_BOOT_R      2  @BASEBOARD_FAB2_LIB.BASEBOARD_FAB2(SCH_1):VR_PVNN_PCH_PH1_BOOT_R
    1  VR_PVNN_PCH_PH1_BOOT      1  @BASEBOARD_FAB2_LIB.BASEBOARD_FAB2(SCH_1):VR_PVNN_PCH_PH1_BOOT

3D01R5F-GP_SMD-RG5  I137  RTI45  [3D01R5F-GP_SMD-RG5-3D01R5F-GP,A]
    2  UNNAMED_236_3D01R5F-GP_I137_2      2  @BASEBOARD_FAB2_LIB.BASEBOARD_FAB2(SCH_1):UNNAMED_236_3D01R5F-GP_I137_2
    1  GND                1  @BASEBOARD_FAB2_LIB.BASEBOARD_FAB2(SCH_1):GND

2D2R2F-GP_SMD-RG1  I123  RTI46  [2D2R2F-GP_SMD-RG1-2D2R2F-GP,64A]
    2  VR_P1V05_PCH_STBY_PH1_BOOT_R      2  @BASEBOARD_FAB2_LIB.BASEBOARD_FAB2(SCH_1):VR_P1V05_PCH_STBY_PH1_BOOT_R
    1  VR_P1V05_PCH_STBY_PH1_BOOT      1  @BASEBOARD_FAB2_LIB.BASEBOARD_FAB2(SCH_1):VR_P1V05_PCH_STBY_PH1_BOOT

2D2R2F-GP_SMD-RG1  I108  RTI47  [2D2R2F-GP_SMD-RG1-2D2R2F-GP,64A]
    2  VR_PVCCIO_CPU0_PH1_BOOT_R      2  @BASEBOARD_FAB2_LIB.BASEBOARD_FAB2(SCH_1):VR_PVCCIO_CPU0_PH1_BOOT_R
    1  VR_PVCCIO_CPU0_PH1_BOOT      1  @BASEBOARD_FAB2_LIB.BASEBOARD_FAB2(SCH_1):VR_PVCCIO_CPU0_PH1_BOOT

3D01R5F-GP_SMD-RG5  I112  RTI48  [3D01R5F-GP_SMD-RG5-3D01R5F-GP,A]
    2  UNNAMED_212_3D01R5F-GP_I112_2      2  @BASEBOARD_FAB2_LIB.BASEBOARD_FAB2(SCH_1):UNNAMED_212_3D01R5F-GP_I112_2
    1  GND                1  @BASEBOARD_FAB2_LIB.BASEBOARD_FAB2(SCH_1):GND

SWITCH_D90553001_SMLF  I351  S8E1   [SWITCH_D90553001_SMLF-IC,D9055A]
    1  GND                A  @BASEBOARD_FAB2_LIB.BASEBOARD_FAB2(SCH_1):GND
    2  FP_NMI_BTN_OUT_R_N      B  @BASEBOARD_FAB2_LIB.BASEBOARD_FAB2(SCH_1):FP_NMI_BTN_OUT_R_N

SWITCH_D37771002_SM  I78  S9A1   [SWITCH_D37771002_SM-IC,D37771-A]
    4  GND             PIN4  @BASEBOARD_FAB2_LIB.BASEBOARD_FAB2(SCH_1):GND
    3  GND             PIN3  @BASEBOARD_FAB2_LIB.BASEBOARD_FAB2(SCH_1):GND
    2  FM_DEBUG_RST_BTN_N   PIN2  @BASEBOARD_FAB2_LIB.BASEBOARD_FAB2(SCH_1):FM_DEBUG_RST_BTN_N
    1  FM_DEBUG_RST_BTN_N   PIN1  @BASEBOARD_FAB2_LIB.BASEBOARD_FAB2(SCH_1):FM_DEBUG_RST_BTN_N

SW_H67881001_SM  I84  S9A2   [SW_H67881001_SM-IC,H67881-001]
    4  GND              IO4  @BASEBOARD_FAB2_LIB.BASEBOARD_FAB2(SCH_1):GND
    3  GND              IO3  @BASEBOARD_FAB2_LIB.BASEBOARD_FAB2(SCH_1):GND
    2  FP_PWR_BTN_R_N    IO2  @BASEBOARD_FAB2_LIB.BASEBOARD_FAB2(SCH_1):FP_PWR_BTN_R_N
    1  FP_PWR_BTN_R_N    IO1  @BASEBOARD_FAB2_LIB.BASEBOARD_FAB2(SCH_1):FP_PWR_BTN_R_N

SHUNT  I130  SH3D1  [SHUNT_SH0201-EMPTY,N_A]
    1  VSENSE_PVCCIO_CPU1_SKT_VRTN      A  @BASEBOARD_FAB2_LIB.BASEBOARD_FAB2(SCH_1):VSENSE_PVCCIO_CPU1_SKT_VRTN
    2  VSENSE_PVCCIO_CPU1_AVSN      B  @BASEBOARD_FAB2_LIB.BASEBOARD_FAB2(SCH_1):VSENSE_PVCCIO_CPU1_AVSN

SHUNT  I129  SH3D2  [SHUNT_SH0201-EMPTY,N_A]
    1  VSENSE_PVCCIO_CPU1_SKT_VSEN      A  @BASEBOARD_FAB2_LIB.BASEBOARD_FAB2(SCH_1):VSENSE_PVCCIO_CPU1_SKT_VSEN
    2  VSENSE_PVCCIO_CPU1_AVSP      B  @BASEBOARD_FAB2_LIB.BASEBOARD_FAB2(SCH_1):VSENSE_PVCCIO_CPU1_AVSP

SHUNT  I104  SH3P1  [SHUNT_SH0201-EMPTY,N_A]
    1  VSENSE_PVCCIO_CPU0_SKT_VSEN      A  @BASEBOARD_FAB2_LIB.BASEBOARD_FAB2(SCH_1):VSENSE_PVCCIO_CPU0_SKT_VSEN
    2  VSENSE_PVCCIO_CPU0_AVSP      B  @BASEBOARD_FAB2_LIB.BASEBOARD_FAB2(SCH_1):VSENSE_PVCCIO_CPU0_AVSP

SHUNT  I105  SH3P2  [SHUNT_SH0201-EMPTY,N_A]
    1  VSENSE_PVCCIO_CPU0_SKT_VRTN      A  @BASEBOARD_FAB2_LIB.BASEBOARD_FAB2(SCH_1):VSENSE_PVCCIO_CPU0_SKT_VRTN
    2  VSENSE_PVCCIO_CPU0_AVSN      B  @BASEBOARD_FAB2_LIB.BASEBOARD_FAB2(SCH_1):VSENSE_PVCCIO_CPU0_AVSN

SHUNT  I240  SH4L1  [SHUNT_SH0201-EMPTY,N_A]
    1  VSENSE_PVDDQ_DEF_N      A  @BASEBOARD_FAB2_LIB.BASEBOARD_FAB2(SCH_1):VSENSE_PVDDQ_DEF_N
    2  GND                B  @BASEBOARD_FAB2_LIB.BASEBOARD_FAB2(SCH_1):GND

SHUNT  I239  SH4L2  [SHUNT_SH0201-EMPTY,N_A]
    1  VSENSE_PVDDQ_DEF_P      A  @BASEBOARD_FAB2_LIB.BASEBOARD_FAB2(SCH_1):VSENSE_PVDDQ_DEF_P
    2  PVDDQ_DEF          B  @BASEBOARD_FAB2_LIB.BASEBOARD_FAB2(SCH_1):PVDDQ_DEF

SHUNT  I259  SH4U1  [SHUNT_SH0201-EMPTY,N_A]
    1  VSENSE_PVDDQ_ABC_N      A  @BASEBOARD_FAB2_LIB.BASEBOARD_FAB2(SCH_1):VSENSE_PVDDQ_ABC_N
    2  GND                B  @BASEBOARD_FAB2_LIB.BASEBOARD_FAB2(SCH_1):GND

SHUNT  I260  SH4U2  [SHUNT_SH0201-EMPTY,N_A]
    1  VSENSE_PVDDQ_ABC_P      A  @BASEBOARD_FAB2_LIB.BASEBOARD_FAB2(SCH_1):VSENSE_PVDDQ_ABC_P
    2  PVDDQ_ABC          B  @BASEBOARD_FAB2_LIB.BASEBOARD_FAB2(SCH_1):PVDDQ_ABC

SHUNT  I53  SH5L1  [SHUNT_SH0201-EMPTY,N_A]
    1  VR_PVTT_DEF_SNS      A  @BASEBOARD_FAB2_LIB.BASEBOARD_FAB2(SCH_1):VR_PVTT_DEF_SNS
    2  PVTT_DEF           B  @BASEBOARD_FAB2_LIB.BASEBOARD_FAB2(SCH_1):PVTT_DEF

SHUNT  I56  SH5U1  [SHUNT_SH0201-EMPTY,N_A]
    1  VR_PVTT_ABC_SNS      A  @BASEBOARD_FAB2_LIB.BASEBOARD_FAB2(SCH_1):VR_PVTT_ABC_SNS
    2  PVTT_ABC           B  @BASEBOARD_FAB2_LIB.BASEBOARD_FAB2(SCH_1):PVTT_ABC

SHUNT  I246  SH7L1  [SHUNT_SH0201-EMPTY,N_A]
    1  VSENSE_PVDDQ_KLM_N      A  @BASEBOARD_FAB2_LIB.BASEBOARD_FAB2(SCH_1):VSENSE_PVDDQ_KLM_N
    2  GND                B  @BASEBOARD_FAB2_LIB.BASEBOARD_FAB2(SCH_1):GND

SHUNT  I245  SH7L2  [SHUNT_SH0201-EMPTY,N_A]
    1  VSENSE_PVDDQ_KLM_P      A  @BASEBOARD_FAB2_LIB.BASEBOARD_FAB2(SCH_1):VSENSE_PVDDQ_KLM_P
    2  PVDDQ_KLM          B  @BASEBOARD_FAB2_LIB.BASEBOARD_FAB2(SCH_1):PVDDQ_KLM

SHUNT  I243  SH7U1  [SHUNT_SH0201-EMPTY,N_A]
    1  VSENSE_PVDDQ_GHJ_P      A  @BASEBOARD_FAB2_LIB.BASEBOARD_FAB2(SCH_1):VSENSE_PVDDQ_GHJ_P
    2  PVDDQ_GHJ          B  @BASEBOARD_FAB2_LIB.BASEBOARD_FAB2(SCH_1):PVDDQ_GHJ

SHUNT  I244  SH7U2  [SHUNT_SH0201-EMPTY,N_A]
    1  VSENSE_PVDDQ_GHJ_N      A  @BASEBOARD_FAB2_LIB.BASEBOARD_FAB2(SCH_1):VSENSE_PVDDQ_GHJ_N
    2  GND                B  @BASEBOARD_FAB2_LIB.BASEBOARD_FAB2(SCH_1):GND

SHUNT  I53  SH8L1  [SHUNT_SH0201-EMPTY,N_A]
    1  VR_PVTT_KLM_SNS      A  @BASEBOARD_FAB2_LIB.BASEBOARD_FAB2(SCH_1):VR_PVTT_KLM_SNS
    2  PVTT_KLM           B  @BASEBOARD_FAB2_LIB.BASEBOARD_FAB2(SCH_1):PVTT_KLM

SHUNT  I53  SH8U1  [SHUNT_SH0201-EMPTY,N_A]
    1  VR_PVTT_GHJ_SNS      A  @BASEBOARD_FAB2_LIB.BASEBOARD_FAB2(SCH_1):VR_PVTT_GHJ_SNS
    2  PVTT_GHJ           B  @BASEBOARD_FAB2_LIB.BASEBOARD_FAB2(SCH_1):PVTT_GHJ

RCC_DFX1940  I7   TC1A1  [RCC_DFX1940_ID4-EMPTY,N_A]
    3  RCC_DFX_1940_1    IO2  @BASEBOARD_FAB2_LIB.BASEBOARD_FAB2(SCH_1):RCC_DFX_1940_1
    2  RCC_DFX_1940_1    IO1  @BASEBOARD_FAB2_LIB.BASEBOARD_FAB2(SCH_1):RCC_DFX_1940_1
    1  GND              GND  @BASEBOARD_FAB2_LIB.BASEBOARD_FAB2(SCH_1):GND

RCC_DFX1940  I3   TC1G1  [RCC_DFX1940_ID4-EMPTY,N_A]
    3  RCC_DFX_1940_4    IO2  @BASEBOARD_FAB2_LIB.BASEBOARD_FAB2(SCH_1):RCC_DFX_1940_4
    2  RCC_DFX_1940_4    IO1  @BASEBOARD_FAB2_LIB.BASEBOARD_FAB2(SCH_1):RCC_DFX_1940_4
    1  GND              GND  @BASEBOARD_FAB2_LIB.BASEBOARD_FAB2(SCH_1):GND

RCC_DFX1940  I9   TC9A1  [RCC_DFX1940_ID4-EMPTY,N_A]
    3  RCC_DFX_1940_2    IO2  @BASEBOARD_FAB2_LIB.BASEBOARD_FAB2(SCH_1):RCC_DFX_1940_2
    2  RCC_DFX_1940_2    IO1  @BASEBOARD_FAB2_LIB.BASEBOARD_FAB2(SCH_1):RCC_DFX_1940_2
    1  GND              GND  @BASEBOARD_FAB2_LIB.BASEBOARD_FAB2(SCH_1):GND

RCC_DFX1940  I1   TC9F1  [RCC_DFX1940_ID4-EMPTY,N_A]
    3  RCC_DFX_1940_3    IO2  @BASEBOARD_FAB2_LIB.BASEBOARD_FAB2(SCH_1):RCC_DFX_1940_3
    2  RCC_DFX_1940_3    IO1  @BASEBOARD_FAB2_LIB.BASEBOARD_FAB2(SCH_1):RCC_DFX_1940_3
    1  GND              GND  @BASEBOARD_FAB2_LIB.BASEBOARD_FAB2(SCH_1):GND

MTG_KEYHOLE_TH  I56  TH1A1  [MTG_KEYHOLE_TH-EMPTY,NA]
    1  GND                1  @BASEBOARD_FAB2_LIB.BASEBOARD_FAB2(SCH_1):GND

MTG_KEYHOLE_TH  I62  TH4A1  [MTG_KEYHOLE_TH-EMPTY,NA]
    1  GND                1  @BASEBOARD_FAB2_LIB.BASEBOARD_FAB2(SCH_1):GND

MTG_KEYHOLE_TH  I49  TH4G1  [MTG_KEYHOLE_TH-EMPTY,NA]
    1  GND                1  @BASEBOARD_FAB2_LIB.BASEBOARD_FAB2(SCH_1):GND

MTG_KEYHOLE_TH  I65  TH7A1  [MTG_KEYHOLE_TH-EMPTY,NA]
    1  GND                1  @BASEBOARD_FAB2_LIB.BASEBOARD_FAB2(SCH_1):GND

MTG_KEYHOLE_TH  I67  TH7G1  [MTG_KEYHOLE_TH-EMPTY,NA]
    1  GND                1  @BASEBOARD_FAB2_LIB.BASEBOARD_FAB2(SCH_1):GND

MTG_KEYHOLE_TH  I54  TH9A1  [MTG_KEYHOLE_TH-EMPTY,NA]
    1  GND                1  @BASEBOARD_FAB2_LIB.BASEBOARD_FAB2(SCH_1):GND

MTG_KEYHOLE_TH  I52  TH9G1  [MTG_KEYHOLE_TH-EMPTY,NA]
    1  GND                1  @BASEBOARD_FAB2_LIB.BASEBOARD_FAB2(SCH_1):GND

MAX9634_SOT  I144  U1B1   [MAX9634_SOT-IC,H35789-001]
    3  VR_PVDDQ_KLM_AIINSEN_R    OUT  @BASEBOARD_FAB2_LIB.BASEBOARD_FAB2(SCH_1):VR_PVDDQ_KLM_AIINSEN_R
    5  P12V_STBY        RSP  @BASEBOARD_FAB2_LIB.BASEBOARD_FAB2(SCH_1):P12V_STBY
    4  P12V_NVDIMM_KLM    RSN  @BASEBOARD_FAB2_LIB.BASEBOARD_FAB2(SCH_1):P12V_NVDIMM_KLM
    1  GND            GND<1>  @BASEBOARD_FAB2_LIB.BASEBOARD_FAB2(SCH_1):GND
    2  GND            GND<0>  @BASEBOARD_FAB2_LIB.BASEBOARD_FAB2(SCH_1):GND

PCA9517_SM  I1   U1B2   [PCA9517_SM-IC,G77073-001-GND=GA]
    5  TP_SMB_PEHPCPU1_EN     EN  @BASEBOARD_FAB2_LIB.BASEBOARD_FAB2(SCH_1):TP_SMB_PEHPCPU1_EN
    6  SMB_PEHPCPU1_STBY_LVC3_R_SDA   SDAB  @BASEBOARD_FAB2_LIB.BASEBOARD_FAB2(SCH_1):SMB_PEHPCPU1_STBY_LVC3_R_SDA
    7  SMB_PEHPCPU1_STBY_LVC3_R_SCL   SCLB  @BASEBOARD_FAB2_LIB.BASEBOARD_FAB2(SCH_1):SMB_PEHPCPU1_STBY_LVC3_R_SCL
    3  SMB_CPU1_PE_HP_GTL_R_SDA   SDAA  @BASEBOARD_FAB2_LIB.BASEBOARD_FAB2(SCH_1):SMB_CPU1_PE_HP_GTL_R_SDA
    2  SMB_CPU1_PE_HP_GTL_R_SCL   SCLA  @BASEBOARD_FAB2_LIB.BASEBOARD_FAB2(SCH_1):SMB_CPU1_PE_HP_GTL_R_SCL
    1  PVCCIO_CPU1     VCCA  @BASEBOARD_FAB2_LIB.BASEBOARD_FAB2(SCH_1):PVCCIO_CPU1
    8  P3V3_STBY       VCCB  @BASEBOARD_FAB2_LIB.BASEBOARD_FAB2(SCH_1):P3V3_STBY

ADM4073_SM  I52  U1B3   [ADM4073_SM-EMPTY,G12194-001]
    5  VR_FET_SW_P12V_STBY_PVCCIN_CPU1    RSN  @BASEBOARD_FAB2_LIB.BASEBOARD_FAB2(SCH_1):VR_FET_SW_P12V_STBY_PVCCIN_CPU1
    3  VR_FET_SW_P12V_PVCCIN_CPU1_R    VCC  @BASEBOARD_FAB2_LIB.BASEBOARD_FAB2(SCH_1):VR_FET_SW_P12V_PVCCIN_CPU1_R
    4  VR_FET_SW_P12V_PVCCIN_CPU1_R    RSP  @BASEBOARD_FAB2_LIB.BASEBOARD_FAB2(SCH_1):VR_FET_SW_P12V_PVCCIN_CPU1_R
    6  PVCCIN_PVSA_CPU1_IINSEN    OUT  @BASEBOARD_FAB2_LIB.BASEBOARD_FAB2(SCH_1):PVCCIN_PVSA_CPU1_IINSEN
    2  GND            GND<1>  @BASEBOARD_FAB2_LIB.BASEBOARD_FAB2(SCH_1):GND
    1  GND            GND<0>  @BASEBOARD_FAB2_LIB.BASEBOARD_FAB2(SCH_1):GND

TTL1G126_A_SOT  I103  U1D1   [TTL1G126_A_SOT-74HC1G126,IC,A7B]
    2  IRQ_OC_DETECT_N      A  @BASEBOARD_FAB2_LIB.BASEBOARD_FAB2(SCH_1):IRQ_OC_DETECT_N
    4  FM_OC_DETECT_N      Y  @BASEBOARD_FAB2_LIB.BASEBOARD_FAB2(SCH_1):FM_OC_DETECT_N
    1  FM_OC_DETECT_EN     OE  @BASEBOARD_FAB2_LIB.BASEBOARD_FAB2(SCH_1):FM_OC_DETECT_EN

TPS3700_SM  I170  U1D2   [TPS3700_SM-IC,H69492-001]
    2  P12V_STBY        VDD  @BASEBOARD_FAB2_LIB.BASEBOARD_FAB2(SCH_1):P12V_STBY
    1  IRQ_OC_DETECT_N   OUTB  @BASEBOARD_FAB2_LIB.BASEBOARD_FAB2(SCH_1):IRQ_OC_DETECT_N
    5  GND              GND  @BASEBOARD_FAB2_LIB.BASEBOARD_FAB2(SCH_1):GND
    6  A_HSC_LOW_GATE   OUTA  @BASEBOARD_FAB2_LIB.BASEBOARD_FAB2(SCH_1):A_HSC_LOW_GATE
    4  A_HSC_LOW       INAP  @BASEBOARD_FAB2_LIB.BASEBOARD_FAB2(SCH_1):A_HSC_LOW
    3  A_HSC_HIGH      INBN  @BASEBOARD_FAB2_LIB.BASEBOARD_FAB2(SCH_1):A_HSC_HIGH

TMP421_TSSOP  I30  U1E1   [TMP421_TSSOP-IC,G62962-001]
    6  SMB_SENSOR_TMP421_2_SDA    SDA  @BASEBOARD_FAB2_LIB.BASEBOARD_FAB2(SCH_1):SMB_SENSOR_TMP421_2_SDA
    7  SMB_SENSOR_TMP421_2_SCL    SCL  @BASEBOARD_FAB2_LIB.BASEBOARD_FAB2(SCH_1):SMB_SENSOR_TMP421_2_SCL
    4  PU_TMP421_2_A0   A<0>  @BASEBOARD_FAB2_LIB.BASEBOARD_FAB2(SCH_1):PU_TMP421_2_A0
    3  PD_TMP421_2_A1   A<1>  @BASEBOARD_FAB2_LIB.BASEBOARD_FAB2(SCH_1):PD_TMP421_2_A1
    8  P3V3_STBY         VP  @BASEBOARD_FAB2_LIB.BASEBOARD_FAB2(SCH_1):P3V3_STBY
    1  ISENSE_TMP421_2_DXP    DXP  @BASEBOARD_FAB2_LIB.BASEBOARD_FAB2(SCH_1):ISENSE_TMP421_2_DXP
    2  ISENSE_TMP421_2_DXN    DXN  @BASEBOARD_FAB2_LIB.BASEBOARD_FAB2(SCH_1):ISENSE_TMP421_2_DXN
    5  GND              GND  @BASEBOARD_FAB2_LIB.BASEBOARD_FAB2(SCH_1):GND

TTL1G08  I121  U1E2   [TTL1G08_SOTLF-NC7SZ08,IC,D1032B]
    4  FM_ENABLE_FAN_POWER   Y<0>  @BASEBOARD_FAB2_LIB.BASEBOARD_FAB2(SCH_1):FM_ENABLE_FAN_POWER
    2  FM_DISABLE_FAN_N   B<0>  @BASEBOARD_FAB2_LIB.BASEBOARD_FAB2(SCH_1):FM_DISABLE_FAN_N
    1  FM_CTNR_PS_ON   A<0>  @BASEBOARD_FAB2_LIB.BASEBOARD_FAB2(SCH_1):FM_CTNR_PS_ON

MAX9634_SOT  I133  U1F1   [MAX9634_SOT-IC,H35789-001]
    3  VR_PVDDQ_GHJ_AIINSEN_R    OUT  @BASEBOARD_FAB2_LIB.BASEBOARD_FAB2(SCH_1):VR_PVDDQ_GHJ_AIINSEN_R
    5  P12V_STBY        RSP  @BASEBOARD_FAB2_LIB.BASEBOARD_FAB2(SCH_1):P12V_STBY
    4  P12V_NVDIMM_GHJ    RSN  @BASEBOARD_FAB2_LIB.BASEBOARD_FAB2(SCH_1):P12V_NVDIMM_GHJ
    1  GND            GND<1>  @BASEBOARD_FAB2_LIB.BASEBOARD_FAB2(SCH_1):GND
    2  GND            GND<0>  @BASEBOARD_FAB2_LIB.BASEBOARD_FAB2(SCH_1):GND

TTL3126_QFNLF  I108  U1L1   [TTL3126_QFNLF-74CBTLV3126,IC,DB]
   12  XDP_TDI         A<0>  @BASEBOARD_FAB2_LIB.BASEBOARD_FAB2(SCH_1):XDP_TDI
   11  XDP_CPU_TDI     B<0>  @BASEBOARD_FAB2_LIB.BASEBOARD_FAB2(SCH_1):XDP_CPU_TDI
   13  PWRGD_PVCCIN_CPU0  OE<0>  @BASEBOARD_FAB2_LIB.BASEBOARD_FAB2(SCH_1):PWRGD_PVCCIN_CPU0

TTL3126_QFNLF  I108  U1L1   [TTL3126_QFNLF-74CBTLV3126,IC,DB]
    9  XDP_TDO         A<0>  @BASEBOARD_FAB2_LIB.BASEBOARD_FAB2(SCH_1):XDP_TDO
    8  XDP_CPU_TDO     B<0>  @BASEBOARD_FAB2_LIB.BASEBOARD_FAB2(SCH_1):XDP_CPU_TDO
   10  PWRGD_PVCCIN_CPU0  OE<0>  @BASEBOARD_FAB2_LIB.BASEBOARD_FAB2(SCH_1):PWRGD_PVCCIN_CPU0

TTL3126_QFNLF  I108  U1L1   [TTL3126_QFNLF-74CBTLV3126,IC,DB]
    5  XDP_TMS         A<0>  @BASEBOARD_FAB2_LIB.BASEBOARD_FAB2(SCH_1):XDP_TMS
    6  XDP_CPU_TMS     B<0>  @BASEBOARD_FAB2_LIB.BASEBOARD_FAB2(SCH_1):XDP_CPU_TMS
    4  PWRGD_PVCCIN_CPU0  OE<0>  @BASEBOARD_FAB2_LIB.BASEBOARD_FAB2(SCH_1):PWRGD_PVCCIN_CPU0

TTL3126_QFNLF  I108  U1L1   [TTL3126_QFNLF-74CBTLV3126,IC,DB]
    2  XDP_TRST_N      A<0>  @BASEBOARD_FAB2_LIB.BASEBOARD_FAB2(SCH_1):XDP_TRST_N
    3  XDP_CPU_TRST_N   B<0>  @BASEBOARD_FAB2_LIB.BASEBOARD_FAB2(SCH_1):XDP_CPU_TRST_N
    1  PWRGD_PVCCIN_CPU0  OE<0>  @BASEBOARD_FAB2_LIB.BASEBOARD_FAB2(SCH_1):PWRGD_PVCCIN_CPU0

TTL1G86_SOTLF  I57  U1L2   [TTL1G86_SOTLF-74AHCT1G86,IC,D3B]
    1  PWRGD_P3V3_R       A  @BASEBOARD_FAB2_LIB.BASEBOARD_FAB2(SCH_1):PWRGD_P3V3_R
    2  FP_PWR_ID_LED_N      B  @BASEBOARD_FAB2_LIB.BASEBOARD_FAB2(SCH_1):FP_PWR_ID_LED_N
    4  FP_ID_LED_P5V_STBY_N      Y  @BASEBOARD_FAB2_LIB.BASEBOARD_FAB2(SCH_1):FP_ID_LED_P5V_STBY_N

ADM809  I80  U1L3   [ADM809_SMLF-IC,D23047-001-GND=A]
    2  PWRGD_P3V3_R1  RESET_N  @BASEBOARD_FAB2_LIB.BASEBOARD_FAB2(SCH_1):PWRGD_P3V3_R1
    3  P3V3             VCC  @BASEBOARD_FAB2_LIB.BASEBOARD_FAB2(SCH_1):P3V3

TTL1G07_A_SOP  I85  U1L4   [TTL1G07_A_SOP-74LVC1G07,IC,C88B]
    2  XDP_RST_CO_N       A  @BASEBOARD_FAB2_LIB.BASEBOARD_FAB2(SCH_1):XDP_RST_CO_N
    4  FM_DEBUG_RST_BTN_R1_N      Y  @BASEBOARD_FAB2_LIB.BASEBOARD_FAB2(SCH_1):FM_DEBUG_RST_BTN_R1_N

TTL3126_QFNLF  I109  U1L5   [TTL3126_QFNLF-74CBTLV3126,IC,DB]
   12  XDP_PREQ_N      A<0>  @BASEBOARD_FAB2_LIB.BASEBOARD_FAB2(SCH_1):XDP_PREQ_N
   11  XDP_CPU_PREQ_N   B<0>  @BASEBOARD_FAB2_LIB.BASEBOARD_FAB2(SCH_1):XDP_CPU_PREQ_N
   13  PWRGD_PVCCIN_CPU0  OE<0>  @BASEBOARD_FAB2_LIB.BASEBOARD_FAB2(SCH_1):PWRGD_PVCCIN_CPU0

TTL3126_QFNLF  I109  U1L5   [TTL3126_QFNLF-74CBTLV3126,IC,DB]
    9  XDP_PRDY_N      A<0>  @BASEBOARD_FAB2_LIB.BASEBOARD_FAB2(SCH_1):XDP_PRDY_N
    8  XDP_CPU_PRDY_N   B<0>  @BASEBOARD_FAB2_LIB.BASEBOARD_FAB2(SCH_1):XDP_CPU_PRDY_N
   10  PWRGD_PVCCIN_CPU0  OE<0>  @BASEBOARD_FAB2_LIB.BASEBOARD_FAB2(SCH_1):PWRGD_PVCCIN_CPU0

TTL3126_QFNLF  I109  U1L5   [TTL3126_QFNLF-74CBTLV3126,IC,DB]
    5  XDP_OBSFN_B0_MBP6_N   A<0>  @BASEBOARD_FAB2_LIB.BASEBOARD_FAB2(SCH_1):XDP_OBSFN_B0_MBP6_N
    6  XDP_CPU_OBSFN_B0_MBP6_N   B<0>  @BASEBOARD_FAB2_LIB.BASEBOARD_FAB2(SCH_1):XDP_CPU_OBSFN_B0_MBP6_N
    4  PWRGD_PVCCIN_CPU0  OE<0>  @BASEBOARD_FAB2_LIB.BASEBOARD_FAB2(SCH_1):PWRGD_PVCCIN_CPU0

TTL3126_QFNLF  I109  U1L5   [TTL3126_QFNLF-74CBTLV3126,IC,DB]
    2  XDP_OBSFN_B1_MBP7_N   A<0>  @BASEBOARD_FAB2_LIB.BASEBOARD_FAB2(SCH_1):XDP_OBSFN_B1_MBP7_N
    3  XDP_CPU_OBSFN_B1_MBP7_N   B<0>  @BASEBOARD_FAB2_LIB.BASEBOARD_FAB2(SCH_1):XDP_CPU_OBSFN_B1_MBP7_N
    1  PWRGD_PVCCIN_CPU0  OE<0>  @BASEBOARD_FAB2_LIB.BASEBOARD_FAB2(SCH_1):PWRGD_PVCCIN_CPU0

TTL1G08  I70  U1M1   [TTL1G08_SOTLF-NC7SZ08,IC,D1032C]
    1  LED_SATA_ACT_R_N   A<0>  @BASEBOARD_FAB2_LIB.BASEBOARD_FAB2(SCH_1):LED_SATA_ACT_R_N
    2  LED_SAS_ACT_R_N   B<0>  @BASEBOARD_FAB2_LIB.BASEBOARD_FAB2(SCH_1):LED_SAS_ACT_R_N
    4  FP_LED_HDD_ACTIVITY_AND_N   Y<0>  @BASEBOARD_FAB2_LIB.BASEBOARD_FAB2(SCH_1):FP_LED_HDD_ACTIVITY_AND_N

NC7SB3157  I107  U1M2   [NC7SB3157_SMLF-IC,C99406-001]
    5  P3V3_STBY        VCC  @BASEBOARD_FAB2_LIB.BASEBOARD_FAB2(SCH_1):P3V3_STBY
    4  JTAG_MCP_MUX_TDO      A  @BASEBOARD_FAB2_LIB.BASEBOARD_FAB2(SCH_1):JTAG_MCP_MUX_TDO
    3  JTAG_MCP_CPU1_TDO     B0  @BASEBOARD_FAB2_LIB.BASEBOARD_FAB2(SCH_1):JTAG_MCP_CPU1_TDO
    1  JTAG_MCP_CPU0_TDO     B1  @BASEBOARD_FAB2_LIB.BASEBOARD_FAB2(SCH_1):JTAG_MCP_CPU0_TDO
    2  GND              GND  @BASEBOARD_FAB2_LIB.BASEBOARD_FAB2(SCH_1):GND
    6  FM_CPU1_CD_PRES      S  @BASEBOARD_FAB2_LIB.BASEBOARD_FAB2(SCH_1):FM_CPU1_CD_PRES

TPS2061_SM  I100  U1M3   [TPS2061_SM-IC,H66405-001]
    1  P5V_USB          OUT  @BASEBOARD_FAB2_LIB.BASEBOARD_FAB2(SCH_1):P5V_USB
    5  P5V               IN  @BASEBOARD_FAB2_LIB.BASEBOARD_FAB2(SCH_1):P5V
    2  GND              GND  @BASEBOARD_FAB2_LIB.BASEBOARD_FAB2(SCH_1):GND
    4  FM_USB_P0_EN_BOOT_BIOS_STRAP_N   EN_N  @BASEBOARD_FAB2_LIB.BASEBOARD_FAB2(SCH_1):FM_USB_P0_EN_BOOT_BIOS_STRAP_N
    3  FM_OC0_USB_N    OC_N  @BASEBOARD_FAB2_LIB.BASEBOARD_FAB2(SCH_1):FM_OC0_USB_N

74CBTLV1G125  I127  U1M4   [74CBTLV1G125_SMLF-IC,C88177-00A]
    4  XDP_CPU1_TDI       B  @BASEBOARD_FAB2_LIB.BASEBOARD_FAB2(SCH_1):XDP_CPU1_TDI
    2  XDP_CPU0_TDO       A  @BASEBOARD_FAB2_LIB.BASEBOARD_FAB2(SCH_1):XDP_CPU0_TDO
    1  FM_CPU1_SKTOCC_LVT3_N   OE_N  @BASEBOARD_FAB2_LIB.BASEBOARD_FAB2(SCH_1):FM_CPU1_SKTOCC_LVT3_N

74CBTLV1G125  I196  U1M5   [74CBTLV1G125_SMLF-IC,C88177-00A]
    2  P1V8_MCP_CPU0      A  @BASEBOARD_FAB2_LIB.BASEBOARD_FAB2(SCH_1):P1V8_MCP_CPU0
    4  JTAG_MCP_TMS_R1      B  @BASEBOARD_FAB2_LIB.BASEBOARD_FAB2(SCH_1):JTAG_MCP_TMS_R1
    1  FM_CPU0_OR_CPU1_MCP_PRES   OE_N  @BASEBOARD_FAB2_LIB.BASEBOARD_FAB2(SCH_1):FM_CPU0_OR_CPU1_MCP_PRES

74CBTLV1G125  I127  U1M6   [74CBTLV1G125_SMLF-IC,C88177-00A]
    4  JTAG_MCP_CPU1_TDI      B  @BASEBOARD_FAB2_LIB.BASEBOARD_FAB2(SCH_1):JTAG_MCP_CPU1_TDI
    2  JTAG_MCP_CPU0_TDO      A  @BASEBOARD_FAB2_LIB.BASEBOARD_FAB2(SCH_1):JTAG_MCP_CPU0_TDO
    1  FM_CPU0_AND_CPU1_MCP_PRES   OE_N  @BASEBOARD_FAB2_LIB.BASEBOARD_FAB2(SCH_1):FM_CPU0_AND_CPU1_MCP_PRES

NC7SB3157  I40  U1M7   [NC7SB3157_SMLF-IC,C99406-001]
    4  XDP_CPU_TDO        A  @BASEBOARD_FAB2_LIB.BASEBOARD_FAB2(SCH_1):XDP_CPU_TDO
    3  XDP_CPU1_TDO      B0  @BASEBOARD_FAB2_LIB.BASEBOARD_FAB2(SCH_1):XDP_CPU1_TDO
    1  XDP_CPU0_TDO      B1  @BASEBOARD_FAB2_LIB.BASEBOARD_FAB2(SCH_1):XDP_CPU0_TDO
    5  P3V3_STBY        VCC  @BASEBOARD_FAB2_LIB.BASEBOARD_FAB2(SCH_1):P3V3_STBY
    2  GND              GND  @BASEBOARD_FAB2_LIB.BASEBOARD_FAB2(SCH_1):GND
    6  FM_CPU1_SKTOCC_LVT3_N      S  @BASEBOARD_FAB2_LIB.BASEBOARD_FAB2(SCH_1):FM_CPU1_SKTOCC_LVT3_N

TTL1G07_A_SOP  I46  U1R1   [TTL1G07_A_SOP-74LVC1G07,IC,C88B]
    4  FM_THROTTLE_R1_N      Y  @BASEBOARD_FAB2_LIB.BASEBOARD_FAB2(SCH_1):FM_THROTTLE_R1_N
    2  FM_FAST_PROCHOT_THROTTLE_DLY_BU      A  @BASEBOARD_FAB2_LIB.BASEBOARD_FAB2(SCH_1):FM_FAST_PROCHOT_THROTTLE_DLY_BUF_N

TTL1G126_A_SOT  I20  U1R2   [TTL1G126_A_SOT-74HC1G126,IC,A7B]
    2  FM_FAST_PROCHOT_THROTTLE_DLY_N      A  @BASEBOARD_FAB2_LIB.BASEBOARD_FAB2(SCH_1):FM_FAST_PROCHOT_THROTTLE_DLY_N
    4  FM_FAST_PROCHOT_THROTTLE_DLY_BU      Y  @BASEBOARD_FAB2_LIB.BASEBOARD_FAB2(SCH_1):FM_FAST_PROCHOT_THROTTLE_DLY_BUF_N
    1  FM_FAST_PROCHOT_EN     OE  @BASEBOARD_FAB2_LIB.BASEBOARD_FAB2(SCH_1):FM_FAST_PROCHOT_EN

SKX_EXT_B_BGA1  I20  U2D1   [SKX_EXT_B_BGA1-IC,TBD]
  DN78  GND            VSS<133>  @BASEBOARD_FAB2_LIB.BASEBOARD_FAB2(SCH_1):GND
  DP67  GND            VSS<132>  @BASEBOARD_FAB2_LIB.BASEBOARD_FAB2(SCH_1):GND
  DP69  GND            VSS<131>  @BASEBOARD_FAB2_LIB.BASEBOARD_FAB2(SCH_1):GND
  DP71  GND            VSS<130>  @BASEBOARD_FAB2_LIB.BASEBOARD_FAB2(SCH_1):GND
  DP81  GND            VSS<129>  @BASEBOARD_FAB2_LIB.BASEBOARD_FAB2(SCH_1):GND
  DP83  GND            VSS<128>  @BASEBOARD_FAB2_LIB.BASEBOARD_FAB2(SCH_1):GND
  BR26  GND            VSS<127>  @BASEBOARD_FAB2_LIB.BASEBOARD_FAB2(SCH_1):GND
  DR6  GND            VSS<126>  @BASEBOARD_FAB2_LIB.BASEBOARD_FAB2(SCH_1):GND
  CA20  GND            VSS<125>  @BASEBOARD_FAB2_LIB.BASEBOARD_FAB2(SCH_1):GND
  CL22  GND            VSS<124>  @BASEBOARD_FAB2_LIB.BASEBOARD_FAB2(SCH_1):GND
  DR20  GND            VSS<123>  @BASEBOARD_FAB2_LIB.BASEBOARD_FAB2(SCH_1):GND
  DR22  GND            VSS<122>  @BASEBOARD_FAB2_LIB.BASEBOARD_FAB2(SCH_1):GND
  DR24  GND            VSS<121>  @BASEBOARD_FAB2_LIB.BASEBOARD_FAB2(SCH_1):GND
  DR26  GND            VSS<120>  @BASEBOARD_FAB2_LIB.BASEBOARD_FAB2(SCH_1):GND
  DR28  GND            VSS<119>  @BASEBOARD_FAB2_LIB.BASEBOARD_FAB2(SCH_1):GND
  DR30  GND            VSS<118>  @BASEBOARD_FAB2_LIB.BASEBOARD_FAB2(SCH_1):GND
  DR32  GND            VSS<117>  @BASEBOARD_FAB2_LIB.BASEBOARD_FAB2(SCH_1):GND
  DR34  GND            VSS<116>  @BASEBOARD_FAB2_LIB.BASEBOARD_FAB2(SCH_1):GND
  DR36  GND            VSS<115>  @BASEBOARD_FAB2_LIB.BASEBOARD_FAB2(SCH_1):GND
  DR38  GND            VSS<114>  @BASEBOARD_FAB2_LIB.BASEBOARD_FAB2(SCH_1):GND
  DR40  GND            VSS<113>  @BASEBOARD_FAB2_LIB.BASEBOARD_FAB2(SCH_1):GND
  DR42  GND            VSS<112>  @BASEBOARD_FAB2_LIB.BASEBOARD_FAB2(SCH_1):GND
  DR66  GND            VSS<111>  @BASEBOARD_FAB2_LIB.BASEBOARD_FAB2(SCH_1):GND
  DR68  GND            VSS<110>  @BASEBOARD_FAB2_LIB.BASEBOARD_FAB2(SCH_1):GND
  DR70  GND            VSS<109>  @BASEBOARD_FAB2_LIB.BASEBOARD_FAB2(SCH_1):GND
  DR72  GND            VSS<108>  @BASEBOARD_FAB2_LIB.BASEBOARD_FAB2(SCH_1):GND
  DR74  GND            VSS<107>  @BASEBOARD_FAB2_LIB.BASEBOARD_FAB2(SCH_1):GND
  DR76  GND            VSS<106>  @BASEBOARD_FAB2_LIB.BASEBOARD_FAB2(SCH_1):GND
  DR78  GND            VSS<105>  @BASEBOARD_FAB2_LIB.BASEBOARD_FAB2(SCH_1):GND
  DT3  GND            VSS<104>  @BASEBOARD_FAB2_LIB.BASEBOARD_FAB2(SCH_1):GND
  DT17  GND            VSS<103>  @BASEBOARD_FAB2_LIB.BASEBOARD_FAB2(SCH_1):GND
  DH21  GND            VSS<102>  @BASEBOARD_FAB2_LIB.BASEBOARD_FAB2(SCH_1):GND
  DT65  GND            VSS<101>  @BASEBOARD_FAB2_LIB.BASEBOARD_FAB2(SCH_1):GND
  DT69  GND            VSS<100>  @BASEBOARD_FAB2_LIB.BASEBOARD_FAB2(SCH_1):GND
  DT79  GND            VSS<99>  @BASEBOARD_FAB2_LIB.BASEBOARD_FAB2(SCH_1):GND
  DT83  GND            VSS<98>  @BASEBOARD_FAB2_LIB.BASEBOARD_FAB2(SCH_1):GND
  DT85  GND            VSS<97>  @BASEBOARD_FAB2_LIB.BASEBOARD_FAB2(SCH_1):GND
  DU10  GND            VSS<96>  @BASEBOARD_FAB2_LIB.BASEBOARD_FAB2(SCH_1):GND
  DU14  GND            VSS<95>  @BASEBOARD_FAB2_LIB.BASEBOARD_FAB2(SCH_1):GND
  CN14  GND            VSS<94>  @BASEBOARD_FAB2_LIB.BASEBOARD_FAB2(SCH_1):GND
  DU22  GND            VSS<93>  @BASEBOARD_FAB2_LIB.BASEBOARD_FAB2(SCH_1):GND
  DU26  GND            VSS<92>  @BASEBOARD_FAB2_LIB.BASEBOARD_FAB2(SCH_1):GND
  DU32  GND            VSS<91>  @BASEBOARD_FAB2_LIB.BASEBOARD_FAB2(SCH_1):GND
  DU38  GND            VSS<90>  @BASEBOARD_FAB2_LIB.BASEBOARD_FAB2(SCH_1):GND
  DU70  GND            VSS<89>  @BASEBOARD_FAB2_LIB.BASEBOARD_FAB2(SCH_1):GND
  DU72  GND            VSS<88>  @BASEBOARD_FAB2_LIB.BASEBOARD_FAB2(SCH_1):GND
  DU78  GND            VSS<87>  @BASEBOARD_FAB2_LIB.BASEBOARD_FAB2(SCH_1):GND
  DU80  GND            VSS<86>  @BASEBOARD_FAB2_LIB.BASEBOARD_FAB2(SCH_1):GND
  DU82  GND            VSS<85>  @BASEBOARD_FAB2_LIB.BASEBOARD_FAB2(SCH_1):GND
  DU84  GND            VSS<84>  @BASEBOARD_FAB2_LIB.BASEBOARD_FAB2(SCH_1):GND
  DV21  GND            VSS<83>  @BASEBOARD_FAB2_LIB.BASEBOARD_FAB2(SCH_1):GND
  DV25  GND            VSS<82>  @BASEBOARD_FAB2_LIB.BASEBOARD_FAB2(SCH_1):GND
  DV27  GND            VSS<81>  @BASEBOARD_FAB2_LIB.BASEBOARD_FAB2(SCH_1):GND
  DV31  GND            VSS<80>  @BASEBOARD_FAB2_LIB.BASEBOARD_FAB2(SCH_1):GND
  DV33  GND            VSS<79>  @BASEBOARD_FAB2_LIB.BASEBOARD_FAB2(SCH_1):GND
  DV37  GND            VSS<78>  @BASEBOARD_FAB2_LIB.BASEBOARD_FAB2(SCH_1):GND
  DV39  GND            VSS<77>  @BASEBOARD_FAB2_LIB.BASEBOARD_FAB2(SCH_1):GND
  DV73  GND            VSS<76>  @BASEBOARD_FAB2_LIB.BASEBOARD_FAB2(SCH_1):GND
  DV77  GND            VSS<75>  @BASEBOARD_FAB2_LIB.BASEBOARD_FAB2(SCH_1):GND
  DV81  GND            VSS<74>  @BASEBOARD_FAB2_LIB.BASEBOARD_FAB2(SCH_1):GND
  DW12  GND            VSS<73>  @BASEBOARD_FAB2_LIB.BASEBOARD_FAB2(SCH_1):GND
  DW20  GND            VSS<72>  @BASEBOARD_FAB2_LIB.BASEBOARD_FAB2(SCH_1):GND
  DW24  GND            VSS<71>  @BASEBOARD_FAB2_LIB.BASEBOARD_FAB2(SCH_1):GND
  DW28  GND            VSS<70>  @BASEBOARD_FAB2_LIB.BASEBOARD_FAB2(SCH_1):GND
  DW30  GND            VSS<69>  @BASEBOARD_FAB2_LIB.BASEBOARD_FAB2(SCH_1):GND
  DW34  GND            VSS<68>  @BASEBOARD_FAB2_LIB.BASEBOARD_FAB2(SCH_1):GND
  DW36  GND            VSS<67>  @BASEBOARD_FAB2_LIB.BASEBOARD_FAB2(SCH_1):GND
  DW40  GND            VSS<66>  @BASEBOARD_FAB2_LIB.BASEBOARD_FAB2(SCH_1):GND
  DW64  GND            VSS<65>  @BASEBOARD_FAB2_LIB.BASEBOARD_FAB2(SCH_1):GND
  DW66  GND            VSS<64>  @BASEBOARD_FAB2_LIB.BASEBOARD_FAB2(SCH_1):GND
  DW68  GND            VSS<63>  @BASEBOARD_FAB2_LIB.BASEBOARD_FAB2(SCH_1):GND
  DW70  GND            VSS<62>  @BASEBOARD_FAB2_LIB.BASEBOARD_FAB2(SCH_1):GND
  DW72  GND            VSS<61>  @BASEBOARD_FAB2_LIB.BASEBOARD_FAB2(SCH_1):GND
  DW74  GND            VSS<60>  @BASEBOARD_FAB2_LIB.BASEBOARD_FAB2(SCH_1):GND
  DW76  GND            VSS<59>  @BASEBOARD_FAB2_LIB.BASEBOARD_FAB2(SCH_1):GND
  DW8  GND            VSS<58>  @BASEBOARD_FAB2_LIB.BASEBOARD_FAB2(SCH_1):GND
  DW82  GND            VSS<57>  @BASEBOARD_FAB2_LIB.BASEBOARD_FAB2(SCH_1):GND
  DW84  GND            VSS<56>  @BASEBOARD_FAB2_LIB.BASEBOARD_FAB2(SCH_1):GND
  DY5  GND            VSS<55>  @BASEBOARD_FAB2_LIB.BASEBOARD_FAB2(SCH_1):GND
  DY19  GND            VSS<54>  @BASEBOARD_FAB2_LIB.BASEBOARD_FAB2(SCH_1):GND
  DY23  GND            VSS<53>  @BASEBOARD_FAB2_LIB.BASEBOARD_FAB2(SCH_1):GND
  DY29  GND            VSS<52>  @BASEBOARD_FAB2_LIB.BASEBOARD_FAB2(SCH_1):GND
  DY35  GND            VSS<51>  @BASEBOARD_FAB2_LIB.BASEBOARD_FAB2(SCH_1):GND
  DY41  GND            VSS<50>  @BASEBOARD_FAB2_LIB.BASEBOARD_FAB2(SCH_1):GND
  DY71  GND            VSS<49>  @BASEBOARD_FAB2_LIB.BASEBOARD_FAB2(SCH_1):GND
  DY75  GND            VSS<48>  @BASEBOARD_FAB2_LIB.BASEBOARD_FAB2(SCH_1):GND
  EA6  GND            VSS<47>  @BASEBOARD_FAB2_LIB.BASEBOARD_FAB2(SCH_1):GND
  J16  GND            VSS<46>  @BASEBOARD_FAB2_LIB.BASEBOARD_FAB2(SCH_1):GND
  EA16  GND            VSS<45>  @BASEBOARD_FAB2_LIB.BASEBOARD_FAB2(SCH_1):GND
  EA20  GND            VSS<44>  @BASEBOARD_FAB2_LIB.BASEBOARD_FAB2(SCH_1):GND
  EA22  GND            VSS<43>  @BASEBOARD_FAB2_LIB.BASEBOARD_FAB2(SCH_1):GND
  EA42  GND            VSS<42>  @BASEBOARD_FAB2_LIB.BASEBOARD_FAB2(SCH_1):GND
  EA64  GND            VSS<41>  @BASEBOARD_FAB2_LIB.BASEBOARD_FAB2(SCH_1):GND
  EA70  GND            VSS<40>  @BASEBOARD_FAB2_LIB.BASEBOARD_FAB2(SCH_1):GND
  EA76  GND            VSS<39>  @BASEBOARD_FAB2_LIB.BASEBOARD_FAB2(SCH_1):GND
  EA78  GND            VSS<38>  @BASEBOARD_FAB2_LIB.BASEBOARD_FAB2(SCH_1):GND
  EA80  GND            VSS<37>  @BASEBOARD_FAB2_LIB.BASEBOARD_FAB2(SCH_1):GND
  EA82  GND            VSS<36>  @BASEBOARD_FAB2_LIB.BASEBOARD_FAB2(SCH_1):GND
  EB13  GND            VSS<35>  @BASEBOARD_FAB2_LIB.BASEBOARD_FAB2(SCH_1):GND
  BR18  GND            VSS<34>  @BASEBOARD_FAB2_LIB.BASEBOARD_FAB2(SCH_1):GND
  EB23  GND            VSS<33>  @BASEBOARD_FAB2_LIB.BASEBOARD_FAB2(SCH_1):GND
  EB25  GND            VSS<32>  @BASEBOARD_FAB2_LIB.BASEBOARD_FAB2(SCH_1):GND
  EB27  GND            VSS<31>  @BASEBOARD_FAB2_LIB.BASEBOARD_FAB2(SCH_1):GND
  EB29  GND            VSS<30>  @BASEBOARD_FAB2_LIB.BASEBOARD_FAB2(SCH_1):GND
  EB31  GND            VSS<29>  @BASEBOARD_FAB2_LIB.BASEBOARD_FAB2(SCH_1):GND
  EB33  GND            VSS<28>  @BASEBOARD_FAB2_LIB.BASEBOARD_FAB2(SCH_1):GND
  EB35  GND            VSS<27>  @BASEBOARD_FAB2_LIB.BASEBOARD_FAB2(SCH_1):GND
  EB37  GND            VSS<26>  @BASEBOARD_FAB2_LIB.BASEBOARD_FAB2(SCH_1):GND
  EB39  GND            VSS<25>  @BASEBOARD_FAB2_LIB.BASEBOARD_FAB2(SCH_1):GND
  EB41  GND            VSS<24>  @BASEBOARD_FAB2_LIB.BASEBOARD_FAB2(SCH_1):GND
  EB65  GND            VSS<23>  @BASEBOARD_FAB2_LIB.BASEBOARD_FAB2(SCH_1):GND
  EB69  GND            VSS<22>  @BASEBOARD_FAB2_LIB.BASEBOARD_FAB2(SCH_1):GND
  EC10  GND            VSS<21>  @BASEBOARD_FAB2_LIB.BASEBOARD_FAB2(SCH_1):GND
  EC70  GND            VSS<20>  @BASEBOARD_FAB2_LIB.BASEBOARD_FAB2(SCH_1):GND
  EC72  GND            VSS<19>  @BASEBOARD_FAB2_LIB.BASEBOARD_FAB2(SCH_1):GND
  EC74  GND            VSS<18>  @BASEBOARD_FAB2_LIB.BASEBOARD_FAB2(SCH_1):GND
  EC76  GND            VSS<17>  @BASEBOARD_FAB2_LIB.BASEBOARD_FAB2(SCH_1):GND
  ED11  GND            VSS<16>  @BASEBOARD_FAB2_LIB.BASEBOARD_FAB2(SCH_1):GND
  ED15  GND            VSS<15>  @BASEBOARD_FAB2_LIB.BASEBOARD_FAB2(SCH_1):GND
  ED23  GND            VSS<14>  @BASEBOARD_FAB2_LIB.BASEBOARD_FAB2(SCH_1):GND
  ED29  GND            VSS<13>  @BASEBOARD_FAB2_LIB.BASEBOARD_FAB2(SCH_1):GND
  ED35  GND            VSS<12>  @BASEBOARD_FAB2_LIB.BASEBOARD_FAB2(SCH_1):GND
  ED77  GND            VSS<11>  @BASEBOARD_FAB2_LIB.BASEBOARD_FAB2(SCH_1):GND
  EE24  GND            VSS<10>  @BASEBOARD_FAB2_LIB.BASEBOARD_FAB2(SCH_1):GND
  EE28  GND            VSS<9>  @BASEBOARD_FAB2_LIB.BASEBOARD_FAB2(SCH_1):GND
  EE30  GND            VSS<8>  @BASEBOARD_FAB2_LIB.BASEBOARD_FAB2(SCH_1):GND
  EE34  GND            VSS<7>  @BASEBOARD_FAB2_LIB.BASEBOARD_FAB2(SCH_1):GND
  EE36  GND            VSS<6>  @BASEBOARD_FAB2_LIB.BASEBOARD_FAB2(SCH_1):GND
  EE70  GND            VSS<5>  @BASEBOARD_FAB2_LIB.BASEBOARD_FAB2(SCH_1):GND
  EE76  GND            VSS<4>  @BASEBOARD_FAB2_LIB.BASEBOARD_FAB2(SCH_1):GND
  EE78  GND            VSS<3>  @BASEBOARD_FAB2_LIB.BASEBOARD_FAB2(SCH_1):GND
  EF71  GND            VSS<2>  @BASEBOARD_FAB2_LIB.BASEBOARD_FAB2(SCH_1):GND
  EF75  GND            VSS<1>  @BASEBOARD_FAB2_LIB.BASEBOARD_FAB2(SCH_1):GND
  EF79  GND            VSS<0>  @BASEBOARD_FAB2_LIB.BASEBOARD_FAB2(SCH_1):GND

SKX_EXT_B_BGA1  I19  U2D1   [SKX_EXT_B_BGA1-IC,TBD]
  DA48  GND            VSS<293>  @BASEBOARD_FAB2_LIB.BASEBOARD_FAB2(SCH_1):GND
  DA50  GND            VSS<292>  @BASEBOARD_FAB2_LIB.BASEBOARD_FAB2(SCH_1):GND
  DA64  GND            VSS<291>  @BASEBOARD_FAB2_LIB.BASEBOARD_FAB2(SCH_1):GND
  DA70  GND            VSS<290>  @BASEBOARD_FAB2_LIB.BASEBOARD_FAB2(SCH_1):GND
  DA74  GND            VSS<289>  @BASEBOARD_FAB2_LIB.BASEBOARD_FAB2(SCH_1):GND
  DA76  GND            VSS<288>  @BASEBOARD_FAB2_LIB.BASEBOARD_FAB2(SCH_1):GND
  DA78  GND            VSS<287>  @BASEBOARD_FAB2_LIB.BASEBOARD_FAB2(SCH_1):GND
  DA80  GND            VSS<286>  @BASEBOARD_FAB2_LIB.BASEBOARD_FAB2(SCH_1):GND
  DB3  GND            VSS<285>  @BASEBOARD_FAB2_LIB.BASEBOARD_FAB2(SCH_1):GND
  DB13  GND            VSS<284>  @BASEBOARD_FAB2_LIB.BASEBOARD_FAB2(SCH_1):GND
  DB17  GND            VSS<283>  @BASEBOARD_FAB2_LIB.BASEBOARD_FAB2(SCH_1):GND
  DB23  GND            VSS<282>  @BASEBOARD_FAB2_LIB.BASEBOARD_FAB2(SCH_1):GND
  DB25  GND            VSS<281>  @BASEBOARD_FAB2_LIB.BASEBOARD_FAB2(SCH_1):GND
  DB39  GND            VSS<280>  @BASEBOARD_FAB2_LIB.BASEBOARD_FAB2(SCH_1):GND
  DB41  GND            VSS<279>  @BASEBOARD_FAB2_LIB.BASEBOARD_FAB2(SCH_1):GND
  DB47  GND            VSS<278>  @BASEBOARD_FAB2_LIB.BASEBOARD_FAB2(SCH_1):GND
  DB49  GND            VSS<277>  @BASEBOARD_FAB2_LIB.BASEBOARD_FAB2(SCH_1):GND
  DB73  GND            VSS<276>  @BASEBOARD_FAB2_LIB.BASEBOARD_FAB2(SCH_1):GND
  DB77  GND            VSS<275>  @BASEBOARD_FAB2_LIB.BASEBOARD_FAB2(SCH_1):GND
  DB83  GND            VSS<274>  @BASEBOARD_FAB2_LIB.BASEBOARD_FAB2(SCH_1):GND
  DB85  GND            VSS<273>  @BASEBOARD_FAB2_LIB.BASEBOARD_FAB2(SCH_1):GND
  DC14  GND            VSS<272>  @BASEBOARD_FAB2_LIB.BASEBOARD_FAB2(SCH_1):GND
  DC24  GND            VSS<271>  @BASEBOARD_FAB2_LIB.BASEBOARD_FAB2(SCH_1):GND
  DC26  GND            VSS<270>  @BASEBOARD_FAB2_LIB.BASEBOARD_FAB2(SCH_1):GND
  DC32  GND            VSS<269>  @BASEBOARD_FAB2_LIB.BASEBOARD_FAB2(SCH_1):GND
  DC38  GND            VSS<268>  @BASEBOARD_FAB2_LIB.BASEBOARD_FAB2(SCH_1):GND
  DC42  GND            VSS<267>  @BASEBOARD_FAB2_LIB.BASEBOARD_FAB2(SCH_1):GND
  DC64  GND            VSS<266>  @BASEBOARD_FAB2_LIB.BASEBOARD_FAB2(SCH_1):GND
  DC66  GND            VSS<265>  @BASEBOARD_FAB2_LIB.BASEBOARD_FAB2(SCH_1):GND
  DC68  GND            VSS<264>  @BASEBOARD_FAB2_LIB.BASEBOARD_FAB2(SCH_1):GND
  DC70  GND            VSS<263>  @BASEBOARD_FAB2_LIB.BASEBOARD_FAB2(SCH_1):GND
  DC78  GND            VSS<262>  @BASEBOARD_FAB2_LIB.BASEBOARD_FAB2(SCH_1):GND
  DC84  GND            VSS<261>  @BASEBOARD_FAB2_LIB.BASEBOARD_FAB2(SCH_1):GND
  DC86  GND            VSS<260>  @BASEBOARD_FAB2_LIB.BASEBOARD_FAB2(SCH_1):GND
  DD11  GND            VSS<259>  @BASEBOARD_FAB2_LIB.BASEBOARD_FAB2(SCH_1):GND
  DD23  GND            VSS<258>  @BASEBOARD_FAB2_LIB.BASEBOARD_FAB2(SCH_1):GND
  DD27  GND            VSS<257>  @BASEBOARD_FAB2_LIB.BASEBOARD_FAB2(SCH_1):GND
  DD31  GND            VSS<256>  @BASEBOARD_FAB2_LIB.BASEBOARD_FAB2(SCH_1):GND
  DD33  GND            VSS<255>  @BASEBOARD_FAB2_LIB.BASEBOARD_FAB2(SCH_1):GND
  DD37  GND            VSS<254>  @BASEBOARD_FAB2_LIB.BASEBOARD_FAB2(SCH_1):GND
  DD71  GND            VSS<253>  @BASEBOARD_FAB2_LIB.BASEBOARD_FAB2(SCH_1):GND
  DD73  GND            VSS<252>  @BASEBOARD_FAB2_LIB.BASEBOARD_FAB2(SCH_1):GND
  DD75  GND            VSS<251>  @BASEBOARD_FAB2_LIB.BASEBOARD_FAB2(SCH_1):GND
  DD81  GND            VSS<250>  @BASEBOARD_FAB2_LIB.BASEBOARD_FAB2(SCH_1):GND
  DD83  GND            VSS<249>  @BASEBOARD_FAB2_LIB.BASEBOARD_FAB2(SCH_1):GND
  DE6  GND            VSS<248>  @BASEBOARD_FAB2_LIB.BASEBOARD_FAB2(SCH_1):GND
  DE8  GND            VSS<247>  @BASEBOARD_FAB2_LIB.BASEBOARD_FAB2(SCH_1):GND
  DE18  GND            VSS<246>  @BASEBOARD_FAB2_LIB.BASEBOARD_FAB2(SCH_1):GND
  DE20  GND            VSS<245>  @BASEBOARD_FAB2_LIB.BASEBOARD_FAB2(SCH_1):GND
  DE24  GND            VSS<244>  @BASEBOARD_FAB2_LIB.BASEBOARD_FAB2(SCH_1):GND
  DE28  GND            VSS<243>  @BASEBOARD_FAB2_LIB.BASEBOARD_FAB2(SCH_1):GND
  DE30  GND            VSS<242>  @BASEBOARD_FAB2_LIB.BASEBOARD_FAB2(SCH_1):GND
  DE34  GND            VSS<241>  @BASEBOARD_FAB2_LIB.BASEBOARD_FAB2(SCH_1):GND
  DE36  GND            VSS<240>  @BASEBOARD_FAB2_LIB.BASEBOARD_FAB2(SCH_1):GND
  DE64  GND            VSS<239>  @BASEBOARD_FAB2_LIB.BASEBOARD_FAB2(SCH_1):GND
  DE70  GND            VSS<238>  @BASEBOARD_FAB2_LIB.BASEBOARD_FAB2(SCH_1):GND
  DE72  GND            VSS<237>  @BASEBOARD_FAB2_LIB.BASEBOARD_FAB2(SCH_1):GND
  DE78  GND            VSS<236>  @BASEBOARD_FAB2_LIB.BASEBOARD_FAB2(SCH_1):GND
  DF5  GND            VSS<235>  @BASEBOARD_FAB2_LIB.BASEBOARD_FAB2(SCH_1):GND
  DF7  GND            VSS<234>  @BASEBOARD_FAB2_LIB.BASEBOARD_FAB2(SCH_1):GND
  H51  GND            VSS<233>  @BASEBOARD_FAB2_LIB.BASEBOARD_FAB2(SCH_1):GND
  DF19  GND            VSS<232>  @BASEBOARD_FAB2_LIB.BASEBOARD_FAB2(SCH_1):GND
  DF29  GND            VSS<231>  @BASEBOARD_FAB2_LIB.BASEBOARD_FAB2(SCH_1):GND
  DF35  GND            VSS<230>  @BASEBOARD_FAB2_LIB.BASEBOARD_FAB2(SCH_1):GND
  DF37  GND            VSS<229>  @BASEBOARD_FAB2_LIB.BASEBOARD_FAB2(SCH_1):GND
  DF39  GND            VSS<228>  @BASEBOARD_FAB2_LIB.BASEBOARD_FAB2(SCH_1):GND
  DF41  GND            VSS<227>  @BASEBOARD_FAB2_LIB.BASEBOARD_FAB2(SCH_1):GND
  DF65  GND            VSS<226>  @BASEBOARD_FAB2_LIB.BASEBOARD_FAB2(SCH_1):GND
  DF69  GND            VSS<225>  @BASEBOARD_FAB2_LIB.BASEBOARD_FAB2(SCH_1):GND
  DF73  GND            VSS<224>  @BASEBOARD_FAB2_LIB.BASEBOARD_FAB2(SCH_1):GND
  DF79  GND            VSS<223>  @BASEBOARD_FAB2_LIB.BASEBOARD_FAB2(SCH_1):GND
  DF83  GND            VSS<222>  @BASEBOARD_FAB2_LIB.BASEBOARD_FAB2(SCH_1):GND
  DF85  GND            VSS<221>  @BASEBOARD_FAB2_LIB.BASEBOARD_FAB2(SCH_1):GND
  DG2  GND            VSS<220>  @BASEBOARD_FAB2_LIB.BASEBOARD_FAB2(SCH_1):GND
  H49  GND            VSS<219>  @BASEBOARD_FAB2_LIB.BASEBOARD_FAB2(SCH_1):GND
  DG14  GND            VSS<218>  @BASEBOARD_FAB2_LIB.BASEBOARD_FAB2(SCH_1):GND
  DG16  GND            VSS<217>  @BASEBOARD_FAB2_LIB.BASEBOARD_FAB2(SCH_1):GND
  DG24  GND            VSS<216>  @BASEBOARD_FAB2_LIB.BASEBOARD_FAB2(SCH_1):GND
  DG66  GND            VSS<215>  @BASEBOARD_FAB2_LIB.BASEBOARD_FAB2(SCH_1):GND
  DG68  GND            VSS<214>  @BASEBOARD_FAB2_LIB.BASEBOARD_FAB2(SCH_1):GND
  DG76  GND            VSS<213>  @BASEBOARD_FAB2_LIB.BASEBOARD_FAB2(SCH_1):GND
  DG78  GND            VSS<212>  @BASEBOARD_FAB2_LIB.BASEBOARD_FAB2(SCH_1):GND
  DG80  GND            VSS<211>  @BASEBOARD_FAB2_LIB.BASEBOARD_FAB2(SCH_1):GND
  DG82  GND            VSS<210>  @BASEBOARD_FAB2_LIB.BASEBOARD_FAB2(SCH_1):GND
  DH13  GND            VSS<209>  @BASEBOARD_FAB2_LIB.BASEBOARD_FAB2(SCH_1):GND
  DH15  GND            VSS<208>  @BASEBOARD_FAB2_LIB.BASEBOARD_FAB2(SCH_1):GND
  DH23  GND            VSS<207>  @BASEBOARD_FAB2_LIB.BASEBOARD_FAB2(SCH_1):GND
  DH25  GND            VSS<206>  @BASEBOARD_FAB2_LIB.BASEBOARD_FAB2(SCH_1):GND
  DH27  GND            VSS<205>  @BASEBOARD_FAB2_LIB.BASEBOARD_FAB2(SCH_1):GND
  DH29  GND            VSS<204>  @BASEBOARD_FAB2_LIB.BASEBOARD_FAB2(SCH_1):GND
  DH31  GND            VSS<203>  @BASEBOARD_FAB2_LIB.BASEBOARD_FAB2(SCH_1):GND
  DH33  GND            VSS<202>  @BASEBOARD_FAB2_LIB.BASEBOARD_FAB2(SCH_1):GND
  DH35  GND            VSS<201>  @BASEBOARD_FAB2_LIB.BASEBOARD_FAB2(SCH_1):GND
  DH37  GND            VSS<200>  @BASEBOARD_FAB2_LIB.BASEBOARD_FAB2(SCH_1):GND
  DH41  GND            VSS<199>  @BASEBOARD_FAB2_LIB.BASEBOARD_FAB2(SCH_1):GND
  DH67  GND            VSS<198>  @BASEBOARD_FAB2_LIB.BASEBOARD_FAB2(SCH_1):GND
  DH71  GND            VSS<197>  @BASEBOARD_FAB2_LIB.BASEBOARD_FAB2(SCH_1):GND
  DH73  GND            VSS<196>  @BASEBOARD_FAB2_LIB.BASEBOARD_FAB2(SCH_1):GND
  DH79  GND            VSS<195>  @BASEBOARD_FAB2_LIB.BASEBOARD_FAB2(SCH_1):GND
  DH81  GND            VSS<194>  @BASEBOARD_FAB2_LIB.BASEBOARD_FAB2(SCH_1):GND
  DH83  GND            VSS<193>  @BASEBOARD_FAB2_LIB.BASEBOARD_FAB2(SCH_1):GND
  DJ2  GND            VSS<192>  @BASEBOARD_FAB2_LIB.BASEBOARD_FAB2(SCH_1):GND
  DJ10  GND            VSS<191>  @BASEBOARD_FAB2_LIB.BASEBOARD_FAB2(SCH_1):GND
  H47  GND            VSS<190>  @BASEBOARD_FAB2_LIB.BASEBOARD_FAB2(SCH_1):GND
  DJ22  GND            VSS<189>  @BASEBOARD_FAB2_LIB.BASEBOARD_FAB2(SCH_1):GND
  DJ38  GND            VSS<188>  @BASEBOARD_FAB2_LIB.BASEBOARD_FAB2(SCH_1):GND
  DJ42  GND            VSS<187>  @BASEBOARD_FAB2_LIB.BASEBOARD_FAB2(SCH_1):GND
  DJ68  GND            VSS<186>  @BASEBOARD_FAB2_LIB.BASEBOARD_FAB2(SCH_1):GND
  DJ74  GND            VSS<185>  @BASEBOARD_FAB2_LIB.BASEBOARD_FAB2(SCH_1):GND
  DJ78  GND            VSS<184>  @BASEBOARD_FAB2_LIB.BASEBOARD_FAB2(SCH_1):GND
  DJ82  GND            VSS<183>  @BASEBOARD_FAB2_LIB.BASEBOARD_FAB2(SCH_1):GND
  DJ84  GND            VSS<182>  @BASEBOARD_FAB2_LIB.BASEBOARD_FAB2(SCH_1):GND
  DK7  GND            VSS<181>  @BASEBOARD_FAB2_LIB.BASEBOARD_FAB2(SCH_1):GND
  DK23  GND            VSS<180>  @BASEBOARD_FAB2_LIB.BASEBOARD_FAB2(SCH_1):GND
  DK29  GND            VSS<179>  @BASEBOARD_FAB2_LIB.BASEBOARD_FAB2(SCH_1):GND
  DK35  GND            VSS<178>  @BASEBOARD_FAB2_LIB.BASEBOARD_FAB2(SCH_1):GND
  DK39  GND            VSS<177>  @BASEBOARD_FAB2_LIB.BASEBOARD_FAB2(SCH_1):GND
  DK41  GND            VSS<176>  @BASEBOARD_FAB2_LIB.BASEBOARD_FAB2(SCH_1):GND
  DK73  GND            VSS<175>  @BASEBOARD_FAB2_LIB.BASEBOARD_FAB2(SCH_1):GND
  DK75  GND            VSS<174>  @BASEBOARD_FAB2_LIB.BASEBOARD_FAB2(SCH_1):GND
  DK77  GND            VSS<173>  @BASEBOARD_FAB2_LIB.BASEBOARD_FAB2(SCH_1):GND
  DK83  GND            VSS<172>  @BASEBOARD_FAB2_LIB.BASEBOARD_FAB2(SCH_1):GND
  DK85  GND            VSS<171>  @BASEBOARD_FAB2_LIB.BASEBOARD_FAB2(SCH_1):GND
  DL16  GND            VSS<170>  @BASEBOARD_FAB2_LIB.BASEBOARD_FAB2(SCH_1):GND
  DL18  GND            VSS<169>  @BASEBOARD_FAB2_LIB.BASEBOARD_FAB2(SCH_1):GND
  DL4  GND            VSS<168>  @BASEBOARD_FAB2_LIB.BASEBOARD_FAB2(SCH_1):GND
  DL22  GND            VSS<167>  @BASEBOARD_FAB2_LIB.BASEBOARD_FAB2(SCH_1):GND
  DL24  GND            VSS<166>  @BASEBOARD_FAB2_LIB.BASEBOARD_FAB2(SCH_1):GND
  DL28  GND            VSS<165>  @BASEBOARD_FAB2_LIB.BASEBOARD_FAB2(SCH_1):GND
  DL30  GND            VSS<164>  @BASEBOARD_FAB2_LIB.BASEBOARD_FAB2(SCH_1):GND
  DL34  GND            VSS<163>  @BASEBOARD_FAB2_LIB.BASEBOARD_FAB2(SCH_1):GND
  DL36  GND            VSS<162>  @BASEBOARD_FAB2_LIB.BASEBOARD_FAB2(SCH_1):GND
  DL40  GND            VSS<161>  @BASEBOARD_FAB2_LIB.BASEBOARD_FAB2(SCH_1):GND
  DL68  GND            VSS<160>  @BASEBOARD_FAB2_LIB.BASEBOARD_FAB2(SCH_1):GND
  DL70  GND            VSS<159>  @BASEBOARD_FAB2_LIB.BASEBOARD_FAB2(SCH_1):GND
  DL74  GND            VSS<158>  @BASEBOARD_FAB2_LIB.BASEBOARD_FAB2(SCH_1):GND
  DL76  GND            VSS<157>  @BASEBOARD_FAB2_LIB.BASEBOARD_FAB2(SCH_1):GND
  DL78  GND            VSS<156>  @BASEBOARD_FAB2_LIB.BASEBOARD_FAB2(SCH_1):GND
  DL80  GND            VSS<155>  @BASEBOARD_FAB2_LIB.BASEBOARD_FAB2(SCH_1):GND
  DM15  GND            VSS<154>  @BASEBOARD_FAB2_LIB.BASEBOARD_FAB2(SCH_1):GND
  H45  GND            VSS<153>  @BASEBOARD_FAB2_LIB.BASEBOARD_FAB2(SCH_1):GND
  DM25  GND            VSS<152>  @BASEBOARD_FAB2_LIB.BASEBOARD_FAB2(SCH_1):GND
  DM27  GND            VSS<151>  @BASEBOARD_FAB2_LIB.BASEBOARD_FAB2(SCH_1):GND
  DM31  GND            VSS<150>  @BASEBOARD_FAB2_LIB.BASEBOARD_FAB2(SCH_1):GND
  DM33  GND            VSS<149>  @BASEBOARD_FAB2_LIB.BASEBOARD_FAB2(SCH_1):GND
  DM37  GND            VSS<148>  @BASEBOARD_FAB2_LIB.BASEBOARD_FAB2(SCH_1):GND
  DM39  GND            VSS<147>  @BASEBOARD_FAB2_LIB.BASEBOARD_FAB2(SCH_1):GND
  DM65  GND            VSS<146>  @BASEBOARD_FAB2_LIB.BASEBOARD_FAB2(SCH_1):GND
  DM73  GND            VSS<145>  @BASEBOARD_FAB2_LIB.BASEBOARD_FAB2(SCH_1):GND
  DM77  GND            VSS<144>  @BASEBOARD_FAB2_LIB.BASEBOARD_FAB2(SCH_1):GND
  DM83  GND            VSS<143>  @BASEBOARD_FAB2_LIB.BASEBOARD_FAB2(SCH_1):GND
  DN2  GND            VSS<142>  @BASEBOARD_FAB2_LIB.BASEBOARD_FAB2(SCH_1):GND
  BH17  GND            VSS<141>  @BASEBOARD_FAB2_LIB.BASEBOARD_FAB2(SCH_1):GND
  DN12  GND            VSS<140>  @BASEBOARD_FAB2_LIB.BASEBOARD_FAB2(SCH_1):GND
  DN22  GND            VSS<139>  @BASEBOARD_FAB2_LIB.BASEBOARD_FAB2(SCH_1):GND
  DN26  GND            VSS<138>  @BASEBOARD_FAB2_LIB.BASEBOARD_FAB2(SCH_1):GND
  DN32  GND            VSS<137>  @BASEBOARD_FAB2_LIB.BASEBOARD_FAB2(SCH_1):GND
  DN38  GND            VSS<136>  @BASEBOARD_FAB2_LIB.BASEBOARD_FAB2(SCH_1):GND
  DN68  GND            VSS<135>  @BASEBOARD_FAB2_LIB.BASEBOARD_FAB2(SCH_1):GND
  DN72  GND            VSS<134>  @BASEBOARD_FAB2_LIB.BASEBOARD_FAB2(SCH_1):GND

SKX_EXT_B_BGA1  I18  U2D1   [SKX_EXT_B_BGA1-IC,TBD]
  P47  GND            VSS<453>  @BASEBOARD_FAB2_LIB.BASEBOARD_FAB2(SCH_1):GND
  CJ62  GND            VSS<452>  @BASEBOARD_FAB2_LIB.BASEBOARD_FAB2(SCH_1):GND
  CJ74  GND            VSS<451>  @BASEBOARD_FAB2_LIB.BASEBOARD_FAB2(SCH_1):GND
  CJ76  GND            VSS<450>  @BASEBOARD_FAB2_LIB.BASEBOARD_FAB2(SCH_1):GND
  CJ78  GND            VSS<449>  @BASEBOARD_FAB2_LIB.BASEBOARD_FAB2(SCH_1):GND
  CJ82  GND            VSS<448>  @BASEBOARD_FAB2_LIB.BASEBOARD_FAB2(SCH_1):GND
  CJ84  GND            VSS<447>  @BASEBOARD_FAB2_LIB.BASEBOARD_FAB2(SCH_1):GND
  CJ86  GND            VSS<446>  @BASEBOARD_FAB2_LIB.BASEBOARD_FAB2(SCH_1):GND
  CK11  GND            VSS<445>  @BASEBOARD_FAB2_LIB.BASEBOARD_FAB2(SCH_1):GND
  CK15  GND            VSS<444>  @BASEBOARD_FAB2_LIB.BASEBOARD_FAB2(SCH_1):GND
  CK21  GND            VSS<443>  @BASEBOARD_FAB2_LIB.BASEBOARD_FAB2(SCH_1):GND
  CK27  GND            VSS<442>  @BASEBOARD_FAB2_LIB.BASEBOARD_FAB2(SCH_1):GND
  CK63  GND            VSS<441>  @BASEBOARD_FAB2_LIB.BASEBOARD_FAB2(SCH_1):GND
  CK65  GND            VSS<440>  @BASEBOARD_FAB2_LIB.BASEBOARD_FAB2(SCH_1):GND
  CK67  GND            VSS<439>  @BASEBOARD_FAB2_LIB.BASEBOARD_FAB2(SCH_1):GND
  CK69  GND            VSS<438>  @BASEBOARD_FAB2_LIB.BASEBOARD_FAB2(SCH_1):GND
  CK71  GND            VSS<437>  @BASEBOARD_FAB2_LIB.BASEBOARD_FAB2(SCH_1):GND
  CK73  GND            VSS<436>  @BASEBOARD_FAB2_LIB.BASEBOARD_FAB2(SCH_1):GND
  CK75  GND            VSS<435>  @BASEBOARD_FAB2_LIB.BASEBOARD_FAB2(SCH_1):GND
  CK83  GND            VSS<434>  @BASEBOARD_FAB2_LIB.BASEBOARD_FAB2(SCH_1):GND
  CK85  GND            VSS<433>  @BASEBOARD_FAB2_LIB.BASEBOARD_FAB2(SCH_1):GND
  CL8  GND            VSS<432>  @BASEBOARD_FAB2_LIB.BASEBOARD_FAB2(SCH_1):GND
  CL14  GND            VSS<431>  @BASEBOARD_FAB2_LIB.BASEBOARD_FAB2(SCH_1):GND
  CL18  GND            VSS<430>  @BASEBOARD_FAB2_LIB.BASEBOARD_FAB2(SCH_1):GND
  P45  GND            VSS<429>  @BASEBOARD_FAB2_LIB.BASEBOARD_FAB2(SCH_1):GND
  H63  GND            VSS<428>  @BASEBOARD_FAB2_LIB.BASEBOARD_FAB2(SCH_1):GND
  CL62  GND            VSS<427>  @BASEBOARD_FAB2_LIB.BASEBOARD_FAB2(SCH_1):GND
  CL64  GND            VSS<426>  @BASEBOARD_FAB2_LIB.BASEBOARD_FAB2(SCH_1):GND
  CL66  GND            VSS<425>  @BASEBOARD_FAB2_LIB.BASEBOARD_FAB2(SCH_1):GND
  CL74  GND            VSS<424>  @BASEBOARD_FAB2_LIB.BASEBOARD_FAB2(SCH_1):GND
  CL76  GND            VSS<423>  @BASEBOARD_FAB2_LIB.BASEBOARD_FAB2(SCH_1):GND
  CL78  GND            VSS<422>  @BASEBOARD_FAB2_LIB.BASEBOARD_FAB2(SCH_1):GND
  CL80  GND            VSS<421>  @BASEBOARD_FAB2_LIB.BASEBOARD_FAB2(SCH_1):GND
  CM19  GND            VSS<420>  @BASEBOARD_FAB2_LIB.BASEBOARD_FAB2(SCH_1):GND
  CM29  GND            VSS<419>  @BASEBOARD_FAB2_LIB.BASEBOARD_FAB2(SCH_1):GND
  CM5  GND            VSS<418>  @BASEBOARD_FAB2_LIB.BASEBOARD_FAB2(SCH_1):GND
  CM31  GND            VSS<417>  @BASEBOARD_FAB2_LIB.BASEBOARD_FAB2(SCH_1):GND
  CM61  GND            VSS<416>  @BASEBOARD_FAB2_LIB.BASEBOARD_FAB2(SCH_1):GND
  CM63  GND            VSS<415>  @BASEBOARD_FAB2_LIB.BASEBOARD_FAB2(SCH_1):GND
  CM67  GND            VSS<414>  @BASEBOARD_FAB2_LIB.BASEBOARD_FAB2(SCH_1):GND
  CM73  GND            VSS<413>  @BASEBOARD_FAB2_LIB.BASEBOARD_FAB2(SCH_1):GND
  CM77  GND            VSS<412>  @BASEBOARD_FAB2_LIB.BASEBOARD_FAB2(SCH_1):GND
  CM83  GND            VSS<411>  @BASEBOARD_FAB2_LIB.BASEBOARD_FAB2(SCH_1):GND
  CM85  GND            VSS<410>  @BASEBOARD_FAB2_LIB.BASEBOARD_FAB2(SCH_1):GND
  CN2  GND            VSS<409>  @BASEBOARD_FAB2_LIB.BASEBOARD_FAB2(SCH_1):GND
  CN12  GND            VSS<408>  @BASEBOARD_FAB2_LIB.BASEBOARD_FAB2(SCH_1):GND
  H61  GND            VSS<407>  @BASEBOARD_FAB2_LIB.BASEBOARD_FAB2(SCH_1):GND
  CN26  GND            VSS<406>  @BASEBOARD_FAB2_LIB.BASEBOARD_FAB2(SCH_1):GND
  CN32  GND            VSS<405>  @BASEBOARD_FAB2_LIB.BASEBOARD_FAB2(SCH_1):GND
  CN60  GND            VSS<404>  @BASEBOARD_FAB2_LIB.BASEBOARD_FAB2(SCH_1):GND
  CN62  GND            VSS<403>  @BASEBOARD_FAB2_LIB.BASEBOARD_FAB2(SCH_1):GND
  CN68  GND            VSS<402>  @BASEBOARD_FAB2_LIB.BASEBOARD_FAB2(SCH_1):GND
  CN78  GND            VSS<401>  @BASEBOARD_FAB2_LIB.BASEBOARD_FAB2(SCH_1):GND
  CP1  GND            VSS<400>  @BASEBOARD_FAB2_LIB.BASEBOARD_FAB2(SCH_1):GND
  H59  GND            VSS<399>  @BASEBOARD_FAB2_LIB.BASEBOARD_FAB2(SCH_1):GND
  CP25  GND            VSS<398>  @BASEBOARD_FAB2_LIB.BASEBOARD_FAB2(SCH_1):GND
  CP59  GND            VSS<397>  @BASEBOARD_FAB2_LIB.BASEBOARD_FAB2(SCH_1):GND
  CP69  GND            VSS<396>  @BASEBOARD_FAB2_LIB.BASEBOARD_FAB2(SCH_1):GND
  CP73  GND            VSS<395>  @BASEBOARD_FAB2_LIB.BASEBOARD_FAB2(SCH_1):GND
  CP75  GND            VSS<394>  @BASEBOARD_FAB2_LIB.BASEBOARD_FAB2(SCH_1):GND
  CP81  GND            VSS<393>  @BASEBOARD_FAB2_LIB.BASEBOARD_FAB2(SCH_1):GND
  CP83  GND            VSS<392>  @BASEBOARD_FAB2_LIB.BASEBOARD_FAB2(SCH_1):GND
  CR6  GND            VSS<391>  @BASEBOARD_FAB2_LIB.BASEBOARD_FAB2(SCH_1):GND
  CR10  GND            VSS<390>  @BASEBOARD_FAB2_LIB.BASEBOARD_FAB2(SCH_1):GND
  CR22  GND            VSS<389>  @BASEBOARD_FAB2_LIB.BASEBOARD_FAB2(SCH_1):GND
  CR24  GND            VSS<388>  @BASEBOARD_FAB2_LIB.BASEBOARD_FAB2(SCH_1):GND
  CR32  GND            VSS<387>  @BASEBOARD_FAB2_LIB.BASEBOARD_FAB2(SCH_1):GND
  CR58  GND            VSS<386>  @BASEBOARD_FAB2_LIB.BASEBOARD_FAB2(SCH_1):GND
  CR62  GND            VSS<385>  @BASEBOARD_FAB2_LIB.BASEBOARD_FAB2(SCH_1):GND
  CR64  GND            VSS<384>  @BASEBOARD_FAB2_LIB.BASEBOARD_FAB2(SCH_1):GND
  CR66  GND            VSS<383>  @BASEBOARD_FAB2_LIB.BASEBOARD_FAB2(SCH_1):GND
  CR68  GND            VSS<382>  @BASEBOARD_FAB2_LIB.BASEBOARD_FAB2(SCH_1):GND
  CR78  GND            VSS<381>  @BASEBOARD_FAB2_LIB.BASEBOARD_FAB2(SCH_1):GND
  CR86  GND            VSS<380>  @BASEBOARD_FAB2_LIB.BASEBOARD_FAB2(SCH_1):GND
  H57  GND            VSS<379>  @BASEBOARD_FAB2_LIB.BASEBOARD_FAB2(SCH_1):GND
  CT13  GND            VSS<378>  @BASEBOARD_FAB2_LIB.BASEBOARD_FAB2(SCH_1):GND
  CT19  GND            VSS<377>  @BASEBOARD_FAB2_LIB.BASEBOARD_FAB2(SCH_1):GND
  CT27  GND            VSS<376>  @BASEBOARD_FAB2_LIB.BASEBOARD_FAB2(SCH_1):GND
  CT29  GND            VSS<375>  @BASEBOARD_FAB2_LIB.BASEBOARD_FAB2(SCH_1):GND
  CT33  GND            VSS<374>  @BASEBOARD_FAB2_LIB.BASEBOARD_FAB2(SCH_1):GND
  CT35  GND            VSS<373>  @BASEBOARD_FAB2_LIB.BASEBOARD_FAB2(SCH_1):GND
  CT57  GND            VSS<372>  @BASEBOARD_FAB2_LIB.BASEBOARD_FAB2(SCH_1):GND
  CT73  GND            VSS<371>  @BASEBOARD_FAB2_LIB.BASEBOARD_FAB2(SCH_1):GND
  CT79  GND            VSS<370>  @BASEBOARD_FAB2_LIB.BASEBOARD_FAB2(SCH_1):GND
  CT83  GND            VSS<369>  @BASEBOARD_FAB2_LIB.BASEBOARD_FAB2(SCH_1):GND
  CT85  GND            VSS<368>  @BASEBOARD_FAB2_LIB.BASEBOARD_FAB2(SCH_1):GND
  CU4  GND            VSS<367>  @BASEBOARD_FAB2_LIB.BASEBOARD_FAB2(SCH_1):GND
  CU22  GND            VSS<366>  @BASEBOARD_FAB2_LIB.BASEBOARD_FAB2(SCH_1):GND
  CU28  GND            VSS<365>  @BASEBOARD_FAB2_LIB.BASEBOARD_FAB2(SCH_1):GND
  CU30  GND            VSS<364>  @BASEBOARD_FAB2_LIB.BASEBOARD_FAB2(SCH_1):GND
  CU34  GND            VSS<363>  @BASEBOARD_FAB2_LIB.BASEBOARD_FAB2(SCH_1):GND
  CU36  GND            VSS<362>  @BASEBOARD_FAB2_LIB.BASEBOARD_FAB2(SCH_1):GND
  CU56  GND            VSS<361>  @BASEBOARD_FAB2_LIB.BASEBOARD_FAB2(SCH_1):GND
  CU62  GND            VSS<360>  @BASEBOARD_FAB2_LIB.BASEBOARD_FAB2(SCH_1):GND
  CU68  GND            VSS<359>  @BASEBOARD_FAB2_LIB.BASEBOARD_FAB2(SCH_1):GND
  CU76  GND            VSS<358>  @BASEBOARD_FAB2_LIB.BASEBOARD_FAB2(SCH_1):GND
  CU78  GND            VSS<357>  @BASEBOARD_FAB2_LIB.BASEBOARD_FAB2(SCH_1):GND
  CU80  GND            VSS<356>  @BASEBOARD_FAB2_LIB.BASEBOARD_FAB2(SCH_1):GND
  CU82  GND            VSS<355>  @BASEBOARD_FAB2_LIB.BASEBOARD_FAB2(SCH_1):GND
  CU86  GND            VSS<354>  @BASEBOARD_FAB2_LIB.BASEBOARD_FAB2(SCH_1):GND
  CV1  GND            VSS<353>  @BASEBOARD_FAB2_LIB.BASEBOARD_FAB2(SCH_1):GND
  H55  GND            VSS<352>  @BASEBOARD_FAB2_LIB.BASEBOARD_FAB2(SCH_1):GND
  CV17  GND            VSS<351>  @BASEBOARD_FAB2_LIB.BASEBOARD_FAB2(SCH_1):GND
  CV25  GND            VSS<350>  @BASEBOARD_FAB2_LIB.BASEBOARD_FAB2(SCH_1):GND
  CV27  GND            VSS<349>  @BASEBOARD_FAB2_LIB.BASEBOARD_FAB2(SCH_1):GND
  CV31  GND            VSS<348>  @BASEBOARD_FAB2_LIB.BASEBOARD_FAB2(SCH_1):GND
  CV33  GND            VSS<347>  @BASEBOARD_FAB2_LIB.BASEBOARD_FAB2(SCH_1):GND
  CV37  GND            VSS<346>  @BASEBOARD_FAB2_LIB.BASEBOARD_FAB2(SCH_1):GND
  CV39  GND            VSS<345>  @BASEBOARD_FAB2_LIB.BASEBOARD_FAB2(SCH_1):GND
  CV41  GND            VSS<344>  @BASEBOARD_FAB2_LIB.BASEBOARD_FAB2(SCH_1):GND
  CV53  GND            VSS<343>  @BASEBOARD_FAB2_LIB.BASEBOARD_FAB2(SCH_1):GND
  CV55  GND            VSS<342>  @BASEBOARD_FAB2_LIB.BASEBOARD_FAB2(SCH_1):GND
  CV63  GND            VSS<341>  @BASEBOARD_FAB2_LIB.BASEBOARD_FAB2(SCH_1):GND
  CV67  GND            VSS<340>  @BASEBOARD_FAB2_LIB.BASEBOARD_FAB2(SCH_1):GND
  CV73  GND            VSS<339>  @BASEBOARD_FAB2_LIB.BASEBOARD_FAB2(SCH_1):GND
  CV79  GND            VSS<338>  @BASEBOARD_FAB2_LIB.BASEBOARD_FAB2(SCH_1):GND
  CV81  GND            VSS<337>  @BASEBOARD_FAB2_LIB.BASEBOARD_FAB2(SCH_1):GND
  CV83  GND            VSS<336>  @BASEBOARD_FAB2_LIB.BASEBOARD_FAB2(SCH_1):GND
  CW12  GND            VSS<335>  @BASEBOARD_FAB2_LIB.BASEBOARD_FAB2(SCH_1):GND
  CW26  GND            VSS<334>  @BASEBOARD_FAB2_LIB.BASEBOARD_FAB2(SCH_1):GND
  CW32  GND            VSS<333>  @BASEBOARD_FAB2_LIB.BASEBOARD_FAB2(SCH_1):GND
  CW38  GND            VSS<332>  @BASEBOARD_FAB2_LIB.BASEBOARD_FAB2(SCH_1):GND
  CW40  GND            VSS<331>  @BASEBOARD_FAB2_LIB.BASEBOARD_FAB2(SCH_1):GND
  CW42  GND            VSS<330>  @BASEBOARD_FAB2_LIB.BASEBOARD_FAB2(SCH_1):GND
  CW52  GND            VSS<329>  @BASEBOARD_FAB2_LIB.BASEBOARD_FAB2(SCH_1):GND
  CW54  GND            VSS<328>  @BASEBOARD_FAB2_LIB.BASEBOARD_FAB2(SCH_1):GND
  CW64  GND            VSS<327>  @BASEBOARD_FAB2_LIB.BASEBOARD_FAB2(SCH_1):GND
  CW66  GND            VSS<326>  @BASEBOARD_FAB2_LIB.BASEBOARD_FAB2(SCH_1):GND
  CW68  GND            VSS<325>  @BASEBOARD_FAB2_LIB.BASEBOARD_FAB2(SCH_1):GND
  CW74  GND            VSS<324>  @BASEBOARD_FAB2_LIB.BASEBOARD_FAB2(SCH_1):GND
  CW78  GND            VSS<323>  @BASEBOARD_FAB2_LIB.BASEBOARD_FAB2(SCH_1):GND
  CW82  GND            VSS<322>  @BASEBOARD_FAB2_LIB.BASEBOARD_FAB2(SCH_1):GND
  CY1  GND            VSS<321>  @BASEBOARD_FAB2_LIB.BASEBOARD_FAB2(SCH_1):GND
  CY9  GND            VSS<320>  @BASEBOARD_FAB2_LIB.BASEBOARD_FAB2(SCH_1):GND
  CY13  GND            VSS<319>  @BASEBOARD_FAB2_LIB.BASEBOARD_FAB2(SCH_1):GND
  CY15  GND            VSS<318>  @BASEBOARD_FAB2_LIB.BASEBOARD_FAB2(SCH_1):GND
  CY21  GND            VSS<317>  @BASEBOARD_FAB2_LIB.BASEBOARD_FAB2(SCH_1):GND
  CY41  GND            VSS<316>  @BASEBOARD_FAB2_LIB.BASEBOARD_FAB2(SCH_1):GND
  CY45  GND            VSS<315>  @BASEBOARD_FAB2_LIB.BASEBOARD_FAB2(SCH_1):GND
  CY51  GND            VSS<314>  @BASEBOARD_FAB2_LIB.BASEBOARD_FAB2(SCH_1):GND
  CY59  GND            VSS<313>  @BASEBOARD_FAB2_LIB.BASEBOARD_FAB2(SCH_1):GND
  CY61  GND            VSS<312>  @BASEBOARD_FAB2_LIB.BASEBOARD_FAB2(SCH_1):GND
  CY65  GND            VSS<311>  @BASEBOARD_FAB2_LIB.BASEBOARD_FAB2(SCH_1):GND
  CY69  GND            VSS<310>  @BASEBOARD_FAB2_LIB.BASEBOARD_FAB2(SCH_1):GND
  CY75  GND            VSS<309>  @BASEBOARD_FAB2_LIB.BASEBOARD_FAB2(SCH_1):GND
  CY77  GND            VSS<308>  @BASEBOARD_FAB2_LIB.BASEBOARD_FAB2(SCH_1):GND
  CY83  GND            VSS<307>  @BASEBOARD_FAB2_LIB.BASEBOARD_FAB2(SCH_1):GND
  CY85  GND            VSS<306>  @BASEBOARD_FAB2_LIB.BASEBOARD_FAB2(SCH_1):GND
  DA6  GND            VSS<305>  @BASEBOARD_FAB2_LIB.BASEBOARD_FAB2(SCH_1):GND
  H53  GND            VSS<304>  @BASEBOARD_FAB2_LIB.BASEBOARD_FAB2(SCH_1):GND
  DA18  GND            VSS<303>  @BASEBOARD_FAB2_LIB.BASEBOARD_FAB2(SCH_1):GND
  DA26  GND            VSS<302>  @BASEBOARD_FAB2_LIB.BASEBOARD_FAB2(SCH_1):GND
  DA28  GND            VSS<301>  @BASEBOARD_FAB2_LIB.BASEBOARD_FAB2(SCH_1):GND
  DA30  GND            VSS<300>  @BASEBOARD_FAB2_LIB.BASEBOARD_FAB2(SCH_1):GND
  DA32  GND            VSS<299>  @BASEBOARD_FAB2_LIB.BASEBOARD_FAB2(SCH_1):GND
  DA34  GND            VSS<298>  @BASEBOARD_FAB2_LIB.BASEBOARD_FAB2(SCH_1):GND
  DA36  GND            VSS<297>  @BASEBOARD_FAB2_LIB.BASEBOARD_FAB2(SCH_1):GND
  DA38  GND            VSS<296>  @BASEBOARD_FAB2_LIB.BASEBOARD_FAB2(SCH_1):GND
  DA44  GND            VSS<295>  @BASEBOARD_FAB2_LIB.BASEBOARD_FAB2(SCH_1):GND
  DA46  GND            VSS<294>  @BASEBOARD_FAB2_LIB.BASEBOARD_FAB2(SCH_1):GND

SKX_EXT_B_BGA1  I17  U2D1   [SKX_EXT_B_BGA1-IC,TBD]
  BG74  GND            VSS<613>  @BASEBOARD_FAB2_LIB.BASEBOARD_FAB2(SCH_1):GND
  BG76  GND            VSS<612>  @BASEBOARD_FAB2_LIB.BASEBOARD_FAB2(SCH_1):GND
  BG78  GND            VSS<611>  @BASEBOARD_FAB2_LIB.BASEBOARD_FAB2(SCH_1):GND
  BG80  GND            VSS<610>  @BASEBOARD_FAB2_LIB.BASEBOARD_FAB2(SCH_1):GND
  BG82  GND            VSS<609>  @BASEBOARD_FAB2_LIB.BASEBOARD_FAB2(SCH_1):GND
  BH7  GND            VSS<608>  @BASEBOARD_FAB2_LIB.BASEBOARD_FAB2(SCH_1):GND
  BH9  GND            VSS<607>  @BASEBOARD_FAB2_LIB.BASEBOARD_FAB2(SCH_1):GND
  BH11  GND            VSS<606>  @BASEBOARD_FAB2_LIB.BASEBOARD_FAB2(SCH_1):GND
  BH15  GND            VSS<605>  @BASEBOARD_FAB2_LIB.BASEBOARD_FAB2(SCH_1):GND
  BH21  GND            VSS<604>  @BASEBOARD_FAB2_LIB.BASEBOARD_FAB2(SCH_1):GND
  BJ4  GND            VSS<603>  @BASEBOARD_FAB2_LIB.BASEBOARD_FAB2(SCH_1):GND
  BJ6  GND            VSS<602>  @BASEBOARD_FAB2_LIB.BASEBOARD_FAB2(SCH_1):GND
  BK3  GND            VSS<601>  @BASEBOARD_FAB2_LIB.BASEBOARD_FAB2(SCH_1):GND
  BK7  GND            VSS<600>  @BASEBOARD_FAB2_LIB.BASEBOARD_FAB2(SCH_1):GND
  BK11  GND            VSS<599>  @BASEBOARD_FAB2_LIB.BASEBOARD_FAB2(SCH_1):GND
  BK19  GND            VSS<598>  @BASEBOARD_FAB2_LIB.BASEBOARD_FAB2(SCH_1):GND
  BL6  GND            VSS<597>  @BASEBOARD_FAB2_LIB.BASEBOARD_FAB2(SCH_1):GND
  BL10  GND            VSS<596>  @BASEBOARD_FAB2_LIB.BASEBOARD_FAB2(SCH_1):GND
  BL12  GND            VSS<595>  @BASEBOARD_FAB2_LIB.BASEBOARD_FAB2(SCH_1):GND
  P61  GND            VSS<594>  @BASEBOARD_FAB2_LIB.BASEBOARD_FAB2(SCH_1):GND
  BL22  GND            VSS<593>  @BASEBOARD_FAB2_LIB.BASEBOARD_FAB2(SCH_1):GND
  BL24  GND            VSS<592>  @BASEBOARD_FAB2_LIB.BASEBOARD_FAB2(SCH_1):GND
  BL64  GND            VSS<591>  @BASEBOARD_FAB2_LIB.BASEBOARD_FAB2(SCH_1):GND
  BL66  GND            VSS<590>  @BASEBOARD_FAB2_LIB.BASEBOARD_FAB2(SCH_1):GND
  BL68  GND            VSS<589>  @BASEBOARD_FAB2_LIB.BASEBOARD_FAB2(SCH_1):GND
  BL70  GND            VSS<588>  @BASEBOARD_FAB2_LIB.BASEBOARD_FAB2(SCH_1):GND
  BL72  GND            VSS<587>  @BASEBOARD_FAB2_LIB.BASEBOARD_FAB2(SCH_1):GND
  BL74  GND            VSS<586>  @BASEBOARD_FAB2_LIB.BASEBOARD_FAB2(SCH_1):GND
  BL76  GND            VSS<585>  @BASEBOARD_FAB2_LIB.BASEBOARD_FAB2(SCH_1):GND
  BL78  GND            VSS<584>  @BASEBOARD_FAB2_LIB.BASEBOARD_FAB2(SCH_1):GND
  BL80  GND            VSS<583>  @BASEBOARD_FAB2_LIB.BASEBOARD_FAB2(SCH_1):GND
  BL82  GND            VSS<582>  @BASEBOARD_FAB2_LIB.BASEBOARD_FAB2(SCH_1):GND
  BM9  GND            VSS<581>  @BASEBOARD_FAB2_LIB.BASEBOARD_FAB2(SCH_1):GND
  BM13  GND            VSS<580>  @BASEBOARD_FAB2_LIB.BASEBOARD_FAB2(SCH_1):GND
  BM15  GND            VSS<579>  @BASEBOARD_FAB2_LIB.BASEBOARD_FAB2(SCH_1):GND
  P59  GND            VSS<578>  @BASEBOARD_FAB2_LIB.BASEBOARD_FAB2(SCH_1):GND
  BM25  GND            VSS<577>  @BASEBOARD_FAB2_LIB.BASEBOARD_FAB2(SCH_1):GND
  BN6  GND            VSS<576>  @BASEBOARD_FAB2_LIB.BASEBOARD_FAB2(SCH_1):GND
  BN10  GND            VSS<575>  @BASEBOARD_FAB2_LIB.BASEBOARD_FAB2(SCH_1):GND
  BN20  GND            VSS<574>  @BASEBOARD_FAB2_LIB.BASEBOARD_FAB2(SCH_1):GND
  BN26  GND            VSS<573>  @BASEBOARD_FAB2_LIB.BASEBOARD_FAB2(SCH_1):GND
  BP3  GND            VSS<572>  @BASEBOARD_FAB2_LIB.BASEBOARD_FAB2(SCH_1):GND
  BP27  GND            VSS<571>  @BASEBOARD_FAB2_LIB.BASEBOARD_FAB2(SCH_1):GND
  BR6  GND            VSS<570>  @BASEBOARD_FAB2_LIB.BASEBOARD_FAB2(SCH_1):GND
  BR10  GND            VSS<569>  @BASEBOARD_FAB2_LIB.BASEBOARD_FAB2(SCH_1):GND
  BR16  GND            VSS<568>  @BASEBOARD_FAB2_LIB.BASEBOARD_FAB2(SCH_1):GND
  P57  GND            VSS<567>  @BASEBOARD_FAB2_LIB.BASEBOARD_FAB2(SCH_1):GND
  BR64  GND            VSS<566>  @BASEBOARD_FAB2_LIB.BASEBOARD_FAB2(SCH_1):GND
  BR66  GND            VSS<565>  @BASEBOARD_FAB2_LIB.BASEBOARD_FAB2(SCH_1):GND
  BR68  GND            VSS<564>  @BASEBOARD_FAB2_LIB.BASEBOARD_FAB2(SCH_1):GND
  BR70  GND            VSS<563>  @BASEBOARD_FAB2_LIB.BASEBOARD_FAB2(SCH_1):GND
  BR72  GND            VSS<562>  @BASEBOARD_FAB2_LIB.BASEBOARD_FAB2(SCH_1):GND
  BR74  GND            VSS<561>  @BASEBOARD_FAB2_LIB.BASEBOARD_FAB2(SCH_1):GND
  BR76  GND            VSS<560>  @BASEBOARD_FAB2_LIB.BASEBOARD_FAB2(SCH_1):GND
  BR78  GND            VSS<559>  @BASEBOARD_FAB2_LIB.BASEBOARD_FAB2(SCH_1):GND
  BR80  GND            VSS<558>  @BASEBOARD_FAB2_LIB.BASEBOARD_FAB2(SCH_1):GND
  BR82  GND            VSS<557>  @BASEBOARD_FAB2_LIB.BASEBOARD_FAB2(SCH_1):GND
  BT3  GND            VSS<556>  @BASEBOARD_FAB2_LIB.BASEBOARD_FAB2(SCH_1):GND
  BT5  GND            VSS<555>  @BASEBOARD_FAB2_LIB.BASEBOARD_FAB2(SCH_1):GND
  BT21  GND            VSS<554>  @BASEBOARD_FAB2_LIB.BASEBOARD_FAB2(SCH_1):GND
  BT23  GND            VSS<553>  @BASEBOARD_FAB2_LIB.BASEBOARD_FAB2(SCH_1):GND
  BT25  GND            VSS<552>  @BASEBOARD_FAB2_LIB.BASEBOARD_FAB2(SCH_1):GND
  BU8  GND            VSS<551>  @BASEBOARD_FAB2_LIB.BASEBOARD_FAB2(SCH_1):GND
  BV5  GND            VSS<550>  @BASEBOARD_FAB2_LIB.BASEBOARD_FAB2(SCH_1):GND
  BU10  GND            VSS<549>  @BASEBOARD_FAB2_LIB.BASEBOARD_FAB2(SCH_1):GND
  BV17  GND            VSS<548>  @BASEBOARD_FAB2_LIB.BASEBOARD_FAB2(SCH_1):GND
  BV25  GND            VSS<547>  @BASEBOARD_FAB2_LIB.BASEBOARD_FAB2(SCH_1):GND
  BW6  GND            VSS<546>  @BASEBOARD_FAB2_LIB.BASEBOARD_FAB2(SCH_1):GND
  P55  GND            VSS<545>  @BASEBOARD_FAB2_LIB.BASEBOARD_FAB2(SCH_1):GND
  BW12  GND            VSS<544>  @BASEBOARD_FAB2_LIB.BASEBOARD_FAB2(SCH_1):GND
  BW14  GND            VSS<543>  @BASEBOARD_FAB2_LIB.BASEBOARD_FAB2(SCH_1):GND
  BW16  GND            VSS<542>  @BASEBOARD_FAB2_LIB.BASEBOARD_FAB2(SCH_1):GND
  BW18  GND            VSS<541>  @BASEBOARD_FAB2_LIB.BASEBOARD_FAB2(SCH_1):GND
  BW26  GND            VSS<540>  @BASEBOARD_FAB2_LIB.BASEBOARD_FAB2(SCH_1):GND
  BW72  GND            VSS<539>  @BASEBOARD_FAB2_LIB.BASEBOARD_FAB2(SCH_1):GND
  BW74  GND            VSS<538>  @BASEBOARD_FAB2_LIB.BASEBOARD_FAB2(SCH_1):GND
  BW76  GND            VSS<537>  @BASEBOARD_FAB2_LIB.BASEBOARD_FAB2(SCH_1):GND
  BW78  GND            VSS<536>  @BASEBOARD_FAB2_LIB.BASEBOARD_FAB2(SCH_1):GND
  BW80  GND            VSS<535>  @BASEBOARD_FAB2_LIB.BASEBOARD_FAB2(SCH_1):GND
  BW82  GND            VSS<534>  @BASEBOARD_FAB2_LIB.BASEBOARD_FAB2(SCH_1):GND
  BY11  GND            VSS<533>  @BASEBOARD_FAB2_LIB.BASEBOARD_FAB2(SCH_1):GND
  BY13  GND            VSS<532>  @BASEBOARD_FAB2_LIB.BASEBOARD_FAB2(SCH_1):GND
  BY23  GND            VSS<531>  @BASEBOARD_FAB2_LIB.BASEBOARD_FAB2(SCH_1):GND
  BY63  GND            VSS<530>  @BASEBOARD_FAB2_LIB.BASEBOARD_FAB2(SCH_1):GND
  BY65  GND            VSS<529>  @BASEBOARD_FAB2_LIB.BASEBOARD_FAB2(SCH_1):GND
  BY67  GND            VSS<528>  @BASEBOARD_FAB2_LIB.BASEBOARD_FAB2(SCH_1):GND
  BY69  GND            VSS<527>  @BASEBOARD_FAB2_LIB.BASEBOARD_FAB2(SCH_1):GND
  BY71  GND            VSS<526>  @BASEBOARD_FAB2_LIB.BASEBOARD_FAB2(SCH_1):GND
  CA2  GND            VSS<525>  @BASEBOARD_FAB2_LIB.BASEBOARD_FAB2(SCH_1):GND
  CA6  GND            VSS<524>  @BASEBOARD_FAB2_LIB.BASEBOARD_FAB2(SCH_1):GND
  CA8  GND            VSS<523>  @BASEBOARD_FAB2_LIB.BASEBOARD_FAB2(SCH_1):GND
  CA10  GND            VSS<522>  @BASEBOARD_FAB2_LIB.BASEBOARD_FAB2(SCH_1):GND
  CA14  GND            VSS<521>  @BASEBOARD_FAB2_LIB.BASEBOARD_FAB2(SCH_1):GND
  CA18  GND            VSS<520>  @BASEBOARD_FAB2_LIB.BASEBOARD_FAB2(SCH_1):GND
  CA26  GND            VSS<519>  @BASEBOARD_FAB2_LIB.BASEBOARD_FAB2(SCH_1):GND
  CA64  GND            VSS<518>  @BASEBOARD_FAB2_LIB.BASEBOARD_FAB2(SCH_1):GND
  CA66  GND            VSS<517>  @BASEBOARD_FAB2_LIB.BASEBOARD_FAB2(SCH_1):GND
  CA68  GND            VSS<516>  @BASEBOARD_FAB2_LIB.BASEBOARD_FAB2(SCH_1):GND
  CA70  GND            VSS<515>  @BASEBOARD_FAB2_LIB.BASEBOARD_FAB2(SCH_1):GND
  CB7  GND            VSS<514>  @BASEBOARD_FAB2_LIB.BASEBOARD_FAB2(SCH_1):GND
  CB9  GND            VSS<513>  @BASEBOARD_FAB2_LIB.BASEBOARD_FAB2(SCH_1):GND
  CB27  GND            VSS<512>  @BASEBOARD_FAB2_LIB.BASEBOARD_FAB2(SCH_1):GND
  CB63  GND            VSS<511>  @BASEBOARD_FAB2_LIB.BASEBOARD_FAB2(SCH_1):GND
  CB71  GND            VSS<510>  @BASEBOARD_FAB2_LIB.BASEBOARD_FAB2(SCH_1):GND
  CC4  GND            VSS<509>  @BASEBOARD_FAB2_LIB.BASEBOARD_FAB2(SCH_1):GND
  CC16  GND            VSS<508>  @BASEBOARD_FAB2_LIB.BASEBOARD_FAB2(SCH_1):GND
  CC18  GND            VSS<507>  @BASEBOARD_FAB2_LIB.BASEBOARD_FAB2(SCH_1):GND
  CC24  GND            VSS<506>  @BASEBOARD_FAB2_LIB.BASEBOARD_FAB2(SCH_1):GND
  CC64  GND            VSS<505>  @BASEBOARD_FAB2_LIB.BASEBOARD_FAB2(SCH_1):GND
  CC72  GND            VSS<504>  @BASEBOARD_FAB2_LIB.BASEBOARD_FAB2(SCH_1):GND
  CC74  GND            VSS<503>  @BASEBOARD_FAB2_LIB.BASEBOARD_FAB2(SCH_1):GND
  CC76  GND            VSS<502>  @BASEBOARD_FAB2_LIB.BASEBOARD_FAB2(SCH_1):GND
  CC78  GND            VSS<501>  @BASEBOARD_FAB2_LIB.BASEBOARD_FAB2(SCH_1):GND
  CC80  GND            VSS<500>  @BASEBOARD_FAB2_LIB.BASEBOARD_FAB2(SCH_1):GND
  CC82  GND            VSS<499>  @BASEBOARD_FAB2_LIB.BASEBOARD_FAB2(SCH_1):GND
  CD5  GND            VSS<498>  @BASEBOARD_FAB2_LIB.BASEBOARD_FAB2(SCH_1):GND
  CD13  GND            VSS<497>  @BASEBOARD_FAB2_LIB.BASEBOARD_FAB2(SCH_1):GND
  CD63  GND            VSS<496>  @BASEBOARD_FAB2_LIB.BASEBOARD_FAB2(SCH_1):GND
  CD73  GND            VSS<495>  @BASEBOARD_FAB2_LIB.BASEBOARD_FAB2(SCH_1):GND
  CD75  GND            VSS<494>  @BASEBOARD_FAB2_LIB.BASEBOARD_FAB2(SCH_1):GND
  CD77  GND            VSS<493>  @BASEBOARD_FAB2_LIB.BASEBOARD_FAB2(SCH_1):GND
  CD79  GND            VSS<492>  @BASEBOARD_FAB2_LIB.BASEBOARD_FAB2(SCH_1):GND
  CD81  GND            VSS<491>  @BASEBOARD_FAB2_LIB.BASEBOARD_FAB2(SCH_1):GND
  CE10  GND            VSS<490>  @BASEBOARD_FAB2_LIB.BASEBOARD_FAB2(SCH_1):GND
  CE14  GND            VSS<489>  @BASEBOARD_FAB2_LIB.BASEBOARD_FAB2(SCH_1):GND
  CE20  GND            VSS<488>  @BASEBOARD_FAB2_LIB.BASEBOARD_FAB2(SCH_1):GND
  CE26  GND            VSS<487>  @BASEBOARD_FAB2_LIB.BASEBOARD_FAB2(SCH_1):GND
  CE62  GND            VSS<486>  @BASEBOARD_FAB2_LIB.BASEBOARD_FAB2(SCH_1):GND
  CE70  GND            VSS<485>  @BASEBOARD_FAB2_LIB.BASEBOARD_FAB2(SCH_1):GND
  CE82  GND            VSS<484>  @BASEBOARD_FAB2_LIB.BASEBOARD_FAB2(SCH_1):GND
  P53  GND            VSS<483>  @BASEBOARD_FAB2_LIB.BASEBOARD_FAB2(SCH_1):GND
  CF9  GND            VSS<482>  @BASEBOARD_FAB2_LIB.BASEBOARD_FAB2(SCH_1):GND
  CF63  GND            VSS<481>  @BASEBOARD_FAB2_LIB.BASEBOARD_FAB2(SCH_1):GND
  CF69  GND            VSS<480>  @BASEBOARD_FAB2_LIB.BASEBOARD_FAB2(SCH_1):GND
  CF71  GND            VSS<479>  @BASEBOARD_FAB2_LIB.BASEBOARD_FAB2(SCH_1):GND
  CF77  GND            VSS<478>  @BASEBOARD_FAB2_LIB.BASEBOARD_FAB2(SCH_1):GND
  CF83  GND            VSS<477>  @BASEBOARD_FAB2_LIB.BASEBOARD_FAB2(SCH_1):GND
  P51  GND            VSS<476>  @BASEBOARD_FAB2_LIB.BASEBOARD_FAB2(SCH_1):GND
  CG18  GND            VSS<475>  @BASEBOARD_FAB2_LIB.BASEBOARD_FAB2(SCH_1):GND
  CG22  GND            VSS<474>  @BASEBOARD_FAB2_LIB.BASEBOARD_FAB2(SCH_1):GND
  CG62  GND            VSS<473>  @BASEBOARD_FAB2_LIB.BASEBOARD_FAB2(SCH_1):GND
  CG68  GND            VSS<472>  @BASEBOARD_FAB2_LIB.BASEBOARD_FAB2(SCH_1):GND
  CG72  GND            VSS<471>  @BASEBOARD_FAB2_LIB.BASEBOARD_FAB2(SCH_1):GND
  CG80  GND            VSS<470>  @BASEBOARD_FAB2_LIB.BASEBOARD_FAB2(SCH_1):GND
  CH1  GND            VSS<469>  @BASEBOARD_FAB2_LIB.BASEBOARD_FAB2(SCH_1):GND
  CH3  GND            VSS<468>  @BASEBOARD_FAB2_LIB.BASEBOARD_FAB2(SCH_1):GND
  CH15  GND            VSS<467>  @BASEBOARD_FAB2_LIB.BASEBOARD_FAB2(SCH_1):GND
  CH19  GND            VSS<466>  @BASEBOARD_FAB2_LIB.BASEBOARD_FAB2(SCH_1):GND
  CH63  GND            VSS<465>  @BASEBOARD_FAB2_LIB.BASEBOARD_FAB2(SCH_1):GND
  CH67  GND            VSS<464>  @BASEBOARD_FAB2_LIB.BASEBOARD_FAB2(SCH_1):GND
  CH73  GND            VSS<463>  @BASEBOARD_FAB2_LIB.BASEBOARD_FAB2(SCH_1):GND
  CH79  GND            VSS<462>  @BASEBOARD_FAB2_LIB.BASEBOARD_FAB2(SCH_1):GND
  CH81  GND            VSS<461>  @BASEBOARD_FAB2_LIB.BASEBOARD_FAB2(SCH_1):GND
  CH83  GND            VSS<460>  @BASEBOARD_FAB2_LIB.BASEBOARD_FAB2(SCH_1):GND
  CJ2  GND            VSS<459>  @BASEBOARD_FAB2_LIB.BASEBOARD_FAB2(SCH_1):GND
  CJ6  GND            VSS<458>  @BASEBOARD_FAB2_LIB.BASEBOARD_FAB2(SCH_1):GND
  CJ8  GND            VSS<457>  @BASEBOARD_FAB2_LIB.BASEBOARD_FAB2(SCH_1):GND
  CJ10  GND            VSS<456>  @BASEBOARD_FAB2_LIB.BASEBOARD_FAB2(SCH_1):GND
  CJ12  GND            VSS<455>  @BASEBOARD_FAB2_LIB.BASEBOARD_FAB2(SCH_1):GND
  P49  GND            VSS<454>  @BASEBOARD_FAB2_LIB.BASEBOARD_FAB2(SCH_1):GND

SKX_EXT_B_BGA1  I23  U2D1   [SKX_EXT_B_BGA1-IC,TBD]
  AL76  GND            VSS<773>  @BASEBOARD_FAB2_LIB.BASEBOARD_FAB2(SCH_1):GND
  AL78  GND            VSS<772>  @BASEBOARD_FAB2_LIB.BASEBOARD_FAB2(SCH_1):GND
  AL80  GND            VSS<771>  @BASEBOARD_FAB2_LIB.BASEBOARD_FAB2(SCH_1):GND
  AL82  GND            VSS<770>  @BASEBOARD_FAB2_LIB.BASEBOARD_FAB2(SCH_1):GND
  AL86  GND            VSS<769>  @BASEBOARD_FAB2_LIB.BASEBOARD_FAB2(SCH_1):GND
  AM1  GND            VSS<768>  @BASEBOARD_FAB2_LIB.BASEBOARD_FAB2(SCH_1):GND
  AC50  GND            VSS<767>  @BASEBOARD_FAB2_LIB.BASEBOARD_FAB2(SCH_1):GND
  AM31  GND            VSS<766>  @BASEBOARD_FAB2_LIB.BASEBOARD_FAB2(SCH_1):GND
  AM57  GND            VSS<765>  @BASEBOARD_FAB2_LIB.BASEBOARD_FAB2(SCH_1):GND
  AM63  GND            VSS<764>  @BASEBOARD_FAB2_LIB.BASEBOARD_FAB2(SCH_1):GND
  AM69  GND            VSS<763>  @BASEBOARD_FAB2_LIB.BASEBOARD_FAB2(SCH_1):GND
  AM73  GND            VSS<762>  @BASEBOARD_FAB2_LIB.BASEBOARD_FAB2(SCH_1):GND
  AM79  GND            VSS<761>  @BASEBOARD_FAB2_LIB.BASEBOARD_FAB2(SCH_1):GND
  AM83  GND            VSS<760>  @BASEBOARD_FAB2_LIB.BASEBOARD_FAB2(SCH_1):GND
  AN2  GND            VSS<759>  @BASEBOARD_FAB2_LIB.BASEBOARD_FAB2(SCH_1):GND
  AN6  GND            VSS<758>  @BASEBOARD_FAB2_LIB.BASEBOARD_FAB2(SCH_1):GND
  AN28  GND            VSS<757>  @BASEBOARD_FAB2_LIB.BASEBOARD_FAB2(SCH_1):GND
  AN58  GND            VSS<756>  @BASEBOARD_FAB2_LIB.BASEBOARD_FAB2(SCH_1):GND
  AN78  GND            VSS<755>  @BASEBOARD_FAB2_LIB.BASEBOARD_FAB2(SCH_1):GND
  AP5  GND            VSS<754>  @BASEBOARD_FAB2_LIB.BASEBOARD_FAB2(SCH_1):GND
  AP9  GND            VSS<753>  @BASEBOARD_FAB2_LIB.BASEBOARD_FAB2(SCH_1):GND
  AP13  GND            VSS<752>  @BASEBOARD_FAB2_LIB.BASEBOARD_FAB2(SCH_1):GND
  AP19  GND            VSS<751>  @BASEBOARD_FAB2_LIB.BASEBOARD_FAB2(SCH_1):GND
  AP31  GND            VSS<750>  @BASEBOARD_FAB2_LIB.BASEBOARD_FAB2(SCH_1):GND
  AP59  GND            VSS<749>  @BASEBOARD_FAB2_LIB.BASEBOARD_FAB2(SCH_1):GND
  AP63  GND            VSS<748>  @BASEBOARD_FAB2_LIB.BASEBOARD_FAB2(SCH_1):GND
  AP65  GND            VSS<747>  @BASEBOARD_FAB2_LIB.BASEBOARD_FAB2(SCH_1):GND
  AP67  GND            VSS<746>  @BASEBOARD_FAB2_LIB.BASEBOARD_FAB2(SCH_1):GND
  AP69  GND            VSS<745>  @BASEBOARD_FAB2_LIB.BASEBOARD_FAB2(SCH_1):GND
  AP73  GND            VSS<744>  @BASEBOARD_FAB2_LIB.BASEBOARD_FAB2(SCH_1):GND
  AP75  GND            VSS<743>  @BASEBOARD_FAB2_LIB.BASEBOARD_FAB2(SCH_1):GND
  AP81  GND            VSS<742>  @BASEBOARD_FAB2_LIB.BASEBOARD_FAB2(SCH_1):GND
  AP83  GND            VSS<741>  @BASEBOARD_FAB2_LIB.BASEBOARD_FAB2(SCH_1):GND
  AP85  GND            VSS<740>  @BASEBOARD_FAB2_LIB.BASEBOARD_FAB2(SCH_1):GND
  AR10  GND            VSS<739>  @BASEBOARD_FAB2_LIB.BASEBOARD_FAB2(SCH_1):GND
  AR24  GND            VSS<738>  @BASEBOARD_FAB2_LIB.BASEBOARD_FAB2(SCH_1):GND
  AR30  GND            VSS<737>  @BASEBOARD_FAB2_LIB.BASEBOARD_FAB2(SCH_1):GND
  AR60  GND            VSS<736>  @BASEBOARD_FAB2_LIB.BASEBOARD_FAB2(SCH_1):GND
  AR72  GND            VSS<735>  @BASEBOARD_FAB2_LIB.BASEBOARD_FAB2(SCH_1):GND
  AR78  GND            VSS<734>  @BASEBOARD_FAB2_LIB.BASEBOARD_FAB2(SCH_1):GND
  AC48  GND            VSS<733>  @BASEBOARD_FAB2_LIB.BASEBOARD_FAB2(SCH_1):GND
  P63  GND            VSS<732>  @BASEBOARD_FAB2_LIB.BASEBOARD_FAB2(SCH_1):GND
  AT15  GND            VSS<731>  @BASEBOARD_FAB2_LIB.BASEBOARD_FAB2(SCH_1):GND
  AT17  GND            VSS<730>  @BASEBOARD_FAB2_LIB.BASEBOARD_FAB2(SCH_1):GND
  AT21  GND            VSS<729>  @BASEBOARD_FAB2_LIB.BASEBOARD_FAB2(SCH_1):GND
  AT27  GND            VSS<728>  @BASEBOARD_FAB2_LIB.BASEBOARD_FAB2(SCH_1):GND
  AT61  GND            VSS<727>  @BASEBOARD_FAB2_LIB.BASEBOARD_FAB2(SCH_1):GND
  AT63  GND            VSS<726>  @BASEBOARD_FAB2_LIB.BASEBOARD_FAB2(SCH_1):GND
  AT69  GND            VSS<725>  @BASEBOARD_FAB2_LIB.BASEBOARD_FAB2(SCH_1):GND
  AT73  GND            VSS<724>  @BASEBOARD_FAB2_LIB.BASEBOARD_FAB2(SCH_1):GND
  AT77  GND            VSS<723>  @BASEBOARD_FAB2_LIB.BASEBOARD_FAB2(SCH_1):GND
  AT83  GND            VSS<722>  @BASEBOARD_FAB2_LIB.BASEBOARD_FAB2(SCH_1):GND
  AT85  GND            VSS<721>  @BASEBOARD_FAB2_LIB.BASEBOARD_FAB2(SCH_1):GND
  AU2  GND            VSS<720>  @BASEBOARD_FAB2_LIB.BASEBOARD_FAB2(SCH_1):GND
  AU6  GND            VSS<719>  @BASEBOARD_FAB2_LIB.BASEBOARD_FAB2(SCH_1):GND
  AU26  GND            VSS<718>  @BASEBOARD_FAB2_LIB.BASEBOARD_FAB2(SCH_1):GND
  AU28  GND            VSS<717>  @BASEBOARD_FAB2_LIB.BASEBOARD_FAB2(SCH_1):GND
  AU62  GND            VSS<716>  @BASEBOARD_FAB2_LIB.BASEBOARD_FAB2(SCH_1):GND
  AU64  GND            VSS<715>  @BASEBOARD_FAB2_LIB.BASEBOARD_FAB2(SCH_1):GND
  AU68  GND            VSS<714>  @BASEBOARD_FAB2_LIB.BASEBOARD_FAB2(SCH_1):GND
  AU74  GND            VSS<713>  @BASEBOARD_FAB2_LIB.BASEBOARD_FAB2(SCH_1):GND
  AU76  GND            VSS<712>  @BASEBOARD_FAB2_LIB.BASEBOARD_FAB2(SCH_1):GND
  AU78  GND            VSS<711>  @BASEBOARD_FAB2_LIB.BASEBOARD_FAB2(SCH_1):GND
  AU80  GND            VSS<710>  @BASEBOARD_FAB2_LIB.BASEBOARD_FAB2(SCH_1):GND
  AU84  GND            VSS<709>  @BASEBOARD_FAB2_LIB.BASEBOARD_FAB2(SCH_1):GND
  AU86  GND            VSS<708>  @BASEBOARD_FAB2_LIB.BASEBOARD_FAB2(SCH_1):GND
  AV1  GND            VSS<707>  @BASEBOARD_FAB2_LIB.BASEBOARD_FAB2(SCH_1):GND
  AV3  GND            VSS<706>  @BASEBOARD_FAB2_LIB.BASEBOARD_FAB2(SCH_1):GND
  AV7  GND            VSS<705>  @BASEBOARD_FAB2_LIB.BASEBOARD_FAB2(SCH_1):GND
  AV11  GND            VSS<704>  @BASEBOARD_FAB2_LIB.BASEBOARD_FAB2(SCH_1):GND
  AV13  GND            VSS<703>  @BASEBOARD_FAB2_LIB.BASEBOARD_FAB2(SCH_1):GND
  AV19  GND            VSS<702>  @BASEBOARD_FAB2_LIB.BASEBOARD_FAB2(SCH_1):GND
  AV23  GND            VSS<701>  @BASEBOARD_FAB2_LIB.BASEBOARD_FAB2(SCH_1):GND
  AV25  GND            VSS<700>  @BASEBOARD_FAB2_LIB.BASEBOARD_FAB2(SCH_1):GND
  AV63  GND            VSS<699>  @BASEBOARD_FAB2_LIB.BASEBOARD_FAB2(SCH_1):GND
  AV65  GND            VSS<698>  @BASEBOARD_FAB2_LIB.BASEBOARD_FAB2(SCH_1):GND
  AV67  GND            VSS<697>  @BASEBOARD_FAB2_LIB.BASEBOARD_FAB2(SCH_1):GND
  AV75  GND            VSS<696>  @BASEBOARD_FAB2_LIB.BASEBOARD_FAB2(SCH_1):GND
  AV83  GND            VSS<695>  @BASEBOARD_FAB2_LIB.BASEBOARD_FAB2(SCH_1):GND
  AW2  GND            VSS<694>  @BASEBOARD_FAB2_LIB.BASEBOARD_FAB2(SCH_1):GND
  AW10  GND            VSS<693>  @BASEBOARD_FAB2_LIB.BASEBOARD_FAB2(SCH_1):GND
  AW62  GND            VSS<692>  @BASEBOARD_FAB2_LIB.BASEBOARD_FAB2(SCH_1):GND
  AW66  GND            VSS<691>  @BASEBOARD_FAB2_LIB.BASEBOARD_FAB2(SCH_1):GND
  AW68  GND            VSS<690>  @BASEBOARD_FAB2_LIB.BASEBOARD_FAB2(SCH_1):GND
  AW70  GND            VSS<689>  @BASEBOARD_FAB2_LIB.BASEBOARD_FAB2(SCH_1):GND
  AW72  GND            VSS<688>  @BASEBOARD_FAB2_LIB.BASEBOARD_FAB2(SCH_1):GND
  AW74  GND            VSS<687>  @BASEBOARD_FAB2_LIB.BASEBOARD_FAB2(SCH_1):GND
  AW78  GND            VSS<686>  @BASEBOARD_FAB2_LIB.BASEBOARD_FAB2(SCH_1):GND
  AW82  GND            VSS<685>  @BASEBOARD_FAB2_LIB.BASEBOARD_FAB2(SCH_1):GND
  AW84  GND            VSS<684>  @BASEBOARD_FAB2_LIB.BASEBOARD_FAB2(SCH_1):GND
  AY5  GND            VSS<683>  @BASEBOARD_FAB2_LIB.BASEBOARD_FAB2(SCH_1):GND
  AY15  GND            VSS<682>  @BASEBOARD_FAB2_LIB.BASEBOARD_FAB2(SCH_1):GND
  AY17  GND            VSS<681>  @BASEBOARD_FAB2_LIB.BASEBOARD_FAB2(SCH_1):GND
  AY21  GND            VSS<680>  @BASEBOARD_FAB2_LIB.BASEBOARD_FAB2(SCH_1):GND
  AY23  GND            VSS<679>  @BASEBOARD_FAB2_LIB.BASEBOARD_FAB2(SCH_1):GND
  AY25  GND            VSS<678>  @BASEBOARD_FAB2_LIB.BASEBOARD_FAB2(SCH_1):GND
  AY63  GND            VSS<677>  @BASEBOARD_FAB2_LIB.BASEBOARD_FAB2(SCH_1):GND
  AY79  GND            VSS<676>  @BASEBOARD_FAB2_LIB.BASEBOARD_FAB2(SCH_1):GND
  AY81  GND            VSS<675>  @BASEBOARD_FAB2_LIB.BASEBOARD_FAB2(SCH_1):GND
  BA2  GND            VSS<674>  @BASEBOARD_FAB2_LIB.BASEBOARD_FAB2(SCH_1):GND
  BA6  GND            VSS<673>  @BASEBOARD_FAB2_LIB.BASEBOARD_FAB2(SCH_1):GND
  BA12  GND            VSS<672>  @BASEBOARD_FAB2_LIB.BASEBOARD_FAB2(SCH_1):GND
  BA62  GND            VSS<671>  @BASEBOARD_FAB2_LIB.BASEBOARD_FAB2(SCH_1):GND
  BA68  GND            VSS<670>  @BASEBOARD_FAB2_LIB.BASEBOARD_FAB2(SCH_1):GND
  BA74  GND            VSS<669>  @BASEBOARD_FAB2_LIB.BASEBOARD_FAB2(SCH_1):GND
  BA80  GND            VSS<668>  @BASEBOARD_FAB2_LIB.BASEBOARD_FAB2(SCH_1):GND
  BA84  GND            VSS<667>  @BASEBOARD_FAB2_LIB.BASEBOARD_FAB2(SCH_1):GND
  BB19  GND            VSS<666>  @BASEBOARD_FAB2_LIB.BASEBOARD_FAB2(SCH_1):GND
  BB23  GND            VSS<665>  @BASEBOARD_FAB2_LIB.BASEBOARD_FAB2(SCH_1):GND
  BB63  GND            VSS<664>  @BASEBOARD_FAB2_LIB.BASEBOARD_FAB2(SCH_1):GND
  BB69  GND            VSS<663>  @BASEBOARD_FAB2_LIB.BASEBOARD_FAB2(SCH_1):GND
  BB73  GND            VSS<662>  @BASEBOARD_FAB2_LIB.BASEBOARD_FAB2(SCH_1):GND
  BB75  GND            VSS<661>  @BASEBOARD_FAB2_LIB.BASEBOARD_FAB2(SCH_1):GND
  BB77  GND            VSS<660>  @BASEBOARD_FAB2_LIB.BASEBOARD_FAB2(SCH_1):GND
  BB79  GND            VSS<659>  @BASEBOARD_FAB2_LIB.BASEBOARD_FAB2(SCH_1):GND
  BB81  GND            VSS<658>  @BASEBOARD_FAB2_LIB.BASEBOARD_FAB2(SCH_1):GND
  BB83  GND            VSS<657>  @BASEBOARD_FAB2_LIB.BASEBOARD_FAB2(SCH_1):GND
  BC4  GND            VSS<656>  @BASEBOARD_FAB2_LIB.BASEBOARD_FAB2(SCH_1):GND
  BC8  GND            VSS<655>  @BASEBOARD_FAB2_LIB.BASEBOARD_FAB2(SCH_1):GND
  BC12  GND            VSS<654>  @BASEBOARD_FAB2_LIB.BASEBOARD_FAB2(SCH_1):GND
  BC16  GND            VSS<653>  @BASEBOARD_FAB2_LIB.BASEBOARD_FAB2(SCH_1):GND
  BC70  GND            VSS<652>  @BASEBOARD_FAB2_LIB.BASEBOARD_FAB2(SCH_1):GND
  BC72  GND            VSS<651>  @BASEBOARD_FAB2_LIB.BASEBOARD_FAB2(SCH_1):GND
  BC74  GND            VSS<650>  @BASEBOARD_FAB2_LIB.BASEBOARD_FAB2(SCH_1):GND
  BC76  GND            VSS<649>  @BASEBOARD_FAB2_LIB.BASEBOARD_FAB2(SCH_1):GND
  BC78  GND            VSS<648>  @BASEBOARD_FAB2_LIB.BASEBOARD_FAB2(SCH_1):GND
  BC80  GND            VSS<647>  @BASEBOARD_FAB2_LIB.BASEBOARD_FAB2(SCH_1):GND
  BC82  GND            VSS<646>  @BASEBOARD_FAB2_LIB.BASEBOARD_FAB2(SCH_1):GND
  BD5  GND            VSS<645>  @BASEBOARD_FAB2_LIB.BASEBOARD_FAB2(SCH_1):GND
  BD11  GND            VSS<644>  @BASEBOARD_FAB2_LIB.BASEBOARD_FAB2(SCH_1):GND
  BD15  GND            VSS<643>  @BASEBOARD_FAB2_LIB.BASEBOARD_FAB2(SCH_1):GND
  BD21  GND            VSS<642>  @BASEBOARD_FAB2_LIB.BASEBOARD_FAB2(SCH_1):GND
  BD27  GND            VSS<641>  @BASEBOARD_FAB2_LIB.BASEBOARD_FAB2(SCH_1):GND
  BD63  GND            VSS<640>  @BASEBOARD_FAB2_LIB.BASEBOARD_FAB2(SCH_1):GND
  BD71  GND            VSS<639>  @BASEBOARD_FAB2_LIB.BASEBOARD_FAB2(SCH_1):GND
  BE4  GND            VSS<638>  @BASEBOARD_FAB2_LIB.BASEBOARD_FAB2(SCH_1):GND
  BE6  GND            VSS<637>  @BASEBOARD_FAB2_LIB.BASEBOARD_FAB2(SCH_1):GND
  BE8  GND            VSS<636>  @BASEBOARD_FAB2_LIB.BASEBOARD_FAB2(SCH_1):GND
  BE10  GND            VSS<635>  @BASEBOARD_FAB2_LIB.BASEBOARD_FAB2(SCH_1):GND
  BE26  GND            VSS<634>  @BASEBOARD_FAB2_LIB.BASEBOARD_FAB2(SCH_1):GND
  BE64  GND            VSS<633>  @BASEBOARD_FAB2_LIB.BASEBOARD_FAB2(SCH_1):GND
  BE66  GND            VSS<632>  @BASEBOARD_FAB2_LIB.BASEBOARD_FAB2(SCH_1):GND
  BE68  GND            VSS<631>  @BASEBOARD_FAB2_LIB.BASEBOARD_FAB2(SCH_1):GND
  BE70  GND            VSS<630>  @BASEBOARD_FAB2_LIB.BASEBOARD_FAB2(SCH_1):GND
  BF9  GND            VSS<629>  @BASEBOARD_FAB2_LIB.BASEBOARD_FAB2(SCH_1):GND
  BF15  GND            VSS<628>  @BASEBOARD_FAB2_LIB.BASEBOARD_FAB2(SCH_1):GND
  BF17  GND            VSS<627>  @BASEBOARD_FAB2_LIB.BASEBOARD_FAB2(SCH_1):GND
  BF19  GND            VSS<626>  @BASEBOARD_FAB2_LIB.BASEBOARD_FAB2(SCH_1):GND
  BF25  GND            VSS<625>  @BASEBOARD_FAB2_LIB.BASEBOARD_FAB2(SCH_1):GND
  BF63  GND            VSS<624>  @BASEBOARD_FAB2_LIB.BASEBOARD_FAB2(SCH_1):GND
  BF65  GND            VSS<623>  @BASEBOARD_FAB2_LIB.BASEBOARD_FAB2(SCH_1):GND
  BF67  GND            VSS<622>  @BASEBOARD_FAB2_LIB.BASEBOARD_FAB2(SCH_1):GND
  BF69  GND            VSS<621>  @BASEBOARD_FAB2_LIB.BASEBOARD_FAB2(SCH_1):GND
  BF71  GND            VSS<620>  @BASEBOARD_FAB2_LIB.BASEBOARD_FAB2(SCH_1):GND
  BG6  GND            VSS<619>  @BASEBOARD_FAB2_LIB.BASEBOARD_FAB2(SCH_1):GND
  BG8  GND            VSS<618>  @BASEBOARD_FAB2_LIB.BASEBOARD_FAB2(SCH_1):GND
  BG10  GND            VSS<617>  @BASEBOARD_FAB2_LIB.BASEBOARD_FAB2(SCH_1):GND
  BG22  GND            VSS<616>  @BASEBOARD_FAB2_LIB.BASEBOARD_FAB2(SCH_1):GND
  BG24  GND            VSS<615>  @BASEBOARD_FAB2_LIB.BASEBOARD_FAB2(SCH_1):GND
  BG72  GND            VSS<614>  @BASEBOARD_FAB2_LIB.BASEBOARD_FAB2(SCH_1):GND

SKX_EXT_B_BGA1  I22  U2D1   [SKX_EXT_B_BGA1-IC,TBD]
  AA18  GND            VSS<933>  @BASEBOARD_FAB2_LIB.BASEBOARD_FAB2(SCH_1):GND
  AA22  GND            VSS<932>  @BASEBOARD_FAB2_LIB.BASEBOARD_FAB2(SCH_1):GND
  AA24  GND            VSS<931>  @BASEBOARD_FAB2_LIB.BASEBOARD_FAB2(SCH_1):GND
  AA30  GND            VSS<930>  @BASEBOARD_FAB2_LIB.BASEBOARD_FAB2(SCH_1):GND
  AA36  GND            VSS<929>  @BASEBOARD_FAB2_LIB.BASEBOARD_FAB2(SCH_1):GND
  AA42  GND            VSS<928>  @BASEBOARD_FAB2_LIB.BASEBOARD_FAB2(SCH_1):GND
  AA64  GND            VSS<927>  @BASEBOARD_FAB2_LIB.BASEBOARD_FAB2(SCH_1):GND
  AA66  GND            VSS<926>  @BASEBOARD_FAB2_LIB.BASEBOARD_FAB2(SCH_1):GND
  AA68  GND            VSS<925>  @BASEBOARD_FAB2_LIB.BASEBOARD_FAB2(SCH_1):GND
  AA76  GND            VSS<924>  @BASEBOARD_FAB2_LIB.BASEBOARD_FAB2(SCH_1):GND
  AA78  GND            VSS<923>  @BASEBOARD_FAB2_LIB.BASEBOARD_FAB2(SCH_1):GND
  AA80  GND            VSS<922>  @BASEBOARD_FAB2_LIB.BASEBOARD_FAB2(SCH_1):GND
  AA82  GND            VSS<921>  @BASEBOARD_FAB2_LIB.BASEBOARD_FAB2(SCH_1):GND
  AB1  GND            VSS<920>  @BASEBOARD_FAB2_LIB.BASEBOARD_FAB2(SCH_1):GND
  AB5  GND            VSS<919>  @BASEBOARD_FAB2_LIB.BASEBOARD_FAB2(SCH_1):GND
  AB11  GND            VSS<918>  @BASEBOARD_FAB2_LIB.BASEBOARD_FAB2(SCH_1):GND
  AB21  GND            VSS<917>  @BASEBOARD_FAB2_LIB.BASEBOARD_FAB2(SCH_1):GND
  AB23  GND            VSS<916>  @BASEBOARD_FAB2_LIB.BASEBOARD_FAB2(SCH_1):GND
  AB25  GND            VSS<915>  @BASEBOARD_FAB2_LIB.BASEBOARD_FAB2(SCH_1):GND
  AB29  GND            VSS<914>  @BASEBOARD_FAB2_LIB.BASEBOARD_FAB2(SCH_1):GND
  AB31  GND            VSS<913>  @BASEBOARD_FAB2_LIB.BASEBOARD_FAB2(SCH_1):GND
  AB35  GND            VSS<912>  @BASEBOARD_FAB2_LIB.BASEBOARD_FAB2(SCH_1):GND
  AB37  GND            VSS<911>  @BASEBOARD_FAB2_LIB.BASEBOARD_FAB2(SCH_1):GND
  AB41  GND            VSS<910>  @BASEBOARD_FAB2_LIB.BASEBOARD_FAB2(SCH_1):GND
  AB65  GND            VSS<909>  @BASEBOARD_FAB2_LIB.BASEBOARD_FAB2(SCH_1):GND
  AB69  GND            VSS<908>  @BASEBOARD_FAB2_LIB.BASEBOARD_FAB2(SCH_1):GND
  AB73  GND            VSS<907>  @BASEBOARD_FAB2_LIB.BASEBOARD_FAB2(SCH_1):GND
  AB79  GND            VSS<906>  @BASEBOARD_FAB2_LIB.BASEBOARD_FAB2(SCH_1):GND
  AB83  GND            VSS<905>  @BASEBOARD_FAB2_LIB.BASEBOARD_FAB2(SCH_1):GND
  AB85  GND            VSS<904>  @BASEBOARD_FAB2_LIB.BASEBOARD_FAB2(SCH_1):GND
  AC18  GND            VSS<903>  @BASEBOARD_FAB2_LIB.BASEBOARD_FAB2(SCH_1):GND
  AC22  GND            VSS<902>  @BASEBOARD_FAB2_LIB.BASEBOARD_FAB2(SCH_1):GND
  AC26  GND            VSS<901>  @BASEBOARD_FAB2_LIB.BASEBOARD_FAB2(SCH_1):GND
  AC28  GND            VSS<900>  @BASEBOARD_FAB2_LIB.BASEBOARD_FAB2(SCH_1):GND
  AC32  GND            VSS<899>  @BASEBOARD_FAB2_LIB.BASEBOARD_FAB2(SCH_1):GND
  AC34  GND            VSS<898>  @BASEBOARD_FAB2_LIB.BASEBOARD_FAB2(SCH_1):GND
  AC38  GND            VSS<897>  @BASEBOARD_FAB2_LIB.BASEBOARD_FAB2(SCH_1):GND
  AC40  GND            VSS<896>  @BASEBOARD_FAB2_LIB.BASEBOARD_FAB2(SCH_1):GND
  AC64  GND            VSS<895>  @BASEBOARD_FAB2_LIB.BASEBOARD_FAB2(SCH_1):GND
  AC70  GND            VSS<894>  @BASEBOARD_FAB2_LIB.BASEBOARD_FAB2(SCH_1):GND
  AC72  GND            VSS<893>  @BASEBOARD_FAB2_LIB.BASEBOARD_FAB2(SCH_1):GND
  AC78  GND            VSS<892>  @BASEBOARD_FAB2_LIB.BASEBOARD_FAB2(SCH_1):GND
  AC84  GND            VSS<891>  @BASEBOARD_FAB2_LIB.BASEBOARD_FAB2(SCH_1):GND
  AC86  GND            VSS<890>  @BASEBOARD_FAB2_LIB.BASEBOARD_FAB2(SCH_1):GND
  AD3  GND            VSS<889>  @BASEBOARD_FAB2_LIB.BASEBOARD_FAB2(SCH_1):GND
  AD7  GND            VSS<888>  @BASEBOARD_FAB2_LIB.BASEBOARD_FAB2(SCH_1):GND
  AD9  GND            VSS<887>  @BASEBOARD_FAB2_LIB.BASEBOARD_FAB2(SCH_1):GND
  AD11  GND            VSS<886>  @BASEBOARD_FAB2_LIB.BASEBOARD_FAB2(SCH_1):GND
  AD13  GND            VSS<885>  @BASEBOARD_FAB2_LIB.BASEBOARD_FAB2(SCH_1):GND
  AD15  GND            VSS<884>  @BASEBOARD_FAB2_LIB.BASEBOARD_FAB2(SCH_1):GND
  AD19  GND            VSS<883>  @BASEBOARD_FAB2_LIB.BASEBOARD_FAB2(SCH_1):GND
  AD21  GND            VSS<882>  @BASEBOARD_FAB2_LIB.BASEBOARD_FAB2(SCH_1):GND
  AD27  GND            VSS<881>  @BASEBOARD_FAB2_LIB.BASEBOARD_FAB2(SCH_1):GND
  AD33  GND            VSS<880>  @BASEBOARD_FAB2_LIB.BASEBOARD_FAB2(SCH_1):GND
  AD39  GND            VSS<879>  @BASEBOARD_FAB2_LIB.BASEBOARD_FAB2(SCH_1):GND
  AD43  GND            VSS<878>  @BASEBOARD_FAB2_LIB.BASEBOARD_FAB2(SCH_1):GND
  AD71  GND            VSS<877>  @BASEBOARD_FAB2_LIB.BASEBOARD_FAB2(SCH_1):GND
  AD73  GND            VSS<876>  @BASEBOARD_FAB2_LIB.BASEBOARD_FAB2(SCH_1):GND
  AD75  GND            VSS<875>  @BASEBOARD_FAB2_LIB.BASEBOARD_FAB2(SCH_1):GND
  AD81  GND            VSS<874>  @BASEBOARD_FAB2_LIB.BASEBOARD_FAB2(SCH_1):GND
  AD83  GND            VSS<873>  @BASEBOARD_FAB2_LIB.BASEBOARD_FAB2(SCH_1):GND
  AD85  GND            VSS<872>  @BASEBOARD_FAB2_LIB.BASEBOARD_FAB2(SCH_1):GND
  AE4  GND            VSS<871>  @BASEBOARD_FAB2_LIB.BASEBOARD_FAB2(SCH_1):GND
  AE8  GND            VSS<870>  @BASEBOARD_FAB2_LIB.BASEBOARD_FAB2(SCH_1):GND
  AC54  GND            VSS<869>  @BASEBOARD_FAB2_LIB.BASEBOARD_FAB2(SCH_1):GND
  AE16  GND            VSS<868>  @BASEBOARD_FAB2_LIB.BASEBOARD_FAB2(SCH_1):GND
  AE38  GND            VSS<867>  @BASEBOARD_FAB2_LIB.BASEBOARD_FAB2(SCH_1):GND
  AE40  GND            VSS<866>  @BASEBOARD_FAB2_LIB.BASEBOARD_FAB2(SCH_1):GND
  AE42  GND            VSS<865>  @BASEBOARD_FAB2_LIB.BASEBOARD_FAB2(SCH_1):GND
  AE64  GND            VSS<864>  @BASEBOARD_FAB2_LIB.BASEBOARD_FAB2(SCH_1):GND
  AE66  GND            VSS<863>  @BASEBOARD_FAB2_LIB.BASEBOARD_FAB2(SCH_1):GND
  AE68  GND            VSS<862>  @BASEBOARD_FAB2_LIB.BASEBOARD_FAB2(SCH_1):GND
  AE70  GND            VSS<861>  @BASEBOARD_FAB2_LIB.BASEBOARD_FAB2(SCH_1):GND
  AE78  GND            VSS<860>  @BASEBOARD_FAB2_LIB.BASEBOARD_FAB2(SCH_1):GND
  AF1  GND            VSS<859>  @BASEBOARD_FAB2_LIB.BASEBOARD_FAB2(SCH_1):GND
  AC52  GND            VSS<858>  @BASEBOARD_FAB2_LIB.BASEBOARD_FAB2(SCH_1):GND
  AF9  GND            VSS<857>  @BASEBOARD_FAB2_LIB.BASEBOARD_FAB2(SCH_1):GND
  AF21  GND            VSS<856>  @BASEBOARD_FAB2_LIB.BASEBOARD_FAB2(SCH_1):GND
  AF23  GND            VSS<855>  @BASEBOARD_FAB2_LIB.BASEBOARD_FAB2(SCH_1):GND
  AF25  GND            VSS<854>  @BASEBOARD_FAB2_LIB.BASEBOARD_FAB2(SCH_1):GND
  AF27  GND            VSS<853>  @BASEBOARD_FAB2_LIB.BASEBOARD_FAB2(SCH_1):GND
  AF29  GND            VSS<852>  @BASEBOARD_FAB2_LIB.BASEBOARD_FAB2(SCH_1):GND
  AF31  GND            VSS<851>  @BASEBOARD_FAB2_LIB.BASEBOARD_FAB2(SCH_1):GND
  AF33  GND            VSS<850>  @BASEBOARD_FAB2_LIB.BASEBOARD_FAB2(SCH_1):GND
  AF37  GND            VSS<849>  @BASEBOARD_FAB2_LIB.BASEBOARD_FAB2(SCH_1):GND
  AF39  GND            VSS<848>  @BASEBOARD_FAB2_LIB.BASEBOARD_FAB2(SCH_1):GND
  AF41  GND            VSS<847>  @BASEBOARD_FAB2_LIB.BASEBOARD_FAB2(SCH_1):GND
  AF73  GND            VSS<846>  @BASEBOARD_FAB2_LIB.BASEBOARD_FAB2(SCH_1):GND
  AF77  GND            VSS<845>  @BASEBOARD_FAB2_LIB.BASEBOARD_FAB2(SCH_1):GND
  AF83  GND            VSS<844>  @BASEBOARD_FAB2_LIB.BASEBOARD_FAB2(SCH_1):GND
  AF85  GND            VSS<843>  @BASEBOARD_FAB2_LIB.BASEBOARD_FAB2(SCH_1):GND
  AG12  GND            VSS<842>  @BASEBOARD_FAB2_LIB.BASEBOARD_FAB2(SCH_1):GND
  AG14  GND            VSS<841>  @BASEBOARD_FAB2_LIB.BASEBOARD_FAB2(SCH_1):GND
  AG18  GND            VSS<840>  @BASEBOARD_FAB2_LIB.BASEBOARD_FAB2(SCH_1):GND
  AG36  GND            VSS<839>  @BASEBOARD_FAB2_LIB.BASEBOARD_FAB2(SCH_1):GND
  AG64  GND            VSS<838>  @BASEBOARD_FAB2_LIB.BASEBOARD_FAB2(SCH_1):GND
  AG70  GND            VSS<837>  @BASEBOARD_FAB2_LIB.BASEBOARD_FAB2(SCH_1):GND
  AG74  GND            VSS<836>  @BASEBOARD_FAB2_LIB.BASEBOARD_FAB2(SCH_1):GND
  AG76  GND            VSS<835>  @BASEBOARD_FAB2_LIB.BASEBOARD_FAB2(SCH_1):GND
  AG78  GND            VSS<834>  @BASEBOARD_FAB2_LIB.BASEBOARD_FAB2(SCH_1):GND
  AG80  GND            VSS<833>  @BASEBOARD_FAB2_LIB.BASEBOARD_FAB2(SCH_1):GND
  AH1  GND            VSS<832>  @BASEBOARD_FAB2_LIB.BASEBOARD_FAB2(SCH_1):GND
  AH5  GND            VSS<831>  @BASEBOARD_FAB2_LIB.BASEBOARD_FAB2(SCH_1):GND
  AH21  GND            VSS<830>  @BASEBOARD_FAB2_LIB.BASEBOARD_FAB2(SCH_1):GND
  AH27  GND            VSS<829>  @BASEBOARD_FAB2_LIB.BASEBOARD_FAB2(SCH_1):GND
  AH33  GND            VSS<828>  @BASEBOARD_FAB2_LIB.BASEBOARD_FAB2(SCH_1):GND
  AH35  GND            VSS<827>  @BASEBOARD_FAB2_LIB.BASEBOARD_FAB2(SCH_1):GND
  AH45  GND            VSS<826>  @BASEBOARD_FAB2_LIB.BASEBOARD_FAB2(SCH_1):GND
  AH47  GND            VSS<825>  @BASEBOARD_FAB2_LIB.BASEBOARD_FAB2(SCH_1):GND
  AH49  GND            VSS<824>  @BASEBOARD_FAB2_LIB.BASEBOARD_FAB2(SCH_1):GND
  AH51  GND            VSS<823>  @BASEBOARD_FAB2_LIB.BASEBOARD_FAB2(SCH_1):GND
  AH53  GND            VSS<822>  @BASEBOARD_FAB2_LIB.BASEBOARD_FAB2(SCH_1):GND
  AH59  GND            VSS<821>  @BASEBOARD_FAB2_LIB.BASEBOARD_FAB2(SCH_1):GND
  AH61  GND            VSS<820>  @BASEBOARD_FAB2_LIB.BASEBOARD_FAB2(SCH_1):GND
  AH65  GND            VSS<819>  @BASEBOARD_FAB2_LIB.BASEBOARD_FAB2(SCH_1):GND
  AH69  GND            VSS<818>  @BASEBOARD_FAB2_LIB.BASEBOARD_FAB2(SCH_1):GND
  AH75  GND            VSS<817>  @BASEBOARD_FAB2_LIB.BASEBOARD_FAB2(SCH_1):GND
  AH77  GND            VSS<816>  @BASEBOARD_FAB2_LIB.BASEBOARD_FAB2(SCH_1):GND
  AH83  GND            VSS<815>  @BASEBOARD_FAB2_LIB.BASEBOARD_FAB2(SCH_1):GND
  AJ8  GND            VSS<814>  @BASEBOARD_FAB2_LIB.BASEBOARD_FAB2(SCH_1):GND
  AJ22  GND            VSS<813>  @BASEBOARD_FAB2_LIB.BASEBOARD_FAB2(SCH_1):GND
  AJ26  GND            VSS<812>  @BASEBOARD_FAB2_LIB.BASEBOARD_FAB2(SCH_1):GND
  AJ28  GND            VSS<811>  @BASEBOARD_FAB2_LIB.BASEBOARD_FAB2(SCH_1):GND
  AJ32  GND            VSS<810>  @BASEBOARD_FAB2_LIB.BASEBOARD_FAB2(SCH_1):GND
  AJ34  GND            VSS<809>  @BASEBOARD_FAB2_LIB.BASEBOARD_FAB2(SCH_1):GND
  AJ46  GND            VSS<808>  @BASEBOARD_FAB2_LIB.BASEBOARD_FAB2(SCH_1):GND
  AJ48  GND            VSS<807>  @BASEBOARD_FAB2_LIB.BASEBOARD_FAB2(SCH_1):GND
  AJ50  GND            VSS<806>  @BASEBOARD_FAB2_LIB.BASEBOARD_FAB2(SCH_1):GND
  AJ52  GND            VSS<805>  @BASEBOARD_FAB2_LIB.BASEBOARD_FAB2(SCH_1):GND
  AJ54  GND            VSS<804>  @BASEBOARD_FAB2_LIB.BASEBOARD_FAB2(SCH_1):GND
  AJ66  GND            VSS<803>  @BASEBOARD_FAB2_LIB.BASEBOARD_FAB2(SCH_1):GND
  AJ68  GND            VSS<802>  @BASEBOARD_FAB2_LIB.BASEBOARD_FAB2(SCH_1):GND
  AJ74  GND            VSS<801>  @BASEBOARD_FAB2_LIB.BASEBOARD_FAB2(SCH_1):GND
  AJ78  GND            VSS<800>  @BASEBOARD_FAB2_LIB.BASEBOARD_FAB2(SCH_1):GND
  AJ82  GND            VSS<799>  @BASEBOARD_FAB2_LIB.BASEBOARD_FAB2(SCH_1):GND
  AJ86  GND            VSS<798>  @BASEBOARD_FAB2_LIB.BASEBOARD_FAB2(SCH_1):GND
  AK9  GND            VSS<797>  @BASEBOARD_FAB2_LIB.BASEBOARD_FAB2(SCH_1):GND
  AK13  GND            VSS<796>  @BASEBOARD_FAB2_LIB.BASEBOARD_FAB2(SCH_1):GND
  AK19  GND            VSS<795>  @BASEBOARD_FAB2_LIB.BASEBOARD_FAB2(SCH_1):GND
  AK23  GND            VSS<794>  @BASEBOARD_FAB2_LIB.BASEBOARD_FAB2(SCH_1):GND
  AK25  GND            VSS<793>  @BASEBOARD_FAB2_LIB.BASEBOARD_FAB2(SCH_1):GND
  AK29  GND            VSS<792>  @BASEBOARD_FAB2_LIB.BASEBOARD_FAB2(SCH_1):GND
  AK31  GND            VSS<791>  @BASEBOARD_FAB2_LIB.BASEBOARD_FAB2(SCH_1):GND
  AK33  GND            VSS<790>  @BASEBOARD_FAB2_LIB.BASEBOARD_FAB2(SCH_1):GND
  AK55  GND            VSS<789>  @BASEBOARD_FAB2_LIB.BASEBOARD_FAB2(SCH_1):GND
  AK65  GND            VSS<788>  @BASEBOARD_FAB2_LIB.BASEBOARD_FAB2(SCH_1):GND
  AK67  GND            VSS<787>  @BASEBOARD_FAB2_LIB.BASEBOARD_FAB2(SCH_1):GND
  AK73  GND            VSS<786>  @BASEBOARD_FAB2_LIB.BASEBOARD_FAB2(SCH_1):GND
  AK79  GND            VSS<785>  @BASEBOARD_FAB2_LIB.BASEBOARD_FAB2(SCH_1):GND
  AK81  GND            VSS<784>  @BASEBOARD_FAB2_LIB.BASEBOARD_FAB2(SCH_1):GND
  AK83  GND            VSS<783>  @BASEBOARD_FAB2_LIB.BASEBOARD_FAB2(SCH_1):GND
  AK85  GND            VSS<782>  @BASEBOARD_FAB2_LIB.BASEBOARD_FAB2(SCH_1):GND
  AL4  GND            VSS<781>  @BASEBOARD_FAB2_LIB.BASEBOARD_FAB2(SCH_1):GND
  AL10  GND            VSS<780>  @BASEBOARD_FAB2_LIB.BASEBOARD_FAB2(SCH_1):GND
  AL24  GND            VSS<779>  @BASEBOARD_FAB2_LIB.BASEBOARD_FAB2(SCH_1):GND
  AL30  GND            VSS<778>  @BASEBOARD_FAB2_LIB.BASEBOARD_FAB2(SCH_1):GND
  AL32  GND            VSS<777>  @BASEBOARD_FAB2_LIB.BASEBOARD_FAB2(SCH_1):GND
  AL56  GND            VSS<776>  @BASEBOARD_FAB2_LIB.BASEBOARD_FAB2(SCH_1):GND
  AL64  GND            VSS<775>  @BASEBOARD_FAB2_LIB.BASEBOARD_FAB2(SCH_1):GND
  AL68  GND            VSS<774>  @BASEBOARD_FAB2_LIB.BASEBOARD_FAB2(SCH_1):GND

SKX_EXT_B_BGA1  I21  U2D1   [SKX_EXT_B_BGA1-IC,TBD]
  J76  GND            VSS<1093>  @BASEBOARD_FAB2_LIB.BASEBOARD_FAB2(SCH_1):GND
  J82  GND            VSS<1092>  @BASEBOARD_FAB2_LIB.BASEBOARD_FAB2(SCH_1):GND
  J84  GND            VSS<1091>  @BASEBOARD_FAB2_LIB.BASEBOARD_FAB2(SCH_1):GND
   K1  GND            VSS<1090>  @BASEBOARD_FAB2_LIB.BASEBOARD_FAB2(SCH_1):GND
  K11  GND            VSS<1089>  @BASEBOARD_FAB2_LIB.BASEBOARD_FAB2(SCH_1):GND
  K13  GND            VSS<1088>  @BASEBOARD_FAB2_LIB.BASEBOARD_FAB2(SCH_1):GND
  K17  GND            VSS<1087>  @BASEBOARD_FAB2_LIB.BASEBOARD_FAB2(SCH_1):GND
  DB7  GND            VSS<1086>  @BASEBOARD_FAB2_LIB.BASEBOARD_FAB2(SCH_1):GND
  K27  GND            VSS<1085>  @BASEBOARD_FAB2_LIB.BASEBOARD_FAB2(SCH_1):GND
  K33  GND            VSS<1084>  @BASEBOARD_FAB2_LIB.BASEBOARD_FAB2(SCH_1):GND
  K39  GND            VSS<1083>  @BASEBOARD_FAB2_LIB.BASEBOARD_FAB2(SCH_1):GND
  K65  GND            VSS<1082>  @BASEBOARD_FAB2_LIB.BASEBOARD_FAB2(SCH_1):GND
  K67  GND            VSS<1081>  @BASEBOARD_FAB2_LIB.BASEBOARD_FAB2(SCH_1):GND
  K69  GND            VSS<1080>  @BASEBOARD_FAB2_LIB.BASEBOARD_FAB2(SCH_1):GND
  K71  GND            VSS<1079>  @BASEBOARD_FAB2_LIB.BASEBOARD_FAB2(SCH_1):GND
  K73  GND            VSS<1078>  @BASEBOARD_FAB2_LIB.BASEBOARD_FAB2(SCH_1):GND
  K77  GND            VSS<1077>  @BASEBOARD_FAB2_LIB.BASEBOARD_FAB2(SCH_1):GND
  K81  GND            VSS<1076>  @BASEBOARD_FAB2_LIB.BASEBOARD_FAB2(SCH_1):GND
  K83  GND            VSS<1075>  @BASEBOARD_FAB2_LIB.BASEBOARD_FAB2(SCH_1):GND
  K85  GND            VSS<1074>  @BASEBOARD_FAB2_LIB.BASEBOARD_FAB2(SCH_1):GND
  L10  GND            VSS<1073>  @BASEBOARD_FAB2_LIB.BASEBOARD_FAB2(SCH_1):GND
   L2  GND            VSS<1072>  @BASEBOARD_FAB2_LIB.BASEBOARD_FAB2(SCH_1):GND
   L6  GND            VSS<1071>  @BASEBOARD_FAB2_LIB.BASEBOARD_FAB2(SCH_1):GND
  L20  GND            VSS<1070>  @BASEBOARD_FAB2_LIB.BASEBOARD_FAB2(SCH_1):GND
  L22  GND            VSS<1069>  @BASEBOARD_FAB2_LIB.BASEBOARD_FAB2(SCH_1):GND
  L72  GND            VSS<1068>  @BASEBOARD_FAB2_LIB.BASEBOARD_FAB2(SCH_1):GND
  L78  GND            VSS<1067>  @BASEBOARD_FAB2_LIB.BASEBOARD_FAB2(SCH_1):GND
  L80  GND            VSS<1066>  @BASEBOARD_FAB2_LIB.BASEBOARD_FAB2(SCH_1):GND
  L82  GND            VSS<1065>  @BASEBOARD_FAB2_LIB.BASEBOARD_FAB2(SCH_1):GND
  BT9  GND            VSS<1064>  @BASEBOARD_FAB2_LIB.BASEBOARD_FAB2(SCH_1):GND
  CT7  GND            VSS<1063>  @BASEBOARD_FAB2_LIB.BASEBOARD_FAB2(SCH_1):GND
  M15  GND            VSS<1062>  @BASEBOARD_FAB2_LIB.BASEBOARD_FAB2(SCH_1):GND
  M17  GND            VSS<1061>  @BASEBOARD_FAB2_LIB.BASEBOARD_FAB2(SCH_1):GND
  M19  GND            VSS<1060>  @BASEBOARD_FAB2_LIB.BASEBOARD_FAB2(SCH_1):GND
  M23  GND            VSS<1059>  @BASEBOARD_FAB2_LIB.BASEBOARD_FAB2(SCH_1):GND
  M25  GND            VSS<1058>  @BASEBOARD_FAB2_LIB.BASEBOARD_FAB2(SCH_1):GND
  M27  GND            VSS<1057>  @BASEBOARD_FAB2_LIB.BASEBOARD_FAB2(SCH_1):GND
  M29  GND            VSS<1056>  @BASEBOARD_FAB2_LIB.BASEBOARD_FAB2(SCH_1):GND
  M31  GND            VSS<1055>  @BASEBOARD_FAB2_LIB.BASEBOARD_FAB2(SCH_1):GND
  M33  GND            VSS<1054>  @BASEBOARD_FAB2_LIB.BASEBOARD_FAB2(SCH_1):GND
  M35  GND            VSS<1053>  @BASEBOARD_FAB2_LIB.BASEBOARD_FAB2(SCH_1):GND
  M37  GND            VSS<1052>  @BASEBOARD_FAB2_LIB.BASEBOARD_FAB2(SCH_1):GND
  M39  GND            VSS<1051>  @BASEBOARD_FAB2_LIB.BASEBOARD_FAB2(SCH_1):GND
  M41  GND            VSS<1050>  @BASEBOARD_FAB2_LIB.BASEBOARD_FAB2(SCH_1):GND
  M43  GND            VSS<1049>  @BASEBOARD_FAB2_LIB.BASEBOARD_FAB2(SCH_1):GND
  M65  GND            VSS<1048>  @BASEBOARD_FAB2_LIB.BASEBOARD_FAB2(SCH_1):GND
  M71  GND            VSS<1047>  @BASEBOARD_FAB2_LIB.BASEBOARD_FAB2(SCH_1):GND
  M79  GND            VSS<1046>  @BASEBOARD_FAB2_LIB.BASEBOARD_FAB2(SCH_1):GND
  M83  GND            VSS<1045>  @BASEBOARD_FAB2_LIB.BASEBOARD_FAB2(SCH_1):GND
  M85  GND            VSS<1044>  @BASEBOARD_FAB2_LIB.BASEBOARD_FAB2(SCH_1):GND
  DM19  GND            VSS<1043>  @BASEBOARD_FAB2_LIB.BASEBOARD_FAB2(SCH_1):GND
  N20  GND            VSS<1042>  @BASEBOARD_FAB2_LIB.BASEBOARD_FAB2(SCH_1):GND
  N22  GND            VSS<1041>  @BASEBOARD_FAB2_LIB.BASEBOARD_FAB2(SCH_1):GND
   N6  GND            VSS<1040>  @BASEBOARD_FAB2_LIB.BASEBOARD_FAB2(SCH_1):GND
  N66  GND            VSS<1039>  @BASEBOARD_FAB2_LIB.BASEBOARD_FAB2(SCH_1):GND
  N70  GND            VSS<1038>  @BASEBOARD_FAB2_LIB.BASEBOARD_FAB2(SCH_1):GND
  N72  GND            VSS<1037>  @BASEBOARD_FAB2_LIB.BASEBOARD_FAB2(SCH_1):GND
  N74  GND            VSS<1036>  @BASEBOARD_FAB2_LIB.BASEBOARD_FAB2(SCH_1):GND
  N76  GND            VSS<1035>  @BASEBOARD_FAB2_LIB.BASEBOARD_FAB2(SCH_1):GND
  N78  GND            VSS<1034>  @BASEBOARD_FAB2_LIB.BASEBOARD_FAB2(SCH_1):GND
   N4  GND            VSS<1033>  @BASEBOARD_FAB2_LIB.BASEBOARD_FAB2(SCH_1):GND
   N8  GND            VSS<1032>  @BASEBOARD_FAB2_LIB.BASEBOARD_FAB2(SCH_1):GND
  P11  GND            VSS<1031>  @BASEBOARD_FAB2_LIB.BASEBOARD_FAB2(SCH_1):GND
  P15  GND            VSS<1030>  @BASEBOARD_FAB2_LIB.BASEBOARD_FAB2(SCH_1):GND
  P27  GND            VSS<1029>  @BASEBOARD_FAB2_LIB.BASEBOARD_FAB2(SCH_1):GND
  P33  GND            VSS<1028>  @BASEBOARD_FAB2_LIB.BASEBOARD_FAB2(SCH_1):GND
  P39  GND            VSS<1027>  @BASEBOARD_FAB2_LIB.BASEBOARD_FAB2(SCH_1):GND
  P67  GND            VSS<1026>  @BASEBOARD_FAB2_LIB.BASEBOARD_FAB2(SCH_1):GND
  P69  GND            VSS<1025>  @BASEBOARD_FAB2_LIB.BASEBOARD_FAB2(SCH_1):GND
  P71  GND            VSS<1024>  @BASEBOARD_FAB2_LIB.BASEBOARD_FAB2(SCH_1):GND
  P81  GND            VSS<1023>  @BASEBOARD_FAB2_LIB.BASEBOARD_FAB2(SCH_1):GND
  P83  GND            VSS<1022>  @BASEBOARD_FAB2_LIB.BASEBOARD_FAB2(SCH_1):GND
  R14  GND            VSS<1021>  @BASEBOARD_FAB2_LIB.BASEBOARD_FAB2(SCH_1):GND
  R18  GND            VSS<1020>  @BASEBOARD_FAB2_LIB.BASEBOARD_FAB2(SCH_1):GND
   R2  GND            VSS<1019>  @BASEBOARD_FAB2_LIB.BASEBOARD_FAB2(SCH_1):GND
   R4  GND            VSS<1018>  @BASEBOARD_FAB2_LIB.BASEBOARD_FAB2(SCH_1):GND
  R22  GND            VSS<1017>  @BASEBOARD_FAB2_LIB.BASEBOARD_FAB2(SCH_1):GND
  R26  GND            VSS<1016>  @BASEBOARD_FAB2_LIB.BASEBOARD_FAB2(SCH_1):GND
  R28  GND            VSS<1015>  @BASEBOARD_FAB2_LIB.BASEBOARD_FAB2(SCH_1):GND
  R32  GND            VSS<1014>  @BASEBOARD_FAB2_LIB.BASEBOARD_FAB2(SCH_1):GND
  R34  GND            VSS<1013>  @BASEBOARD_FAB2_LIB.BASEBOARD_FAB2(SCH_1):GND
  R38  GND            VSS<1012>  @BASEBOARD_FAB2_LIB.BASEBOARD_FAB2(SCH_1):GND
  R40  GND            VSS<1011>  @BASEBOARD_FAB2_LIB.BASEBOARD_FAB2(SCH_1):GND
  R68  GND            VSS<1010>  @BASEBOARD_FAB2_LIB.BASEBOARD_FAB2(SCH_1):GND
  R72  GND            VSS<1009>  @BASEBOARD_FAB2_LIB.BASEBOARD_FAB2(SCH_1):GND
  R78  GND            VSS<1008>  @BASEBOARD_FAB2_LIB.BASEBOARD_FAB2(SCH_1):GND
  R86  GND            VSS<1007>  @BASEBOARD_FAB2_LIB.BASEBOARD_FAB2(SCH_1):GND
  T13  GND            VSS<1006>  @BASEBOARD_FAB2_LIB.BASEBOARD_FAB2(SCH_1):GND
  T17  GND            VSS<1005>  @BASEBOARD_FAB2_LIB.BASEBOARD_FAB2(SCH_1):GND
  T25  GND            VSS<1004>  @BASEBOARD_FAB2_LIB.BASEBOARD_FAB2(SCH_1):GND
  T29  GND            VSS<1003>  @BASEBOARD_FAB2_LIB.BASEBOARD_FAB2(SCH_1):GND
  T31  GND            VSS<1002>  @BASEBOARD_FAB2_LIB.BASEBOARD_FAB2(SCH_1):GND
  T35  GND            VSS<1001>  @BASEBOARD_FAB2_LIB.BASEBOARD_FAB2(SCH_1):GND
  T37  GND            VSS<1000>  @BASEBOARD_FAB2_LIB.BASEBOARD_FAB2(SCH_1):GND
  T41  GND            VSS<999>  @BASEBOARD_FAB2_LIB.BASEBOARD_FAB2(SCH_1):GND
  T65  GND            VSS<998>  @BASEBOARD_FAB2_LIB.BASEBOARD_FAB2(SCH_1):GND
  T73  GND            VSS<997>  @BASEBOARD_FAB2_LIB.BASEBOARD_FAB2(SCH_1):GND
  T77  GND            VSS<996>  @BASEBOARD_FAB2_LIB.BASEBOARD_FAB2(SCH_1):GND
  T83  GND            VSS<995>  @BASEBOARD_FAB2_LIB.BASEBOARD_FAB2(SCH_1):GND
  T85  GND            VSS<994>  @BASEBOARD_FAB2_LIB.BASEBOARD_FAB2(SCH_1):GND
   U2  GND            VSS<993>  @BASEBOARD_FAB2_LIB.BASEBOARD_FAB2(SCH_1):GND
   U4  GND            VSS<992>  @BASEBOARD_FAB2_LIB.BASEBOARD_FAB2(SCH_1):GND
   U6  GND            VSS<991>  @BASEBOARD_FAB2_LIB.BASEBOARD_FAB2(SCH_1):GND
  U20  GND            VSS<990>  @BASEBOARD_FAB2_LIB.BASEBOARD_FAB2(SCH_1):GND
  U22  GND            VSS<989>  @BASEBOARD_FAB2_LIB.BASEBOARD_FAB2(SCH_1):GND
  U24  GND            VSS<988>  @BASEBOARD_FAB2_LIB.BASEBOARD_FAB2(SCH_1):GND
  U30  GND            VSS<987>  @BASEBOARD_FAB2_LIB.BASEBOARD_FAB2(SCH_1):GND
  U36  GND            VSS<986>  @BASEBOARD_FAB2_LIB.BASEBOARD_FAB2(SCH_1):GND
  U42  GND            VSS<985>  @BASEBOARD_FAB2_LIB.BASEBOARD_FAB2(SCH_1):GND
  U68  GND            VSS<984>  @BASEBOARD_FAB2_LIB.BASEBOARD_FAB2(SCH_1):GND
  U70  GND            VSS<983>  @BASEBOARD_FAB2_LIB.BASEBOARD_FAB2(SCH_1):GND
  U74  GND            VSS<982>  @BASEBOARD_FAB2_LIB.BASEBOARD_FAB2(SCH_1):GND
  U76  GND            VSS<981>  @BASEBOARD_FAB2_LIB.BASEBOARD_FAB2(SCH_1):GND
  U78  GND            VSS<980>  @BASEBOARD_FAB2_LIB.BASEBOARD_FAB2(SCH_1):GND
  U80  GND            VSS<979>  @BASEBOARD_FAB2_LIB.BASEBOARD_FAB2(SCH_1):GND
  U86  GND            VSS<978>  @BASEBOARD_FAB2_LIB.BASEBOARD_FAB2(SCH_1):GND
   V1  GND            VSS<977>  @BASEBOARD_FAB2_LIB.BASEBOARD_FAB2(SCH_1):GND
   V5  GND            VSS<976>  @BASEBOARD_FAB2_LIB.BASEBOARD_FAB2(SCH_1):GND
   V9  GND            VSS<975>  @BASEBOARD_FAB2_LIB.BASEBOARD_FAB2(SCH_1):GND
  V13  GND            VSS<974>  @BASEBOARD_FAB2_LIB.BASEBOARD_FAB2(SCH_1):GND
  V15  GND            VSS<973>  @BASEBOARD_FAB2_LIB.BASEBOARD_FAB2(SCH_1):GND
  V21  GND            VSS<972>  @BASEBOARD_FAB2_LIB.BASEBOARD_FAB2(SCH_1):GND
  V23  GND            VSS<971>  @BASEBOARD_FAB2_LIB.BASEBOARD_FAB2(SCH_1):GND
  V43  GND            VSS<970>  @BASEBOARD_FAB2_LIB.BASEBOARD_FAB2(SCH_1):GND
  V73  GND            VSS<969>  @BASEBOARD_FAB2_LIB.BASEBOARD_FAB2(SCH_1):GND
  V75  GND            VSS<968>  @BASEBOARD_FAB2_LIB.BASEBOARD_FAB2(SCH_1):GND
  V77  GND            VSS<967>  @BASEBOARD_FAB2_LIB.BASEBOARD_FAB2(SCH_1):GND
  V83  GND            VSS<966>  @BASEBOARD_FAB2_LIB.BASEBOARD_FAB2(SCH_1):GND
   W8  GND            VSS<965>  @BASEBOARD_FAB2_LIB.BASEBOARD_FAB2(SCH_1):GND
  AC56  GND            VSS<964>  @BASEBOARD_FAB2_LIB.BASEBOARD_FAB2(SCH_1):GND
  W12  GND            VSS<963>  @BASEBOARD_FAB2_LIB.BASEBOARD_FAB2(SCH_1):GND
  W22  GND            VSS<962>  @BASEBOARD_FAB2_LIB.BASEBOARD_FAB2(SCH_1):GND
  W24  GND            VSS<961>  @BASEBOARD_FAB2_LIB.BASEBOARD_FAB2(SCH_1):GND
  W26  GND            VSS<960>  @BASEBOARD_FAB2_LIB.BASEBOARD_FAB2(SCH_1):GND
  W28  GND            VSS<959>  @BASEBOARD_FAB2_LIB.BASEBOARD_FAB2(SCH_1):GND
  W30  GND            VSS<958>  @BASEBOARD_FAB2_LIB.BASEBOARD_FAB2(SCH_1):GND
  W32  GND            VSS<957>  @BASEBOARD_FAB2_LIB.BASEBOARD_FAB2(SCH_1):GND
  W34  GND            VSS<956>  @BASEBOARD_FAB2_LIB.BASEBOARD_FAB2(SCH_1):GND
  W36  GND            VSS<955>  @BASEBOARD_FAB2_LIB.BASEBOARD_FAB2(SCH_1):GND
  W38  GND            VSS<954>  @BASEBOARD_FAB2_LIB.BASEBOARD_FAB2(SCH_1):GND
  W40  GND            VSS<953>  @BASEBOARD_FAB2_LIB.BASEBOARD_FAB2(SCH_1):GND
  W42  GND            VSS<952>  @BASEBOARD_FAB2_LIB.BASEBOARD_FAB2(SCH_1):GND
  W68  GND            VSS<951>  @BASEBOARD_FAB2_LIB.BASEBOARD_FAB2(SCH_1):GND
  W74  GND            VSS<950>  @BASEBOARD_FAB2_LIB.BASEBOARD_FAB2(SCH_1):GND
  W78  GND            VSS<949>  @BASEBOARD_FAB2_LIB.BASEBOARD_FAB2(SCH_1):GND
  W82  GND            VSS<948>  @BASEBOARD_FAB2_LIB.BASEBOARD_FAB2(SCH_1):GND
  Y15  GND            VSS<947>  @BASEBOARD_FAB2_LIB.BASEBOARD_FAB2(SCH_1):GND
  Y17  GND            VSS<946>  @BASEBOARD_FAB2_LIB.BASEBOARD_FAB2(SCH_1):GND
   Y5  GND            VSS<945>  @BASEBOARD_FAB2_LIB.BASEBOARD_FAB2(SCH_1):GND
  Y67  GND            VSS<944>  @BASEBOARD_FAB2_LIB.BASEBOARD_FAB2(SCH_1):GND
   Y7  GND            VSS<943>  @BASEBOARD_FAB2_LIB.BASEBOARD_FAB2(SCH_1):GND
   Y9  GND            VSS<942>  @BASEBOARD_FAB2_LIB.BASEBOARD_FAB2(SCH_1):GND
  Y71  GND            VSS<941>  @BASEBOARD_FAB2_LIB.BASEBOARD_FAB2(SCH_1):GND
  Y73  GND            VSS<940>  @BASEBOARD_FAB2_LIB.BASEBOARD_FAB2(SCH_1):GND
  Y79  GND            VSS<939>  @BASEBOARD_FAB2_LIB.BASEBOARD_FAB2(SCH_1):GND
  Y81  GND            VSS<938>  @BASEBOARD_FAB2_LIB.BASEBOARD_FAB2(SCH_1):GND
  Y83  GND            VSS<937>  @BASEBOARD_FAB2_LIB.BASEBOARD_FAB2(SCH_1):GND
  Y85  GND            VSS<936>  @BASEBOARD_FAB2_LIB.BASEBOARD_FAB2(SCH_1):GND
  AA4  GND            VSS<935>  @BASEBOARD_FAB2_LIB.BASEBOARD_FAB2(SCH_1):GND
  AA16  GND            VSS<934>  @BASEBOARD_FAB2_LIB.BASEBOARD_FAB2(SCH_1):GND

SKX_EXT_B_BGA1  I20  U2D1   [SKX_EXT_B_BGA1-IC,TBD]
   B9  GND            VSS<1253>  @BASEBOARD_FAB2_LIB.BASEBOARD_FAB2(SCH_1):GND
  A42  GND            VSS<1252>  @BASEBOARD_FAB2_LIB.BASEBOARD_FAB2(SCH_1):GND
  B43  GND            VSS<1251>  @BASEBOARD_FAB2_LIB.BASEBOARD_FAB2(SCH_1):GND
   B5  GND            VSS<1250>  @BASEBOARD_FAB2_LIB.BASEBOARD_FAB2(SCH_1):GND
  B79  GND            VSS<1249>  @BASEBOARD_FAB2_LIB.BASEBOARD_FAB2(SCH_1):GND
   C4  GND            VSS<1248>  @BASEBOARD_FAB2_LIB.BASEBOARD_FAB2(SCH_1):GND
  C80  GND            VSS<1247>  @BASEBOARD_FAB2_LIB.BASEBOARD_FAB2(SCH_1):GND
   D3  GND            VSS<1246>  @BASEBOARD_FAB2_LIB.BASEBOARD_FAB2(SCH_1):GND
  D81  GND            VSS<1245>  @BASEBOARD_FAB2_LIB.BASEBOARD_FAB2(SCH_1):GND
  E82  GND            VSS<1244>  @BASEBOARD_FAB2_LIB.BASEBOARD_FAB2(SCH_1):GND
  J86  GND            VSS<1243>  @BASEBOARD_FAB2_LIB.BASEBOARD_FAB2(SCH_1):GND
  DY85  GND            VSS<1242>  @BASEBOARD_FAB2_LIB.BASEBOARD_FAB2(SCH_1):GND
  EA84  GND            VSS<1241>  @BASEBOARD_FAB2_LIB.BASEBOARD_FAB2(SCH_1):GND
  EB83  GND            VSS<1240>  @BASEBOARD_FAB2_LIB.BASEBOARD_FAB2(SCH_1):GND
  DW2  GND            VSS<1239>  @BASEBOARD_FAB2_LIB.BASEBOARD_FAB2(SCH_1):GND
  EC42  GND            VSS<1238>  @BASEBOARD_FAB2_LIB.BASEBOARD_FAB2(SCH_1):GND
  EC6  GND            VSS<1237>  @BASEBOARD_FAB2_LIB.BASEBOARD_FAB2(SCH_1):GND
  EC82  GND            VSS<1236>  @BASEBOARD_FAB2_LIB.BASEBOARD_FAB2(SCH_1):GND
  ED41  GND            VSS<1235>  @BASEBOARD_FAB2_LIB.BASEBOARD_FAB2(SCH_1):GND
  ED7  GND            VSS<1234>  @BASEBOARD_FAB2_LIB.BASEBOARD_FAB2(SCH_1):GND
  ED81  GND            VSS<1233>  @BASEBOARD_FAB2_LIB.BASEBOARD_FAB2(SCH_1):GND
  EE40  GND            VSS<1232>  @BASEBOARD_FAB2_LIB.BASEBOARD_FAB2(SCH_1):GND
  EE8  GND            VSS<1231>  @BASEBOARD_FAB2_LIB.BASEBOARD_FAB2(SCH_1):GND
  EE80  GND            VSS<1230>  @BASEBOARD_FAB2_LIB.BASEBOARD_FAB2(SCH_1):GND
  ED69  GND            VSS<1229>  @BASEBOARD_FAB2_LIB.BASEBOARD_FAB2(SCH_1):GND
  E66  GND            VSS<1228>  @BASEBOARD_FAB2_LIB.BASEBOARD_FAB2(SCH_1):GND
  V11  GND            VSS<1227>  @BASEBOARD_FAB2_LIB.BASEBOARD_FAB2(SCH_1):GND
   L8  GND            VSS<1226>  @BASEBOARD_FAB2_LIB.BASEBOARD_FAB2(SCH_1):GND
  EA14  GND            VSS<1225>  @BASEBOARD_FAB2_LIB.BASEBOARD_FAB2(SCH_1):GND
  DY63  GND            VSS<1224>  @BASEBOARD_FAB2_LIB.BASEBOARD_FAB2(SCH_1):GND
  DY61  GND            VSS<1223>  @BASEBOARD_FAB2_LIB.BASEBOARD_FAB2(SCH_1):GND
  DY59  GND            VSS<1222>  @BASEBOARD_FAB2_LIB.BASEBOARD_FAB2(SCH_1):GND
  DY57  GND            VSS<1221>  @BASEBOARD_FAB2_LIB.BASEBOARD_FAB2(SCH_1):GND
  DY55  GND            VSS<1220>  @BASEBOARD_FAB2_LIB.BASEBOARD_FAB2(SCH_1):GND
  DY53  GND            VSS<1219>  @BASEBOARD_FAB2_LIB.BASEBOARD_FAB2(SCH_1):GND
  DY51  GND            VSS<1218>  @BASEBOARD_FAB2_LIB.BASEBOARD_FAB2(SCH_1):GND
  DY49  GND            VSS<1217>  @BASEBOARD_FAB2_LIB.BASEBOARD_FAB2(SCH_1):GND
  DY47  GND            VSS<1216>  @BASEBOARD_FAB2_LIB.BASEBOARD_FAB2(SCH_1):GND
  DY45  GND            VSS<1215>  @BASEBOARD_FAB2_LIB.BASEBOARD_FAB2(SCH_1):GND
  DV19  GND            VSS<1214>  @BASEBOARD_FAB2_LIB.BASEBOARD_FAB2(SCH_1):GND
  DP9  GND            VSS<1213>  @BASEBOARD_FAB2_LIB.BASEBOARD_FAB2(SCH_1):GND
  DP63  GND            VSS<1212>  @BASEBOARD_FAB2_LIB.BASEBOARD_FAB2(SCH_1):GND
  DP61  GND            VSS<1211>  @BASEBOARD_FAB2_LIB.BASEBOARD_FAB2(SCH_1):GND
  DP59  GND            VSS<1210>  @BASEBOARD_FAB2_LIB.BASEBOARD_FAB2(SCH_1):GND
  DP57  GND            VSS<1209>  @BASEBOARD_FAB2_LIB.BASEBOARD_FAB2(SCH_1):GND
  DP55  GND            VSS<1208>  @BASEBOARD_FAB2_LIB.BASEBOARD_FAB2(SCH_1):GND
  DP53  GND            VSS<1207>  @BASEBOARD_FAB2_LIB.BASEBOARD_FAB2(SCH_1):GND
  DP51  GND            VSS<1206>  @BASEBOARD_FAB2_LIB.BASEBOARD_FAB2(SCH_1):GND
  DP49  GND            VSS<1205>  @BASEBOARD_FAB2_LIB.BASEBOARD_FAB2(SCH_1):GND
  DP47  GND            VSS<1204>  @BASEBOARD_FAB2_LIB.BASEBOARD_FAB2(SCH_1):GND
  DP45  GND            VSS<1203>  @BASEBOARD_FAB2_LIB.BASEBOARD_FAB2(SCH_1):GND
  DN18  GND            VSS<1202>  @BASEBOARD_FAB2_LIB.BASEBOARD_FAB2(SCH_1):GND
  DL8  GND            VSS<1201>  @BASEBOARD_FAB2_LIB.BASEBOARD_FAB2(SCH_1):GND
  DE62  GND            VSS<1200>  @BASEBOARD_FAB2_LIB.BASEBOARD_FAB2(SCH_1):GND
  DE60  GND            VSS<1199>  @BASEBOARD_FAB2_LIB.BASEBOARD_FAB2(SCH_1):GND
  DE58  GND            VSS<1198>  @BASEBOARD_FAB2_LIB.BASEBOARD_FAB2(SCH_1):GND
  DE56  GND            VSS<1197>  @BASEBOARD_FAB2_LIB.BASEBOARD_FAB2(SCH_1):GND
  DE54  GND            VSS<1196>  @BASEBOARD_FAB2_LIB.BASEBOARD_FAB2(SCH_1):GND
  DE52  GND            VSS<1195>  @BASEBOARD_FAB2_LIB.BASEBOARD_FAB2(SCH_1):GND
  DE50  GND            VSS<1194>  @BASEBOARD_FAB2_LIB.BASEBOARD_FAB2(SCH_1):GND
  DE48  GND            VSS<1193>  @BASEBOARD_FAB2_LIB.BASEBOARD_FAB2(SCH_1):GND
  CW6  GND            VSS<1192>  @BASEBOARD_FAB2_LIB.BASEBOARD_FAB2(SCH_1):GND
  CG6  GND            VSS<1191>  @BASEBOARD_FAB2_LIB.BASEBOARD_FAB2(SCH_1):GND
  AR6  GND            VSS<1190>  @BASEBOARD_FAB2_LIB.BASEBOARD_FAB2(SCH_1):GND
  AJ4  GND            VSS<1189>  @BASEBOARD_FAB2_LIB.BASEBOARD_FAB2(SCH_1):GND
  AC62  GND            VSS<1188>  @BASEBOARD_FAB2_LIB.BASEBOARD_FAB2(SCH_1):GND
  AC60  GND            VSS<1187>  @BASEBOARD_FAB2_LIB.BASEBOARD_FAB2(SCH_1):GND
  AC58  GND            VSS<1186>  @BASEBOARD_FAB2_LIB.BASEBOARD_FAB2(SCH_1):GND
  A26  GND            VSS<1185>  @BASEBOARD_FAB2_LIB.BASEBOARD_FAB2(SCH_1):GND
  A30  GND            VSS<1184>  @BASEBOARD_FAB2_LIB.BASEBOARD_FAB2(SCH_1):GND
  A32  GND            VSS<1183>  @BASEBOARD_FAB2_LIB.BASEBOARD_FAB2(SCH_1):GND
  A36  GND            VSS<1182>  @BASEBOARD_FAB2_LIB.BASEBOARD_FAB2(SCH_1):GND
  A38  GND            VSS<1181>  @BASEBOARD_FAB2_LIB.BASEBOARD_FAB2(SCH_1):GND
  B25  GND            VSS<1180>  @BASEBOARD_FAB2_LIB.BASEBOARD_FAB2(SCH_1):GND
  B31  GND            VSS<1179>  @BASEBOARD_FAB2_LIB.BASEBOARD_FAB2(SCH_1):GND
  B37  GND            VSS<1178>  @BASEBOARD_FAB2_LIB.BASEBOARD_FAB2(SCH_1):GND
  B71  GND            VSS<1177>  @BASEBOARD_FAB2_LIB.BASEBOARD_FAB2(SCH_1):GND
  B75  GND            VSS<1176>  @BASEBOARD_FAB2_LIB.BASEBOARD_FAB2(SCH_1):GND
   C8  GND            VSS<1175>  @BASEBOARD_FAB2_LIB.BASEBOARD_FAB2(SCH_1):GND
  C10  GND            VSS<1174>  @BASEBOARD_FAB2_LIB.BASEBOARD_FAB2(SCH_1):GND
  C12  GND            VSS<1173>  @BASEBOARD_FAB2_LIB.BASEBOARD_FAB2(SCH_1):GND
  C14  GND            VSS<1172>  @BASEBOARD_FAB2_LIB.BASEBOARD_FAB2(SCH_1):GND
  C16  GND            VSS<1171>  @BASEBOARD_FAB2_LIB.BASEBOARD_FAB2(SCH_1):GND
  C76  GND            VSS<1170>  @BASEBOARD_FAB2_LIB.BASEBOARD_FAB2(SCH_1):GND
  C78  GND            VSS<1169>  @BASEBOARD_FAB2_LIB.BASEBOARD_FAB2(SCH_1):GND
  CM27  GND            VSS<1168>  @BASEBOARD_FAB2_LIB.BASEBOARD_FAB2(SCH_1):GND
  D11  GND            VSS<1167>  @BASEBOARD_FAB2_LIB.BASEBOARD_FAB2(SCH_1):GND
  D13  GND            VSS<1166>  @BASEBOARD_FAB2_LIB.BASEBOARD_FAB2(SCH_1):GND
  D25  GND            VSS<1165>  @BASEBOARD_FAB2_LIB.BASEBOARD_FAB2(SCH_1):GND
  D27  GND            VSS<1164>  @BASEBOARD_FAB2_LIB.BASEBOARD_FAB2(SCH_1):GND
  D29  GND            VSS<1163>  @BASEBOARD_FAB2_LIB.BASEBOARD_FAB2(SCH_1):GND
  D31  GND            VSS<1162>  @BASEBOARD_FAB2_LIB.BASEBOARD_FAB2(SCH_1):GND
  D33  GND            VSS<1161>  @BASEBOARD_FAB2_LIB.BASEBOARD_FAB2(SCH_1):GND
  D35  GND            VSS<1160>  @BASEBOARD_FAB2_LIB.BASEBOARD_FAB2(SCH_1):GND
  D37  GND            VSS<1159>  @BASEBOARD_FAB2_LIB.BASEBOARD_FAB2(SCH_1):GND
  D39  GND            VSS<1158>  @BASEBOARD_FAB2_LIB.BASEBOARD_FAB2(SCH_1):GND
  D41  GND            VSS<1157>  @BASEBOARD_FAB2_LIB.BASEBOARD_FAB2(SCH_1):GND
  D43  GND            VSS<1156>  @BASEBOARD_FAB2_LIB.BASEBOARD_FAB2(SCH_1):GND
  D77  GND            VSS<1155>  @BASEBOARD_FAB2_LIB.BASEBOARD_FAB2(SCH_1):GND
   E6  GND            VSS<1154>  @BASEBOARD_FAB2_LIB.BASEBOARD_FAB2(SCH_1):GND
   E8  GND            VSS<1153>  @BASEBOARD_FAB2_LIB.BASEBOARD_FAB2(SCH_1):GND
  E16  GND            VSS<1152>  @BASEBOARD_FAB2_LIB.BASEBOARD_FAB2(SCH_1):GND
  E18  GND            VSS<1151>  @BASEBOARD_FAB2_LIB.BASEBOARD_FAB2(SCH_1):GND
  E20  GND            VSS<1150>  @BASEBOARD_FAB2_LIB.BASEBOARD_FAB2(SCH_1):GND
  E22  GND            VSS<1149>  @BASEBOARD_FAB2_LIB.BASEBOARD_FAB2(SCH_1):GND
  E72  GND            VSS<1148>  @BASEBOARD_FAB2_LIB.BASEBOARD_FAB2(SCH_1):GND
  E74  GND            VSS<1147>  @BASEBOARD_FAB2_LIB.BASEBOARD_FAB2(SCH_1):GND
  E76  GND            VSS<1146>  @BASEBOARD_FAB2_LIB.BASEBOARD_FAB2(SCH_1):GND
   F5  GND            VSS<1145>  @BASEBOARD_FAB2_LIB.BASEBOARD_FAB2(SCH_1):GND
  F17  GND            VSS<1144>  @BASEBOARD_FAB2_LIB.BASEBOARD_FAB2(SCH_1):GND
  F19  GND            VSS<1143>  @BASEBOARD_FAB2_LIB.BASEBOARD_FAB2(SCH_1):GND
  F25  GND            VSS<1142>  @BASEBOARD_FAB2_LIB.BASEBOARD_FAB2(SCH_1):GND
  F31  GND            VSS<1141>  @BASEBOARD_FAB2_LIB.BASEBOARD_FAB2(SCH_1):GND
  F37  GND            VSS<1140>  @BASEBOARD_FAB2_LIB.BASEBOARD_FAB2(SCH_1):GND
  F43  GND            VSS<1139>  @BASEBOARD_FAB2_LIB.BASEBOARD_FAB2(SCH_1):GND
  F67  GND            VSS<1138>  @BASEBOARD_FAB2_LIB.BASEBOARD_FAB2(SCH_1):GND
  F69  GND            VSS<1137>  @BASEBOARD_FAB2_LIB.BASEBOARD_FAB2(SCH_1):GND
   G4  GND            VSS<1136>  @BASEBOARD_FAB2_LIB.BASEBOARD_FAB2(SCH_1):GND
   G8  GND            VSS<1135>  @BASEBOARD_FAB2_LIB.BASEBOARD_FAB2(SCH_1):GND
  G22  GND            VSS<1134>  @BASEBOARD_FAB2_LIB.BASEBOARD_FAB2(SCH_1):GND
  G24  GND            VSS<1133>  @BASEBOARD_FAB2_LIB.BASEBOARD_FAB2(SCH_1):GND
  G26  GND            VSS<1132>  @BASEBOARD_FAB2_LIB.BASEBOARD_FAB2(SCH_1):GND
  G30  GND            VSS<1131>  @BASEBOARD_FAB2_LIB.BASEBOARD_FAB2(SCH_1):GND
  G32  GND            VSS<1130>  @BASEBOARD_FAB2_LIB.BASEBOARD_FAB2(SCH_1):GND
  G36  GND            VSS<1129>  @BASEBOARD_FAB2_LIB.BASEBOARD_FAB2(SCH_1):GND
  G38  GND            VSS<1128>  @BASEBOARD_FAB2_LIB.BASEBOARD_FAB2(SCH_1):GND
  G42  GND            VSS<1127>  @BASEBOARD_FAB2_LIB.BASEBOARD_FAB2(SCH_1):GND
  G66  GND            VSS<1126>  @BASEBOARD_FAB2_LIB.BASEBOARD_FAB2(SCH_1):GND
  G70  GND            VSS<1125>  @BASEBOARD_FAB2_LIB.BASEBOARD_FAB2(SCH_1):GND
  G76  GND            VSS<1124>  @BASEBOARD_FAB2_LIB.BASEBOARD_FAB2(SCH_1):GND
  G78  GND            VSS<1123>  @BASEBOARD_FAB2_LIB.BASEBOARD_FAB2(SCH_1):GND
  G80  GND            VSS<1122>  @BASEBOARD_FAB2_LIB.BASEBOARD_FAB2(SCH_1):GND
  G82  GND            VSS<1121>  @BASEBOARD_FAB2_LIB.BASEBOARD_FAB2(SCH_1):GND
   H3  GND            VSS<1120>  @BASEBOARD_FAB2_LIB.BASEBOARD_FAB2(SCH_1):GND
  H11  GND            VSS<1119>  @BASEBOARD_FAB2_LIB.BASEBOARD_FAB2(SCH_1):GND
  H25  GND            VSS<1118>  @BASEBOARD_FAB2_LIB.BASEBOARD_FAB2(SCH_1):GND
  H27  GND            VSS<1117>  @BASEBOARD_FAB2_LIB.BASEBOARD_FAB2(SCH_1):GND
  H29  GND            VSS<1116>  @BASEBOARD_FAB2_LIB.BASEBOARD_FAB2(SCH_1):GND
  H31  GND            VSS<1115>  @BASEBOARD_FAB2_LIB.BASEBOARD_FAB2(SCH_1):GND
  H33  GND            VSS<1114>  @BASEBOARD_FAB2_LIB.BASEBOARD_FAB2(SCH_1):GND
  H35  GND            VSS<1113>  @BASEBOARD_FAB2_LIB.BASEBOARD_FAB2(SCH_1):GND
  H37  GND            VSS<1112>  @BASEBOARD_FAB2_LIB.BASEBOARD_FAB2(SCH_1):GND
  H39  GND            VSS<1111>  @BASEBOARD_FAB2_LIB.BASEBOARD_FAB2(SCH_1):GND
  H41  GND            VSS<1110>  @BASEBOARD_FAB2_LIB.BASEBOARD_FAB2(SCH_1):GND
  H65  GND            VSS<1109>  @BASEBOARD_FAB2_LIB.BASEBOARD_FAB2(SCH_1):GND
  H71  GND            VSS<1108>  @BASEBOARD_FAB2_LIB.BASEBOARD_FAB2(SCH_1):GND
  H75  GND            VSS<1107>  @BASEBOARD_FAB2_LIB.BASEBOARD_FAB2(SCH_1):GND
  DN44  GND            VSS<1106>  @BASEBOARD_FAB2_LIB.BASEBOARD_FAB2(SCH_1):GND
   J4  GND            VSS<1105>  @BASEBOARD_FAB2_LIB.BASEBOARD_FAB2(SCH_1):GND
  J12  GND            VSS<1104>  @BASEBOARD_FAB2_LIB.BASEBOARD_FAB2(SCH_1):GND
  J14  GND            VSS<1103>  @BASEBOARD_FAB2_LIB.BASEBOARD_FAB2(SCH_1):GND
  J22  GND            VSS<1102>  @BASEBOARD_FAB2_LIB.BASEBOARD_FAB2(SCH_1):GND
  J26  GND            VSS<1101>  @BASEBOARD_FAB2_LIB.BASEBOARD_FAB2(SCH_1):GND
  J28  GND            VSS<1100>  @BASEBOARD_FAB2_LIB.BASEBOARD_FAB2(SCH_1):GND
  J32  GND            VSS<1099>  @BASEBOARD_FAB2_LIB.BASEBOARD_FAB2(SCH_1):GND
  J34  GND            VSS<1098>  @BASEBOARD_FAB2_LIB.BASEBOARD_FAB2(SCH_1):GND
  J38  GND            VSS<1097>  @BASEBOARD_FAB2_LIB.BASEBOARD_FAB2(SCH_1):GND
  J40  GND            VSS<1096>  @BASEBOARD_FAB2_LIB.BASEBOARD_FAB2(SCH_1):GND
  J72  GND            VSS<1095>  @BASEBOARD_FAB2_LIB.BASEBOARD_FAB2(SCH_1):GND
  J74  GND            VSS<1094>  @BASEBOARD_FAB2_LIB.BASEBOARD_FAB2(SCH_1):GND

SKX_EXT_B_BGA1  I107  U2D1   [SKX_EXT_B_BGA1-IC,TBD]
  CE76  VSENSE_PVSA_CPU1_SKT_VSEN  VCCSA_SENSE  @BASEBOARD_FAB2_LIB.BASEBOARD_FAB2(SCH_1):VSENSE_PVSA_CPU1_SKT_VSEN
  CG76  VSENSE_PVSA_CPU1_SKT_VRTN  VSS_VCCSA_SENSE  @BASEBOARD_FAB2_LIB.BASEBOARD_FAB2(SCH_1):VSENSE_PVSA_CPU1_SKT_VRTN
  BN16  VSENSE_PVCCMCP_CPU1_SKT_VSEN  CD_VCC_CORE_SENSE  @BASEBOARD_FAB2_LIB.BASEBOARD_FAB2(SCH_1):VSENSE_PVCCMCP_CPU1_SKT_VSEN
  BL16  VSENSE_PVCCMCP_CPU1_SKT_VRTN  CD_VSS_VCC_CORE_SENSE  @BASEBOARD_FAB2_LIB.BASEBOARD_FAB2(SCH_1):VSENSE_PVCCMCP_CPU1_SKT_VRTN
  BH5  VSENSE_PVCCIO_CPU1_SKT_VSEN  VCCIO_SENSE  @BASEBOARD_FAB2_LIB.BASEBOARD_FAB2(SCH_1):VSENSE_PVCCIO_CPU1_SKT_VSEN
  BF5  VSENSE_PVCCIO_CPU1_SKT_VRTN  VSS_VCCIO_SENSE  @BASEBOARD_FAB2_LIB.BASEBOARD_FAB2(SCH_1):VSENSE_PVCCIO_CPU1_SKT_VRTN
  BT17  VSENSE_PVCCIOMCP_CPU1_SKT_VSEN  CD_VCCP_SENSE<1>  @BASEBOARD_FAB2_LIB.BASEBOARD_FAB2(SCH_1):VSENSE_PVCCIOMCP_CPU1_SKT_VSEN
  BU16  VSENSE_PVCCIOMCP_CPU1_SKT_VRTN  CD_VCCP_SENSE<0>  @BASEBOARD_FAB2_LIB.BASEBOARD_FAB2(SCH_1):VSENSE_PVCCIOMCP_CPU1_SKT_VRTN
  ED83  TP_CPU1_RSVD_9  RSVD<9>  @BASEBOARD_FAB2_LIB.BASEBOARD_FAB2(SCH_1):TP_CPU1_RSVD_9
  EE16  TP_CPU1_RSVD_8  RSVD<8>  @BASEBOARD_FAB2_LIB.BASEBOARD_FAB2(SCH_1):TP_CPU1_RSVD_8
  CP31  TP_CPU1_RSVD_73  RSVD<73>  @BASEBOARD_FAB2_LIB.BASEBOARD_FAB2(SCH_1):TP_CPU1_RSVD_73
  CR60  TP_CPU1_RSVD_72  RSVD<72>  @BASEBOARD_FAB2_LIB.BASEBOARD_FAB2(SCH_1):TP_CPU1_RSVD_72
  CT5  TP_CPU1_RSVD_70  RSVD<70>  @BASEBOARD_FAB2_LIB.BASEBOARD_FAB2(SCH_1):TP_CPU1_RSVD_70
  EE46  TP_CPU1_RSVD_7  RSVD<7>  @BASEBOARD_FAB2_LIB.BASEBOARD_FAB2(SCH_1):TP_CPU1_RSVD_7
  CT69  TP_CPU1_RSVD_69  RSVD<69>  @BASEBOARD_FAB2_LIB.BASEBOARD_FAB2(SCH_1):TP_CPU1_RSVD_69
  CU6  TP_CPU1_RSVD_67  RSVD<67>  @BASEBOARD_FAB2_LIB.BASEBOARD_FAB2(SCH_1):TP_CPU1_RSVD_67
  CU60  TP_CPU1_RSVD_66  RSVD<66>  @BASEBOARD_FAB2_LIB.BASEBOARD_FAB2(SCH_1):TP_CPU1_RSVD_66
  CV69  TP_CPU1_RSVD_64  RSVD<64>  @BASEBOARD_FAB2_LIB.BASEBOARD_FAB2(SCH_1):TP_CPU1_RSVD_64
  CW60  TP_CPU1_RSVD_61  RSVD<61>  @BASEBOARD_FAB2_LIB.BASEBOARD_FAB2(SCH_1):TP_CPU1_RSVD_61
  CW62  TP_CPU1_RSVD_60  RSVD<60>  @BASEBOARD_FAB2_LIB.BASEBOARD_FAB2(SCH_1):TP_CPU1_RSVD_60
  EE6  TP_CPU1_RSVD_6  RSVD<6>  @BASEBOARD_FAB2_LIB.BASEBOARD_FAB2(SCH_1):TP_CPU1_RSVD_6
  CY23  TP_CPU1_RSVD_59  RSVD<59>  @BASEBOARD_FAB2_LIB.BASEBOARD_FAB2(SCH_1):TP_CPU1_RSVD_59
  CY39  TP_CPU1_RSVD_57  RSVD<57>  @BASEBOARD_FAB2_LIB.BASEBOARD_FAB2(SCH_1):TP_CPU1_RSVD_57
  CY53  TP_CPU1_RSVD_56  RSVD<56>  @BASEBOARD_FAB2_LIB.BASEBOARD_FAB2(SCH_1):TP_CPU1_RSVD_56
  CY57  TP_CPU1_RSVD_55  RSVD<55>  @BASEBOARD_FAB2_LIB.BASEBOARD_FAB2(SCH_1):TP_CPU1_RSVD_55
  CY63  TP_CPU1_RSVD_54  RSVD<54>  @BASEBOARD_FAB2_LIB.BASEBOARD_FAB2(SCH_1):TP_CPU1_RSVD_54
  CY73  TP_CPU1_RSVD_53  RSVD<53>  @BASEBOARD_FAB2_LIB.BASEBOARD_FAB2(SCH_1):TP_CPU1_RSVD_53
  DA40  TP_CPU1_RSVD_51  RSVD<51>  @BASEBOARD_FAB2_LIB.BASEBOARD_FAB2(SCH_1):TP_CPU1_RSVD_51
  DA52  TP_CPU1_RSVD_50  RSVD<50>  @BASEBOARD_FAB2_LIB.BASEBOARD_FAB2(SCH_1):TP_CPU1_RSVD_50
  EE82  TP_CPU1_RSVD_5  RSVD<5>  @BASEBOARD_FAB2_LIB.BASEBOARD_FAB2(SCH_1):TP_CPU1_RSVD_5
  DA54  TP_CPU1_RSVD_49  RSVD<49>  @BASEBOARD_FAB2_LIB.BASEBOARD_FAB2(SCH_1):TP_CPU1_RSVD_49
  DA56  TP_CPU1_RSVD_48  RSVD<48>  @BASEBOARD_FAB2_LIB.BASEBOARD_FAB2(SCH_1):TP_CPU1_RSVD_48
  DC46  TP_CPU1_RSVD_47  RSVD<47>  @BASEBOARD_FAB2_LIB.BASEBOARD_FAB2(SCH_1):TP_CPU1_RSVD_47
  DC52  TP_CPU1_RSVD_46  RSVD<46>  @BASEBOARD_FAB2_LIB.BASEBOARD_FAB2(SCH_1):TP_CPU1_RSVD_46
  DD51  TP_CPU1_RSVD_45  RSVD<45>  @BASEBOARD_FAB2_LIB.BASEBOARD_FAB2(SCH_1):TP_CPU1_RSVD_45
  DG36  TP_CPU1_RSVD_44  RSVD<44>  @BASEBOARD_FAB2_LIB.BASEBOARD_FAB2(SCH_1):TP_CPU1_RSVD_44
  DG64  TP_CPU1_RSVD_43  RSVD<43>  @BASEBOARD_FAB2_LIB.BASEBOARD_FAB2(SCH_1):TP_CPU1_RSVD_43
  DH65  TP_CPU1_RSVD_42  RSVD<42>  @BASEBOARD_FAB2_LIB.BASEBOARD_FAB2(SCH_1):TP_CPU1_RSVD_42
  DJ36  TP_CPU1_RSVD_41  RSVD<41>  @BASEBOARD_FAB2_LIB.BASEBOARD_FAB2(SCH_1):TP_CPU1_RSVD_41
  DJ66  TP_CPU1_RSVD_40  RSVD<40>  @BASEBOARD_FAB2_LIB.BASEBOARD_FAB2(SCH_1):TP_CPU1_RSVD_40
  EE84  TP_CPU1_RSVD_4  RSVD<4>  @BASEBOARD_FAB2_LIB.BASEBOARD_FAB2(SCH_1):TP_CPU1_RSVD_4
  DK15  TP_CPU1_RSVD_39  RSVD<39>  @BASEBOARD_FAB2_LIB.BASEBOARD_FAB2(SCH_1):TP_CPU1_RSVD_39
  DK37  TP_CPU1_RSVD_38  RSVD<38>  @BASEBOARD_FAB2_LIB.BASEBOARD_FAB2(SCH_1):TP_CPU1_RSVD_38
  DK65  TP_CPU1_RSVD_37  RSVD<37>  @BASEBOARD_FAB2_LIB.BASEBOARD_FAB2(SCH_1):TP_CPU1_RSVD_37
  DK67  TP_CPU1_RSVD_36  RSVD<36>  @BASEBOARD_FAB2_LIB.BASEBOARD_FAB2(SCH_1):TP_CPU1_RSVD_36
  DL38  TP_CPU1_RSVD_35  RSVD<35>  @BASEBOARD_FAB2_LIB.BASEBOARD_FAB2(SCH_1):TP_CPU1_RSVD_35
  DL66  TP_CPU1_RSVD_34  RSVD<34>  @BASEBOARD_FAB2_LIB.BASEBOARD_FAB2(SCH_1):TP_CPU1_RSVD_34
  DM67  TP_CPU1_RSVD_33  RSVD<33>  @BASEBOARD_FAB2_LIB.BASEBOARD_FAB2(SCH_1):TP_CPU1_RSVD_33
  DN62  TP_CPU1_RSVD_32  RSVD<32>  @BASEBOARD_FAB2_LIB.BASEBOARD_FAB2(SCH_1):TP_CPU1_RSVD_32
  DN66  TP_CPU1_RSVD_31  RSVD<31>  @BASEBOARD_FAB2_LIB.BASEBOARD_FAB2(SCH_1):TP_CPU1_RSVD_31
  DP17  TP_CPU1_RSVD_30  RSVD<30>  @BASEBOARD_FAB2_LIB.BASEBOARD_FAB2(SCH_1):TP_CPU1_RSVD_30
  EF47  TP_CPU1_RSVD_3  RSVD<3>  @BASEBOARD_FAB2_LIB.BASEBOARD_FAB2(SCH_1):TP_CPU1_RSVD_3
  DP65  TP_CPU1_RSVD_29  RSVD<29>  @BASEBOARD_FAB2_LIB.BASEBOARD_FAB2(SCH_1):TP_CPU1_RSVD_29
  DR44  TP_CPU1_RSVD_28  RSVD<28>  @BASEBOARD_FAB2_LIB.BASEBOARD_FAB2(SCH_1):TP_CPU1_RSVD_28
  DT71  TP_CPU1_RSVD_27  RSVD<27>  @BASEBOARD_FAB2_LIB.BASEBOARD_FAB2(SCH_1):TP_CPU1_RSVD_27
  DU44  TP_CPU1_RSVD_26  RSVD<26>  @BASEBOARD_FAB2_LIB.BASEBOARD_FAB2(SCH_1):TP_CPU1_RSVD_26
  DV61  TP_CPU1_RSVD_25  RSVD<25>  @BASEBOARD_FAB2_LIB.BASEBOARD_FAB2(SCH_1):TP_CPU1_RSVD_25
  DV71  TP_CPU1_RSVD_24  RSVD<24>  @BASEBOARD_FAB2_LIB.BASEBOARD_FAB2(SCH_1):TP_CPU1_RSVD_24
  DW44  TP_CPU1_RSVD_23  RSVD<23>  @BASEBOARD_FAB2_LIB.BASEBOARD_FAB2(SCH_1):TP_CPU1_RSVD_23
  DW46  TP_CPU1_RSVD_22  RSVD<22>  @BASEBOARD_FAB2_LIB.BASEBOARD_FAB2(SCH_1):TP_CPU1_RSVD_22
  DY3  TP_CPU1_RSVD_21  RSVD<21>  @BASEBOARD_FAB2_LIB.BASEBOARD_FAB2(SCH_1):TP_CPU1_RSVD_21
  EA4  TP_CPU1_RSVD_20  RSVD<20>  @BASEBOARD_FAB2_LIB.BASEBOARD_FAB2(SCH_1):TP_CPU1_RSVD_20
  EF77  TP_CPU1_RSVD_2  RSVD<2>  @BASEBOARD_FAB2_LIB.BASEBOARD_FAB2(SCH_1):TP_CPU1_RSVD_2
  EA44  TP_CPU1_RSVD_19  RSVD<19>  @BASEBOARD_FAB2_LIB.BASEBOARD_FAB2(SCH_1):TP_CPU1_RSVD_19
  EB3  TP_CPU1_RSVD_18  RSVD<18>  @BASEBOARD_FAB2_LIB.BASEBOARD_FAB2(SCH_1):TP_CPU1_RSVD_18
  EB5  TP_CPU1_RSVD_17  RSVD<17>  @BASEBOARD_FAB2_LIB.BASEBOARD_FAB2(SCH_1):TP_CPU1_RSVD_17
  EB85  TP_CPU1_RSVD_16  RSVD<16>  @BASEBOARD_FAB2_LIB.BASEBOARD_FAB2(SCH_1):TP_CPU1_RSVD_16
  EC16  TP_CPU1_RSVD_15  RSVD<15>  @BASEBOARD_FAB2_LIB.BASEBOARD_FAB2(SCH_1):TP_CPU1_RSVD_15
  EC4  TP_CPU1_RSVD_14  RSVD<14>  @BASEBOARD_FAB2_LIB.BASEBOARD_FAB2(SCH_1):TP_CPU1_RSVD_14
  EC44  TP_CPU1_RSVD_13  RSVD<13>  @BASEBOARD_FAB2_LIB.BASEBOARD_FAB2(SCH_1):TP_CPU1_RSVD_13
  EC84  TP_CPU1_RSVD_12  RSVD<12>  @BASEBOARD_FAB2_LIB.BASEBOARD_FAB2(SCH_1):TP_CPU1_RSVD_12
  ED45  TP_CPU1_RSVD_11  RSVD<11>  @BASEBOARD_FAB2_LIB.BASEBOARD_FAB2(SCH_1):TP_CPU1_RSVD_11
  ED5  TP_CPU1_RSVD_10  RSVD<10>  @BASEBOARD_FAB2_LIB.BASEBOARD_FAB2(SCH_1):TP_CPU1_RSVD_10
  EF81  TP_CPU1_RSVD_1  RSVD<1>  @BASEBOARD_FAB2_LIB.BASEBOARD_FAB2(SCH_1):TP_CPU1_RSVD_1
  EF83  TP_CPU1_RSVD_0  RSVD<0>  @BASEBOARD_FAB2_LIB.BASEBOARD_FAB2(SCH_1):TP_CPU1_RSVD_0
  CW22  TP_CPU1_KTI2_DFX_DN  RSVD<63>  @BASEBOARD_FAB2_LIB.BASEBOARD_FAB2(SCH_1):TP_CPU1_KTI2_DFX_DN
  CN22  TP_CPU1_KTI2_AMONV  RSVD<77>  @BASEBOARD_FAB2_LIB.BASEBOARD_FAB2(SCH_1):TP_CPU1_KTI2_AMONV
  CL26  PVCCMCP_CPU1   RSVD<80>  @BASEBOARD_FAB2_LIB.BASEBOARD_FAB2(SCH_1):PVCCMCP_CPU1
  CM23  PVCCMCP_CPU1   RSVD<79>  @BASEBOARD_FAB2_LIB.BASEBOARD_FAB2(SCH_1):PVCCMCP_CPU1
  CM25  PVCCMCP_CPU1   RSVD<78>  @BASEBOARD_FAB2_LIB.BASEBOARD_FAB2(SCH_1):PVCCMCP_CPU1
  CN24  PVCCMCP_CPU1   RSVD<76>  @BASEBOARD_FAB2_LIB.BASEBOARD_FAB2(SCH_1):PVCCMCP_CPU1
  CP23  PVCCMCP_CPU1   RSVD<74>  @BASEBOARD_FAB2_LIB.BASEBOARD_FAB2(SCH_1):PVCCMCP_CPU1
  CT23  PVCCMCP_CPU1   RSVD<71>  @BASEBOARD_FAB2_LIB.BASEBOARD_FAB2(SCH_1):PVCCMCP_CPU1
  CU24  PVCCMCP_CPU1   RSVD<68>  @BASEBOARD_FAB2_LIB.BASEBOARD_FAB2(SCH_1):PVCCMCP_CPU1
  CV23  PVCCMCP_CPU1   RSVD<65>  @BASEBOARD_FAB2_LIB.BASEBOARD_FAB2(SCH_1):PVCCMCP_CPU1
  CW24  PVCCMCP_CPU1   RSVD<62>  @BASEBOARD_FAB2_LIB.BASEBOARD_FAB2(SCH_1):PVCCMCP_CPU1
  CY25  PVCCMCP_CPU1   RSVD<58>  @BASEBOARD_FAB2_LIB.BASEBOARD_FAB2(SCH_1):PVCCMCP_CPU1
  DA24  PVCCMCP_CPU1   RSVD<52>  @BASEBOARD_FAB2_LIB.BASEBOARD_FAB2(SCH_1):PVCCMCP_CPU1
  CN6  PVCCIO_CPU1    VCCIO<19>  @BASEBOARD_FAB2_LIB.BASEBOARD_FAB2(SCH_1):PVCCIO_CPU1
  CU12  PVCCIO_CPU1    VCCIO<18>  @BASEBOARD_FAB2_LIB.BASEBOARD_FAB2(SCH_1):PVCCIO_CPU1
  CV21  PVCCIO_CPU1    VCCIO<17>  @BASEBOARD_FAB2_LIB.BASEBOARD_FAB2(SCH_1):PVCCIO_CPU1
  CU18  PVCCIO_CPU1    VCCIO<16>  @BASEBOARD_FAB2_LIB.BASEBOARD_FAB2(SCH_1):PVCCIO_CPU1
  CY17  PVCCIO_CPU1    VCCIO<15>  @BASEBOARD_FAB2_LIB.BASEBOARD_FAB2(SCH_1):PVCCIO_CPU1
  DC18  PVCCIO_CPU1    VCCIO<14>  @BASEBOARD_FAB2_LIB.BASEBOARD_FAB2(SCH_1):PVCCIO_CPU1
  DE14  PVCCIO_CPU1    VCCIO<13>  @BASEBOARD_FAB2_LIB.BASEBOARD_FAB2(SCH_1):PVCCIO_CPU1
  CP13  PVCCIO_CPU1    VCCIO<12>  @BASEBOARD_FAB2_LIB.BASEBOARD_FAB2(SCH_1):PVCCIO_CPU1
  CL20  PVCCIO_CPU1    VCCIO<11>  @BASEBOARD_FAB2_LIB.BASEBOARD_FAB2(SCH_1):PVCCIO_CPU1
  CG14  PVCCIO_CPU1    VCCIO<10>  @BASEBOARD_FAB2_LIB.BASEBOARD_FAB2(SCH_1):PVCCIO_CPU1
  CF5  PVCCIO_CPU1    VCCIO<9>  @BASEBOARD_FAB2_LIB.BASEBOARD_FAB2(SCH_1):PVCCIO_CPU1
  DK21  PVCCIO_CPU1    VCCIO<8>  @BASEBOARD_FAB2_LIB.BASEBOARD_FAB2(SCH_1):PVCCIO_CPU1
  BE24  PVCCIO_CPU1    VCCIO<7>  @BASEBOARD_FAB2_LIB.BASEBOARD_FAB2(SCH_1):PVCCIO_CPU1
  AT7  PVCCIO_CPU1    VCCIO<6>  @BASEBOARD_FAB2_LIB.BASEBOARD_FAB2(SCH_1):PVCCIO_CPU1
  AT5  PVCCIO_CPU1    VCCIO<5>  @BASEBOARD_FAB2_LIB.BASEBOARD_FAB2(SCH_1):PVCCIO_CPU1
  AM5  PVCCIO_CPU1    VCCIO<4>  @BASEBOARD_FAB2_LIB.BASEBOARD_FAB2(SCH_1):PVCCIO_CPU1
  DV11  PVCCIO_CPU1    VCCIO<3>  @BASEBOARD_FAB2_LIB.BASEBOARD_FAB2(SCH_1):PVCCIO_CPU1
  AF5  PVCCIO_CPU1    VCCIO<2>  @BASEBOARD_FAB2_LIB.BASEBOARD_FAB2(SCH_1):PVCCIO_CPU1
  AE10  PVCCIO_CPU1    VCCIO<1>  @BASEBOARD_FAB2_LIB.BASEBOARD_FAB2(SCH_1):PVCCIO_CPU1
  EE10  PVCCIO_CPU1    VCCIO<0>  @BASEBOARD_FAB2_LIB.BASEBOARD_FAB2(SCH_1):PVCCIO_CPU1
  CN28  PD_CPU1_MCP01_DMON  RSVD<75>  @BASEBOARD_FAB2_LIB.BASEBOARD_FAB2(SCH_1):PD_CPU1_MCP01_DMON

SKX_EXT_B_BGA1  I33  U2D1   [SKX_EXT_B_BGA1-IC,TBD]
  CB65  PVSA_CPU1      VCCSA<25>  @BASEBOARD_FAB2_LIB.BASEBOARD_FAB2(SCH_1):PVSA_CPU1
  CB67  PVSA_CPU1      VCCSA<24>  @BASEBOARD_FAB2_LIB.BASEBOARD_FAB2(SCH_1):PVSA_CPU1
  CB69  PVSA_CPU1      VCCSA<23>  @BASEBOARD_FAB2_LIB.BASEBOARD_FAB2(SCH_1):PVSA_CPU1
  CC66  PVSA_CPU1      VCCSA<22>  @BASEBOARD_FAB2_LIB.BASEBOARD_FAB2(SCH_1):PVSA_CPU1
  CC68  PVSA_CPU1      VCCSA<21>  @BASEBOARD_FAB2_LIB.BASEBOARD_FAB2(SCH_1):PVSA_CPU1
  CC70  PVSA_CPU1      VCCSA<20>  @BASEBOARD_FAB2_LIB.BASEBOARD_FAB2(SCH_1):PVSA_CPU1
  CD65  PVSA_CPU1      VCCSA<19>  @BASEBOARD_FAB2_LIB.BASEBOARD_FAB2(SCH_1):PVSA_CPU1
  CD67  PVSA_CPU1      VCCSA<18>  @BASEBOARD_FAB2_LIB.BASEBOARD_FAB2(SCH_1):PVSA_CPU1
  CD69  PVSA_CPU1      VCCSA<17>  @BASEBOARD_FAB2_LIB.BASEBOARD_FAB2(SCH_1):PVSA_CPU1
  CD71  PVSA_CPU1      VCCSA<16>  @BASEBOARD_FAB2_LIB.BASEBOARD_FAB2(SCH_1):PVSA_CPU1
  CE64  PVSA_CPU1      VCCSA<15>  @BASEBOARD_FAB2_LIB.BASEBOARD_FAB2(SCH_1):PVSA_CPU1
  CE66  PVSA_CPU1      VCCSA<14>  @BASEBOARD_FAB2_LIB.BASEBOARD_FAB2(SCH_1):PVSA_CPU1
  CE68  PVSA_CPU1      VCCSA<13>  @BASEBOARD_FAB2_LIB.BASEBOARD_FAB2(SCH_1):PVSA_CPU1
  CE72  PVSA_CPU1      VCCSA<12>  @BASEBOARD_FAB2_LIB.BASEBOARD_FAB2(SCH_1):PVSA_CPU1
  CE74  PVSA_CPU1      VCCSA<11>  @BASEBOARD_FAB2_LIB.BASEBOARD_FAB2(SCH_1):PVSA_CPU1
  CF65  PVSA_CPU1      VCCSA<10>  @BASEBOARD_FAB2_LIB.BASEBOARD_FAB2(SCH_1):PVSA_CPU1
  CF67  PVSA_CPU1      VCCSA<9>  @BASEBOARD_FAB2_LIB.BASEBOARD_FAB2(SCH_1):PVSA_CPU1
  CF73  PVSA_CPU1      VCCSA<8>  @BASEBOARD_FAB2_LIB.BASEBOARD_FAB2(SCH_1):PVSA_CPU1
  CF75  PVSA_CPU1      VCCSA<7>  @BASEBOARD_FAB2_LIB.BASEBOARD_FAB2(SCH_1):PVSA_CPU1
  CG64  PVSA_CPU1      VCCSA<6>  @BASEBOARD_FAB2_LIB.BASEBOARD_FAB2(SCH_1):PVSA_CPU1
  CG66  PVSA_CPU1      VCCSA<5>  @BASEBOARD_FAB2_LIB.BASEBOARD_FAB2(SCH_1):PVSA_CPU1
  CG74  PVSA_CPU1      VCCSA<4>  @BASEBOARD_FAB2_LIB.BASEBOARD_FAB2(SCH_1):PVSA_CPU1
  CH65  PVSA_CPU1      VCCSA<3>  @BASEBOARD_FAB2_LIB.BASEBOARD_FAB2(SCH_1):PVSA_CPU1
  CH75  PVSA_CPU1      VCCSA<2>  @BASEBOARD_FAB2_LIB.BASEBOARD_FAB2(SCH_1):PVSA_CPU1
  CJ64  PVSA_CPU1      VCCSA<1>  @BASEBOARD_FAB2_LIB.BASEBOARD_FAB2(SCH_1):PVSA_CPU1
  CJ66  PVSA_CPU1      VCCSA<0>  @BASEBOARD_FAB2_LIB.BASEBOARD_FAB2(SCH_1):PVSA_CPU1
   A8  PVPP_GHJ       CD_VPP<3>  @BASEBOARD_FAB2_LIB.BASEBOARD_FAB2(SCH_1):PVPP_GHJ
  A10  PVPP_GHJ       CD_VPP<2>  @BASEBOARD_FAB2_LIB.BASEBOARD_FAB2(SCH_1):PVPP_GHJ
  A12  PVPP_GHJ       CD_VPP<1>  @BASEBOARD_FAB2_LIB.BASEBOARD_FAB2(SCH_1):PVPP_GHJ
  B11  PVPP_GHJ       CD_VPP<0>  @BASEBOARD_FAB2_LIB.BASEBOARD_FAB2(SCH_1):PVPP_GHJ
  BD13  PVCCMCP_CPU1   CD_VCC_CORE<12>  @BASEBOARD_FAB2_LIB.BASEBOARD_FAB2(SCH_1):PVCCMCP_CPU1
  BE12  PVCCMCP_CPU1   CD_VCC_CORE<11>  @BASEBOARD_FAB2_LIB.BASEBOARD_FAB2(SCH_1):PVCCMCP_CPU1
  BE14  PVCCMCP_CPU1   CD_VCC_CORE<10>  @BASEBOARD_FAB2_LIB.BASEBOARD_FAB2(SCH_1):PVCCMCP_CPU1
  BF11  PVCCMCP_CPU1   CD_VCC_CORE<9>  @BASEBOARD_FAB2_LIB.BASEBOARD_FAB2(SCH_1):PVCCMCP_CPU1
  BF13  PVCCMCP_CPU1   CD_VCC_CORE<8>  @BASEBOARD_FAB2_LIB.BASEBOARD_FAB2(SCH_1):PVCCMCP_CPU1
  BG12  PVCCMCP_CPU1   CD_VCC_CORE<7>  @BASEBOARD_FAB2_LIB.BASEBOARD_FAB2(SCH_1):PVCCMCP_CPU1
  BG14  PVCCMCP_CPU1   CD_VCC_CORE<6>  @BASEBOARD_FAB2_LIB.BASEBOARD_FAB2(SCH_1):PVCCMCP_CPU1
  BH13  PVCCMCP_CPU1   CD_VCC_CORE<5>  @BASEBOARD_FAB2_LIB.BASEBOARD_FAB2(SCH_1):PVCCMCP_CPU1
  BJ12  PVCCMCP_CPU1   CD_VCC_CORE<4>  @BASEBOARD_FAB2_LIB.BASEBOARD_FAB2(SCH_1):PVCCMCP_CPU1
  BJ14  PVCCMCP_CPU1   CD_VCC_CORE<3>  @BASEBOARD_FAB2_LIB.BASEBOARD_FAB2(SCH_1):PVCCMCP_CPU1
  BK13  PVCCMCP_CPU1   CD_VCC_CORE<2>  @BASEBOARD_FAB2_LIB.BASEBOARD_FAB2(SCH_1):PVCCMCP_CPU1
  BK15  PVCCMCP_CPU1   CD_VCC_CORE<1>  @BASEBOARD_FAB2_LIB.BASEBOARD_FAB2(SCH_1):PVCCMCP_CPU1
  BL14  PVCCMCP_CPU1   CD_VCC_CORE<0>  @BASEBOARD_FAB2_LIB.BASEBOARD_FAB2(SCH_1):PVCCMCP_CPU1
  AR28  PVCCIO_CPU1    VCCIO<104>  @BASEBOARD_FAB2_LIB.BASEBOARD_FAB2(SCH_1):PVCCIO_CPU1
  AL28  PVCCIO_CPU1    VCCIO<103>  @BASEBOARD_FAB2_LIB.BASEBOARD_FAB2(SCH_1):PVCCIO_CPU1
  AM29  PVCCIO_CPU1    VCCIO<102>  @BASEBOARD_FAB2_LIB.BASEBOARD_FAB2(SCH_1):PVCCIO_CPU1
  AG34  PVCCIO_CPU1    VCCIO<101>  @BASEBOARD_FAB2_LIB.BASEBOARD_FAB2(SCH_1):PVCCIO_CPU1
  AE34  PVCCIO_CPU1    VCCIO<100>  @BASEBOARD_FAB2_LIB.BASEBOARD_FAB2(SCH_1):PVCCIO_CPU1
  AD35  PVCCIO_CPU1    VCCIO<99>  @BASEBOARD_FAB2_LIB.BASEBOARD_FAB2(SCH_1):PVCCIO_CPU1
  AF35  PVCCIO_CPU1    VCCIO<98>  @BASEBOARD_FAB2_LIB.BASEBOARD_FAB2(SCH_1):PVCCIO_CPU1
  AC36  PVCCIO_CPU1    VCCIO<97>  @BASEBOARD_FAB2_LIB.BASEBOARD_FAB2(SCH_1):PVCCIO_CPU1
  AD37  PVCCIO_CPU1    VCCIO<96>  @BASEBOARD_FAB2_LIB.BASEBOARD_FAB2(SCH_1):PVCCIO_CPU1
  AE36  PVCCIO_CPU1    VCCIO<95>  @BASEBOARD_FAB2_LIB.BASEBOARD_FAB2(SCH_1):PVCCIO_CPU1
  BF27  PVCCIO_CPU1    VCCIO<94>  @BASEBOARD_FAB2_LIB.BASEBOARD_FAB2(SCH_1):PVCCIO_CPU1
  BG26  PVCCIO_CPU1    VCCIO<93>  @BASEBOARD_FAB2_LIB.BASEBOARD_FAB2(SCH_1):PVCCIO_CPU1
  BH25  PVCCIO_CPU1    VCCIO<92>  @BASEBOARD_FAB2_LIB.BASEBOARD_FAB2(SCH_1):PVCCIO_CPU1
  BH27  PVCCIO_CPU1    VCCIO<91>  @BASEBOARD_FAB2_LIB.BASEBOARD_FAB2(SCH_1):PVCCIO_CPU1
  BJ26  PVCCIO_CPU1    VCCIO<90>  @BASEBOARD_FAB2_LIB.BASEBOARD_FAB2(SCH_1):PVCCIO_CPU1
  BK25  PVCCIO_CPU1    VCCIO<89>  @BASEBOARD_FAB2_LIB.BASEBOARD_FAB2(SCH_1):PVCCIO_CPU1
  BK27  PVCCIO_CPU1    VCCIO<88>  @BASEBOARD_FAB2_LIB.BASEBOARD_FAB2(SCH_1):PVCCIO_CPU1
  BL26  PVCCIO_CPU1    VCCIO<87>  @BASEBOARD_FAB2_LIB.BASEBOARD_FAB2(SCH_1):PVCCIO_CPU1
  BM27  PVCCIO_CPU1    VCCIO<86>  @BASEBOARD_FAB2_LIB.BASEBOARD_FAB2(SCH_1):PVCCIO_CPU1
  CH27  PVCCIO_CPU1    VCCIO<85>  @BASEBOARD_FAB2_LIB.BASEBOARD_FAB2(SCH_1):PVCCIO_CPU1
  CJ28  PVCCIO_CPU1    VCCIO<84>  @BASEBOARD_FAB2_LIB.BASEBOARD_FAB2(SCH_1):PVCCIO_CPU1
  CC26  PVCCIO_CPU1    VCCIO<83>  @BASEBOARD_FAB2_LIB.BASEBOARD_FAB2(SCH_1):PVCCIO_CPU1
  CD27  PVCCIO_CPU1    VCCIO<82>  @BASEBOARD_FAB2_LIB.BASEBOARD_FAB2(SCH_1):PVCCIO_CPU1
  CF27  PVCCIO_CPU1    VCCIO<81>  @BASEBOARD_FAB2_LIB.BASEBOARD_FAB2(SCH_1):PVCCIO_CPU1
  AV27  PVCCIO_CPU1    VCCIO<80>  @BASEBOARD_FAB2_LIB.BASEBOARD_FAB2(SCH_1):PVCCIO_CPU1
  AW26  PVCCIO_CPU1    VCCIO<79>  @BASEBOARD_FAB2_LIB.BASEBOARD_FAB2(SCH_1):PVCCIO_CPU1
  AY27  PVCCIO_CPU1    VCCIO<78>  @BASEBOARD_FAB2_LIB.BASEBOARD_FAB2(SCH_1):PVCCIO_CPU1
  BA26  PVCCIO_CPU1    VCCIO<77>  @BASEBOARD_FAB2_LIB.BASEBOARD_FAB2(SCH_1):PVCCIO_CPU1
  BB27  PVCCIO_CPU1    VCCIO<76>  @BASEBOARD_FAB2_LIB.BASEBOARD_FAB2(SCH_1):PVCCIO_CPU1
  BC26  PVCCIO_CPU1    VCCIO<75>  @BASEBOARD_FAB2_LIB.BASEBOARD_FAB2(SCH_1):PVCCIO_CPU1
  W10  PVCCIO_CPU1    VCCIO<74>  @BASEBOARD_FAB2_LIB.BASEBOARD_FAB2(SCH_1):PVCCIO_CPU1
  N18  PVCCIO_CPU1    VCCIO<73>  @BASEBOARD_FAB2_LIB.BASEBOARD_FAB2(SCH_1):PVCCIO_CPU1
   M9  PVCCIO_CPU1    VCCIO<72>  @BASEBOARD_FAB2_LIB.BASEBOARD_FAB2(SCH_1):PVCCIO_CPU1
   M7  PVCCIO_CPU1    VCCIO<71>  @BASEBOARD_FAB2_LIB.BASEBOARD_FAB2(SCH_1):PVCCIO_CPU1
  K15  PVCCIO_CPU1    VCCIO<70>  @BASEBOARD_FAB2_LIB.BASEBOARD_FAB2(SCH_1):PVCCIO_CPU1
   J2  PVCCIO_CPU1    VCCIO<69>  @BASEBOARD_FAB2_LIB.BASEBOARD_FAB2(SCH_1):PVCCIO_CPU1
  EB15  PVCCIO_CPU1    VCCIO<68>  @BASEBOARD_FAB2_LIB.BASEBOARD_FAB2(SCH_1):PVCCIO_CPU1
  EA12  PVCCIO_CPU1    VCCIO<67>  @BASEBOARD_FAB2_LIB.BASEBOARD_FAB2(SCH_1):PVCCIO_CPU1
  DU20  PVCCIO_CPU1    VCCIO<66>  @BASEBOARD_FAB2_LIB.BASEBOARD_FAB2(SCH_1):PVCCIO_CPU1
  DR2  PVCCIO_CPU1    VCCIO<65>  @BASEBOARD_FAB2_LIB.BASEBOARD_FAB2(SCH_1):PVCCIO_CPU1
  DR10  PVCCIO_CPU1    VCCIO<64>  @BASEBOARD_FAB2_LIB.BASEBOARD_FAB2(SCH_1):PVCCIO_CPU1
  DP19  PVCCIO_CPU1    VCCIO<63>  @BASEBOARD_FAB2_LIB.BASEBOARD_FAB2(SCH_1):PVCCIO_CPU1
  DN8  PVCCIO_CPU1    VCCIO<62>  @BASEBOARD_FAB2_LIB.BASEBOARD_FAB2(SCH_1):PVCCIO_CPU1
  DM17  PVCCIO_CPU1    VCCIO<61>  @BASEBOARD_FAB2_LIB.BASEBOARD_FAB2(SCH_1):PVCCIO_CPU1
  DJ16  PVCCIO_CPU1    VCCIO<60>  @BASEBOARD_FAB2_LIB.BASEBOARD_FAB2(SCH_1):PVCCIO_CPU1
  H13  PVCCIO_CPU1    VCCIO<59>  @BASEBOARD_FAB2_LIB.BASEBOARD_FAB2(SCH_1):PVCCIO_CPU1
  J10  PVCCIO_CPU1    VCCIO<58>  @BASEBOARD_FAB2_LIB.BASEBOARD_FAB2(SCH_1):PVCCIO_CPU1
  L14  PVCCIO_CPU1    VCCIO<57>  @BASEBOARD_FAB2_LIB.BASEBOARD_FAB2(SCH_1):PVCCIO_CPU1
  L16  PVCCIO_CPU1    VCCIO<56>  @BASEBOARD_FAB2_LIB.BASEBOARD_FAB2(SCH_1):PVCCIO_CPU1
  DH7  PVCCIO_CPU1    VCCIO<55>  @BASEBOARD_FAB2_LIB.BASEBOARD_FAB2(SCH_1):PVCCIO_CPU1
  DG8  PVCCIO_CPU1    VCCIO<54>  @BASEBOARD_FAB2_LIB.BASEBOARD_FAB2(SCH_1):PVCCIO_CPU1
  M11  PVCCIO_CPU1    VCCIO<53>  @BASEBOARD_FAB2_LIB.BASEBOARD_FAB2(SCH_1):PVCCIO_CPU1
  M21  PVCCIO_CPU1    VCCIO<52>  @BASEBOARD_FAB2_LIB.BASEBOARD_FAB2(SCH_1):PVCCIO_CPU1
   P5  PVCCIO_CPU1    VCCIO<51>  @BASEBOARD_FAB2_LIB.BASEBOARD_FAB2(SCH_1):PVCCIO_CPU1
   T3  PVCCIO_CPU1    VCCIO<50>  @BASEBOARD_FAB2_LIB.BASEBOARD_FAB2(SCH_1):PVCCIO_CPU1
  U14  PVCCIO_CPU1    VCCIO<49>  @BASEBOARD_FAB2_LIB.BASEBOARD_FAB2(SCH_1):PVCCIO_CPU1
  DF21  PVCCIO_CPU1    VCCIO<48>  @BASEBOARD_FAB2_LIB.BASEBOARD_FAB2(SCH_1):PVCCIO_CPU1
   W4  PVCCIO_CPU1    VCCIO<47>  @BASEBOARD_FAB2_LIB.BASEBOARD_FAB2(SCH_1):PVCCIO_CPU1
   W6  PVCCIO_CPU1    VCCIO<46>  @BASEBOARD_FAB2_LIB.BASEBOARD_FAB2(SCH_1):PVCCIO_CPU1
  AA10  PVCCIO_CPU1    VCCIO<45>  @BASEBOARD_FAB2_LIB.BASEBOARD_FAB2(SCH_1):PVCCIO_CPU1
  AC20  PVCCIO_CPU1    VCCIO<44>  @BASEBOARD_FAB2_LIB.BASEBOARD_FAB2(SCH_1):PVCCIO_CPU1
  AC4  PVCCIO_CPU1    VCCIO<43>  @BASEBOARD_FAB2_LIB.BASEBOARD_FAB2(SCH_1):PVCCIO_CPU1
  AH9  PVCCIO_CPU1    VCCIO<42>  @BASEBOARD_FAB2_LIB.BASEBOARD_FAB2(SCH_1):PVCCIO_CPU1
  DF13  PVCCIO_CPU1    VCCIO<41>  @BASEBOARD_FAB2_LIB.BASEBOARD_FAB2(SCH_1):PVCCIO_CPU1
  AN10  PVCCIO_CPU1    VCCIO<40>  @BASEBOARD_FAB2_LIB.BASEBOARD_FAB2(SCH_1):PVCCIO_CPU1
  DD7  PVCCIO_CPU1    VCCIO<39>  @BASEBOARD_FAB2_LIB.BASEBOARD_FAB2(SCH_1):PVCCIO_CPU1
  AT11  PVCCIO_CPU1    VCCIO<38>  @BASEBOARD_FAB2_LIB.BASEBOARD_FAB2(SCH_1):PVCCIO_CPU1
  AW6  PVCCIO_CPU1    VCCIO<37>  @BASEBOARD_FAB2_LIB.BASEBOARD_FAB2(SCH_1):PVCCIO_CPU1
  AY11  PVCCIO_CPU1    VCCIO<36>  @BASEBOARD_FAB2_LIB.BASEBOARD_FAB2(SCH_1):PVCCIO_CPU1
  BA24  PVCCIO_CPU1    VCCIO<35>  @BASEBOARD_FAB2_LIB.BASEBOARD_FAB2(SCH_1):PVCCIO_CPU1
  BB5  PVCCIO_CPU1    VCCIO<34>  @BASEBOARD_FAB2_LIB.BASEBOARD_FAB2(SCH_1):PVCCIO_CPU1
  DA14  PVCCIO_CPU1    VCCIO<33>  @BASEBOARD_FAB2_LIB.BASEBOARD_FAB2(SCH_1):PVCCIO_CPU1
  BF23  PVCCIO_CPU1    VCCIO<32>  @BASEBOARD_FAB2_LIB.BASEBOARD_FAB2(SCH_1):PVCCIO_CPU1
  BJ24  PVCCIO_CPU1    VCCIO<31>  @BASEBOARD_FAB2_LIB.BASEBOARD_FAB2(SCH_1):PVCCIO_CPU1
  BP25  PVCCIO_CPU1    VCCIO<30>  @BASEBOARD_FAB2_LIB.BASEBOARD_FAB2(SCH_1):PVCCIO_CPU1
  CB13  PVCCIO_CPU1    VCCIO<29>  @BASEBOARD_FAB2_LIB.BASEBOARD_FAB2(SCH_1):PVCCIO_CPU1
  CB17  PVCCIO_CPU1    VCCIO<28>  @BASEBOARD_FAB2_LIB.BASEBOARD_FAB2(SCH_1):PVCCIO_CPU1
  CD9  PVCCIO_CPU1    VCCIO<27>  @BASEBOARD_FAB2_LIB.BASEBOARD_FAB2(SCH_1):PVCCIO_CPU1
  CE18  PVCCIO_CPU1    VCCIO<26>  @BASEBOARD_FAB2_LIB.BASEBOARD_FAB2(SCH_1):PVCCIO_CPU1
   D7  PVCCIO_CPU1    VCCIO<25>  @BASEBOARD_FAB2_LIB.BASEBOARD_FAB2(SCH_1):PVCCIO_CPU1
  CH9  PVCCIO_CPU1    VCCIO<24>  @BASEBOARD_FAB2_LIB.BASEBOARD_FAB2(SCH_1):PVCCIO_CPU1
  CV7  PVCCIO_CPU1    VCCIO<23>  @BASEBOARD_FAB2_LIB.BASEBOARD_FAB2(SCH_1):PVCCIO_CPU1
  CK5  PVCCIO_CPU1    VCCIO<22>  @BASEBOARD_FAB2_LIB.BASEBOARD_FAB2(SCH_1):PVCCIO_CPU1
  CL12  PVCCIO_CPU1    VCCIO<21>  @BASEBOARD_FAB2_LIB.BASEBOARD_FAB2(SCH_1):PVCCIO_CPU1
  CM15  PVCCIO_CPU1    VCCIO<20>  @BASEBOARD_FAB2_LIB.BASEBOARD_FAB2(SCH_1):PVCCIO_CPU1
  BM11  PVCCIOMCP_CPU1  CD_VCCP<15>  @BASEBOARD_FAB2_LIB.BASEBOARD_FAB2(SCH_1):PVCCIOMCP_CPU1
  BN12  PVCCIOMCP_CPU1  CD_VCCP<14>  @BASEBOARD_FAB2_LIB.BASEBOARD_FAB2(SCH_1):PVCCIOMCP_CPU1
  BN14  PVCCIOMCP_CPU1  CD_VCCP<13>  @BASEBOARD_FAB2_LIB.BASEBOARD_FAB2(SCH_1):PVCCIOMCP_CPU1
  BP11  PVCCIOMCP_CPU1  CD_VCCP<12>  @BASEBOARD_FAB2_LIB.BASEBOARD_FAB2(SCH_1):PVCCIOMCP_CPU1
  BP13  PVCCIOMCP_CPU1  CD_VCCP<11>  @BASEBOARD_FAB2_LIB.BASEBOARD_FAB2(SCH_1):PVCCIOMCP_CPU1
  BP15  PVCCIOMCP_CPU1  CD_VCCP<10>  @BASEBOARD_FAB2_LIB.BASEBOARD_FAB2(SCH_1):PVCCIOMCP_CPU1
  BR12  PVCCIOMCP_CPU1  CD_VCCP<9>  @BASEBOARD_FAB2_LIB.BASEBOARD_FAB2(SCH_1):PVCCIOMCP_CPU1
  BR14  PVCCIOMCP_CPU1  CD_VCCP<8>  @BASEBOARD_FAB2_LIB.BASEBOARD_FAB2(SCH_1):PVCCIOMCP_CPU1
  BT11  PVCCIOMCP_CPU1  CD_VCCP<7>  @BASEBOARD_FAB2_LIB.BASEBOARD_FAB2(SCH_1):PVCCIOMCP_CPU1
  BT13  PVCCIOMCP_CPU1  CD_VCCP<6>  @BASEBOARD_FAB2_LIB.BASEBOARD_FAB2(SCH_1):PVCCIOMCP_CPU1
  BT15  PVCCIOMCP_CPU1  CD_VCCP<5>  @BASEBOARD_FAB2_LIB.BASEBOARD_FAB2(SCH_1):PVCCIOMCP_CPU1
  BU12  PVCCIOMCP_CPU1  CD_VCCP<4>  @BASEBOARD_FAB2_LIB.BASEBOARD_FAB2(SCH_1):PVCCIOMCP_CPU1
  BU14  PVCCIOMCP_CPU1  CD_VCCP<3>  @BASEBOARD_FAB2_LIB.BASEBOARD_FAB2(SCH_1):PVCCIOMCP_CPU1
  BV11  PVCCIOMCP_CPU1  CD_VCCP<2>  @BASEBOARD_FAB2_LIB.BASEBOARD_FAB2(SCH_1):PVCCIOMCP_CPU1
  BV13  PVCCIOMCP_CPU1  CD_VCCP<1>  @BASEBOARD_FAB2_LIB.BASEBOARD_FAB2(SCH_1):PVCCIOMCP_CPU1
  BV15  PVCCIOMCP_CPU1  CD_VCCP<0>  @BASEBOARD_FAB2_LIB.BASEBOARD_FAB2(SCH_1):PVCCIOMCP_CPU1
  CY55  P3V3_STBY      VCC33  @BASEBOARD_FAB2_LIB.BASEBOARD_FAB2(SCH_1):P3V3_STBY
  BY27  P1V8_MCP_CPU1  CD_VCCIN<3>  @BASEBOARD_FAB2_LIB.BASEBOARD_FAB2(SCH_1):P1V8_MCP_CPU1
  BV27  P1V8_MCP_CPU1  CD_VCCIN<2>  @BASEBOARD_FAB2_LIB.BASEBOARD_FAB2(SCH_1):P1V8_MCP_CPU1
  BU26  P1V8_MCP_CPU1  CD_VCCIN<1>  @BASEBOARD_FAB2_LIB.BASEBOARD_FAB2(SCH_1):P1V8_MCP_CPU1
  BT27  P1V8_MCP_CPU1  CD_VCCIN<0>  @BASEBOARD_FAB2_LIB.BASEBOARD_FAB2(SCH_1):P1V8_MCP_CPU1

SKX_EXT_B_BGA1  I32  U2D1   [SKX_EXT_B_BGA1-IC,TBD]
  EE44  PVDDQ_KLM      VCCD345<50>  @BASEBOARD_FAB2_LIB.BASEBOARD_FAB2(SCH_1):PVDDQ_KLM
  EF45  PVDDQ_KLM      VCCD345<49>  @BASEBOARD_FAB2_LIB.BASEBOARD_FAB2(SCH_1):PVDDQ_KLM
  DB53  PVDDQ_KLM      VCCD345<48>  @BASEBOARD_FAB2_LIB.BASEBOARD_FAB2(SCH_1):PVDDQ_KLM
  DB55  PVDDQ_KLM      VCCD345<47>  @BASEBOARD_FAB2_LIB.BASEBOARD_FAB2(SCH_1):PVDDQ_KLM
  DB57  PVDDQ_KLM      VCCD345<46>  @BASEBOARD_FAB2_LIB.BASEBOARD_FAB2(SCH_1):PVDDQ_KLM
  DB59  PVDDQ_KLM      VCCD345<45>  @BASEBOARD_FAB2_LIB.BASEBOARD_FAB2(SCH_1):PVDDQ_KLM
  DB61  PVDDQ_KLM      VCCD345<44>  @BASEBOARD_FAB2_LIB.BASEBOARD_FAB2(SCH_1):PVDDQ_KLM
  DB63  PVDDQ_KLM      VCCD345<43>  @BASEBOARD_FAB2_LIB.BASEBOARD_FAB2(SCH_1):PVDDQ_KLM
  DD45  PVDDQ_KLM      VCCD345<42>  @BASEBOARD_FAB2_LIB.BASEBOARD_FAB2(SCH_1):PVDDQ_KLM
  DH45  PVDDQ_KLM      VCCD345<41>  @BASEBOARD_FAB2_LIB.BASEBOARD_FAB2(SCH_1):PVDDQ_KLM
  DH47  PVDDQ_KLM      VCCD345<40>  @BASEBOARD_FAB2_LIB.BASEBOARD_FAB2(SCH_1):PVDDQ_KLM
  DH49  PVDDQ_KLM      VCCD345<39>  @BASEBOARD_FAB2_LIB.BASEBOARD_FAB2(SCH_1):PVDDQ_KLM
  DH51  PVDDQ_KLM      VCCD345<38>  @BASEBOARD_FAB2_LIB.BASEBOARD_FAB2(SCH_1):PVDDQ_KLM
  DH53  PVDDQ_KLM      VCCD345<37>  @BASEBOARD_FAB2_LIB.BASEBOARD_FAB2(SCH_1):PVDDQ_KLM
  DH55  PVDDQ_KLM      VCCD345<36>  @BASEBOARD_FAB2_LIB.BASEBOARD_FAB2(SCH_1):PVDDQ_KLM
  DH57  PVDDQ_KLM      VCCD345<35>  @BASEBOARD_FAB2_LIB.BASEBOARD_FAB2(SCH_1):PVDDQ_KLM
  DH59  PVDDQ_KLM      VCCD345<34>  @BASEBOARD_FAB2_LIB.BASEBOARD_FAB2(SCH_1):PVDDQ_KLM
  DH61  PVDDQ_KLM      VCCD345<33>  @BASEBOARD_FAB2_LIB.BASEBOARD_FAB2(SCH_1):PVDDQ_KLM
  DH63  PVDDQ_KLM      VCCD345<32>  @BASEBOARD_FAB2_LIB.BASEBOARD_FAB2(SCH_1):PVDDQ_KLM
  DJ64  PVDDQ_KLM      VCCD345<31>  @BASEBOARD_FAB2_LIB.BASEBOARD_FAB2(SCH_1):PVDDQ_KLM
  DL46  PVDDQ_KLM      VCCD345<30>  @BASEBOARD_FAB2_LIB.BASEBOARD_FAB2(SCH_1):PVDDQ_KLM
  DL48  PVDDQ_KLM      VCCD345<29>  @BASEBOARD_FAB2_LIB.BASEBOARD_FAB2(SCH_1):PVDDQ_KLM
  DL50  PVDDQ_KLM      VCCD345<28>  @BASEBOARD_FAB2_LIB.BASEBOARD_FAB2(SCH_1):PVDDQ_KLM
  DL52  PVDDQ_KLM      VCCD345<27>  @BASEBOARD_FAB2_LIB.BASEBOARD_FAB2(SCH_1):PVDDQ_KLM
  DL54  PVDDQ_KLM      VCCD345<26>  @BASEBOARD_FAB2_LIB.BASEBOARD_FAB2(SCH_1):PVDDQ_KLM
  DL56  PVDDQ_KLM      VCCD345<25>  @BASEBOARD_FAB2_LIB.BASEBOARD_FAB2(SCH_1):PVDDQ_KLM
  DL58  PVDDQ_KLM      VCCD345<24>  @BASEBOARD_FAB2_LIB.BASEBOARD_FAB2(SCH_1):PVDDQ_KLM
  DL60  PVDDQ_KLM      VCCD345<23>  @BASEBOARD_FAB2_LIB.BASEBOARD_FAB2(SCH_1):PVDDQ_KLM
  DL62  PVDDQ_KLM      VCCD345<22>  @BASEBOARD_FAB2_LIB.BASEBOARD_FAB2(SCH_1):PVDDQ_KLM
  DU46  PVDDQ_KLM      VCCD345<21>  @BASEBOARD_FAB2_LIB.BASEBOARD_FAB2(SCH_1):PVDDQ_KLM
  DU48  PVDDQ_KLM      VCCD345<20>  @BASEBOARD_FAB2_LIB.BASEBOARD_FAB2(SCH_1):PVDDQ_KLM
  DU50  PVDDQ_KLM      VCCD345<19>  @BASEBOARD_FAB2_LIB.BASEBOARD_FAB2(SCH_1):PVDDQ_KLM
  DU52  PVDDQ_KLM      VCCD345<18>  @BASEBOARD_FAB2_LIB.BASEBOARD_FAB2(SCH_1):PVDDQ_KLM
  DU54  PVDDQ_KLM      VCCD345<17>  @BASEBOARD_FAB2_LIB.BASEBOARD_FAB2(SCH_1):PVDDQ_KLM
  DU56  PVDDQ_KLM      VCCD345<16>  @BASEBOARD_FAB2_LIB.BASEBOARD_FAB2(SCH_1):PVDDQ_KLM
  DU58  PVDDQ_KLM      VCCD345<15>  @BASEBOARD_FAB2_LIB.BASEBOARD_FAB2(SCH_1):PVDDQ_KLM
  DU60  PVDDQ_KLM      VCCD345<14>  @BASEBOARD_FAB2_LIB.BASEBOARD_FAB2(SCH_1):PVDDQ_KLM
  DU62  PVDDQ_KLM      VCCD345<13>  @BASEBOARD_FAB2_LIB.BASEBOARD_FAB2(SCH_1):PVDDQ_KLM
  DU64  PVDDQ_KLM      VCCD345<12>  @BASEBOARD_FAB2_LIB.BASEBOARD_FAB2(SCH_1):PVDDQ_KLM
  EC46  PVDDQ_KLM      VCCD345<11>  @BASEBOARD_FAB2_LIB.BASEBOARD_FAB2(SCH_1):PVDDQ_KLM
  EC48  PVDDQ_KLM      VCCD345<10>  @BASEBOARD_FAB2_LIB.BASEBOARD_FAB2(SCH_1):PVDDQ_KLM
  EC50  PVDDQ_KLM      VCCD345<9>  @BASEBOARD_FAB2_LIB.BASEBOARD_FAB2(SCH_1):PVDDQ_KLM
  EC52  PVDDQ_KLM      VCCD345<8>  @BASEBOARD_FAB2_LIB.BASEBOARD_FAB2(SCH_1):PVDDQ_KLM
  EC54  PVDDQ_KLM      VCCD345<7>  @BASEBOARD_FAB2_LIB.BASEBOARD_FAB2(SCH_1):PVDDQ_KLM
  EC56  PVDDQ_KLM      VCCD345<6>  @BASEBOARD_FAB2_LIB.BASEBOARD_FAB2(SCH_1):PVDDQ_KLM
  EC58  PVDDQ_KLM      VCCD345<5>  @BASEBOARD_FAB2_LIB.BASEBOARD_FAB2(SCH_1):PVDDQ_KLM
  EC60  PVDDQ_KLM      VCCD345<4>  @BASEBOARD_FAB2_LIB.BASEBOARD_FAB2(SCH_1):PVDDQ_KLM
  EC62  PVDDQ_KLM      VCCD345<3>  @BASEBOARD_FAB2_LIB.BASEBOARD_FAB2(SCH_1):PVDDQ_KLM
  EF49  PVDDQ_KLM      VCCD345<2>  @BASEBOARD_FAB2_LIB.BASEBOARD_FAB2(SCH_1):PVDDQ_KLM
  EF53  PVDDQ_KLM      VCCD345<1>  @BASEBOARD_FAB2_LIB.BASEBOARD_FAB2(SCH_1):PVDDQ_KLM
  EF59  PVDDQ_KLM      VCCD345<0>  @BASEBOARD_FAB2_LIB.BASEBOARD_FAB2(SCH_1):PVDDQ_KLM
  B47  PVDDQ_GHJ      VCCD012<51>  @BASEBOARD_FAB2_LIB.BASEBOARD_FAB2(SCH_1):PVDDQ_GHJ
  C46  PVDDQ_GHJ      VCCD012<50>  @BASEBOARD_FAB2_LIB.BASEBOARD_FAB2(SCH_1):PVDDQ_GHJ
  D45  PVDDQ_GHJ      VCCD012<49>  @BASEBOARD_FAB2_LIB.BASEBOARD_FAB2(SCH_1):PVDDQ_GHJ
  AF63  PVDDQ_GHJ      VCCD012<48>  @BASEBOARD_FAB2_LIB.BASEBOARD_FAB2(SCH_1):PVDDQ_GHJ
  AF61  PVDDQ_GHJ      VCCD012<47>  @BASEBOARD_FAB2_LIB.BASEBOARD_FAB2(SCH_1):PVDDQ_GHJ
  AF59  PVDDQ_GHJ      VCCD012<46>  @BASEBOARD_FAB2_LIB.BASEBOARD_FAB2(SCH_1):PVDDQ_GHJ
  AF57  PVDDQ_GHJ      VCCD012<45>  @BASEBOARD_FAB2_LIB.BASEBOARD_FAB2(SCH_1):PVDDQ_GHJ
  AF55  PVDDQ_GHJ      VCCD012<44>  @BASEBOARD_FAB2_LIB.BASEBOARD_FAB2(SCH_1):PVDDQ_GHJ
  AD45  PVDDQ_GHJ      VCCD012<43>  @BASEBOARD_FAB2_LIB.BASEBOARD_FAB2(SCH_1):PVDDQ_GHJ
  Y63  PVDDQ_GHJ      VCCD012<42>  @BASEBOARD_FAB2_LIB.BASEBOARD_FAB2(SCH_1):PVDDQ_GHJ
  Y61  PVDDQ_GHJ      VCCD012<41>  @BASEBOARD_FAB2_LIB.BASEBOARD_FAB2(SCH_1):PVDDQ_GHJ
  Y59  PVDDQ_GHJ      VCCD012<40>  @BASEBOARD_FAB2_LIB.BASEBOARD_FAB2(SCH_1):PVDDQ_GHJ
  Y57  PVDDQ_GHJ      VCCD012<39>  @BASEBOARD_FAB2_LIB.BASEBOARD_FAB2(SCH_1):PVDDQ_GHJ
  Y55  PVDDQ_GHJ      VCCD012<38>  @BASEBOARD_FAB2_LIB.BASEBOARD_FAB2(SCH_1):PVDDQ_GHJ
  Y53  PVDDQ_GHJ      VCCD012<37>  @BASEBOARD_FAB2_LIB.BASEBOARD_FAB2(SCH_1):PVDDQ_GHJ
  Y51  PVDDQ_GHJ      VCCD012<36>  @BASEBOARD_FAB2_LIB.BASEBOARD_FAB2(SCH_1):PVDDQ_GHJ
  Y49  PVDDQ_GHJ      VCCD012<35>  @BASEBOARD_FAB2_LIB.BASEBOARD_FAB2(SCH_1):PVDDQ_GHJ
  Y47  PVDDQ_GHJ      VCCD012<34>  @BASEBOARD_FAB2_LIB.BASEBOARD_FAB2(SCH_1):PVDDQ_GHJ
  Y45  PVDDQ_GHJ      VCCD012<33>  @BASEBOARD_FAB2_LIB.BASEBOARD_FAB2(SCH_1):PVDDQ_GHJ
  W64  PVDDQ_GHJ      VCCD012<32>  @BASEBOARD_FAB2_LIB.BASEBOARD_FAB2(SCH_1):PVDDQ_GHJ
  U62  PVDDQ_GHJ      VCCD012<31>  @BASEBOARD_FAB2_LIB.BASEBOARD_FAB2(SCH_1):PVDDQ_GHJ
  U60  PVDDQ_GHJ      VCCD012<30>  @BASEBOARD_FAB2_LIB.BASEBOARD_FAB2(SCH_1):PVDDQ_GHJ
  U58  PVDDQ_GHJ      VCCD012<29>  @BASEBOARD_FAB2_LIB.BASEBOARD_FAB2(SCH_1):PVDDQ_GHJ
  U56  PVDDQ_GHJ      VCCD012<28>  @BASEBOARD_FAB2_LIB.BASEBOARD_FAB2(SCH_1):PVDDQ_GHJ
  U54  PVDDQ_GHJ      VCCD012<27>  @BASEBOARD_FAB2_LIB.BASEBOARD_FAB2(SCH_1):PVDDQ_GHJ
  U52  PVDDQ_GHJ      VCCD012<26>  @BASEBOARD_FAB2_LIB.BASEBOARD_FAB2(SCH_1):PVDDQ_GHJ
  U50  PVDDQ_GHJ      VCCD012<25>  @BASEBOARD_FAB2_LIB.BASEBOARD_FAB2(SCH_1):PVDDQ_GHJ
  U48  PVDDQ_GHJ      VCCD012<24>  @BASEBOARD_FAB2_LIB.BASEBOARD_FAB2(SCH_1):PVDDQ_GHJ
  U46  PVDDQ_GHJ      VCCD012<23>  @BASEBOARD_FAB2_LIB.BASEBOARD_FAB2(SCH_1):PVDDQ_GHJ
  N64  PVDDQ_GHJ      VCCD012<22>  @BASEBOARD_FAB2_LIB.BASEBOARD_FAB2(SCH_1):PVDDQ_GHJ
  L62  PVDDQ_GHJ      VCCD012<21>  @BASEBOARD_FAB2_LIB.BASEBOARD_FAB2(SCH_1):PVDDQ_GHJ
  L60  PVDDQ_GHJ      VCCD012<20>  @BASEBOARD_FAB2_LIB.BASEBOARD_FAB2(SCH_1):PVDDQ_GHJ
  L58  PVDDQ_GHJ      VCCD012<19>  @BASEBOARD_FAB2_LIB.BASEBOARD_FAB2(SCH_1):PVDDQ_GHJ
  L56  PVDDQ_GHJ      VCCD012<18>  @BASEBOARD_FAB2_LIB.BASEBOARD_FAB2(SCH_1):PVDDQ_GHJ
  L54  PVDDQ_GHJ      VCCD012<17>  @BASEBOARD_FAB2_LIB.BASEBOARD_FAB2(SCH_1):PVDDQ_GHJ
  L52  PVDDQ_GHJ      VCCD012<16>  @BASEBOARD_FAB2_LIB.BASEBOARD_FAB2(SCH_1):PVDDQ_GHJ
  L50  PVDDQ_GHJ      VCCD012<15>  @BASEBOARD_FAB2_LIB.BASEBOARD_FAB2(SCH_1):PVDDQ_GHJ
  L48  PVDDQ_GHJ      VCCD012<14>  @BASEBOARD_FAB2_LIB.BASEBOARD_FAB2(SCH_1):PVDDQ_GHJ
  L46  PVDDQ_GHJ      VCCD012<13>  @BASEBOARD_FAB2_LIB.BASEBOARD_FAB2(SCH_1):PVDDQ_GHJ
  E64  PVDDQ_GHJ      VCCD012<12>  @BASEBOARD_FAB2_LIB.BASEBOARD_FAB2(SCH_1):PVDDQ_GHJ
  E62  PVDDQ_GHJ      VCCD012<11>  @BASEBOARD_FAB2_LIB.BASEBOARD_FAB2(SCH_1):PVDDQ_GHJ
  E60  PVDDQ_GHJ      VCCD012<10>  @BASEBOARD_FAB2_LIB.BASEBOARD_FAB2(SCH_1):PVDDQ_GHJ
  E58  PVDDQ_GHJ      VCCD012<9>  @BASEBOARD_FAB2_LIB.BASEBOARD_FAB2(SCH_1):PVDDQ_GHJ
  E56  PVDDQ_GHJ      VCCD012<8>  @BASEBOARD_FAB2_LIB.BASEBOARD_FAB2(SCH_1):PVDDQ_GHJ
  E54  PVDDQ_GHJ      VCCD012<7>  @BASEBOARD_FAB2_LIB.BASEBOARD_FAB2(SCH_1):PVDDQ_GHJ
  E52  PVDDQ_GHJ      VCCD012<6>  @BASEBOARD_FAB2_LIB.BASEBOARD_FAB2(SCH_1):PVDDQ_GHJ
  E50  PVDDQ_GHJ      VCCD012<5>  @BASEBOARD_FAB2_LIB.BASEBOARD_FAB2(SCH_1):PVDDQ_GHJ
  E48  PVDDQ_GHJ      VCCD012<4>  @BASEBOARD_FAB2_LIB.BASEBOARD_FAB2(SCH_1):PVDDQ_GHJ
  E46  PVDDQ_GHJ      VCCD012<3>  @BASEBOARD_FAB2_LIB.BASEBOARD_FAB2(SCH_1):PVDDQ_GHJ
  B59  PVDDQ_GHJ      VCCD012<2>  @BASEBOARD_FAB2_LIB.BASEBOARD_FAB2(SCH_1):PVDDQ_GHJ
  B53  PVDDQ_GHJ      VCCD012<1>  @BASEBOARD_FAB2_LIB.BASEBOARD_FAB2(SCH_1):PVDDQ_GHJ
  B49  PVDDQ_GHJ      VCCD012<0>  @BASEBOARD_FAB2_LIB.BASEBOARD_FAB2(SCH_1):PVDDQ_GHJ

SKX_EXT_B_BGA1  I51  U2D1   [SKX_EXT_B_BGA1-IC,TBD]
  AV85  VSENSE_VCCINR2PMAX_CPU1  VCCINPMAX<1>  @BASEBOARD_FAB2_LIB.BASEBOARD_FAB2(SCH_1):VSENSE_VCCINR2PMAX_CPU1
  AW86  VSENSE_VCCINR2PMAX_CPU1  VCCINPMAX<0>  @BASEBOARD_FAB2_LIB.BASEBOARD_FAB2(SCH_1):VSENSE_VCCINR2PMAX_CPU1
  BA86  VSENSE_PVCCIN_CPU1_SKT_VSEN  VCCIN_SENSE  @BASEBOARD_FAB2_LIB.BASEBOARD_FAB2(SCH_1):VSENSE_PVCCIN_CPU1_SKT_VSEN
  AY85  VSENSE_PVCCIN_CPU1_SKT_VRTN  VSS_VCCIN_SENSE  @BASEBOARD_FAB2_LIB.BASEBOARD_FAB2(SCH_1):VSENSE_PVCCIN_CPU1_SKT_VRTN
  AD41  VSENSE_PMAX_CPU1  VSENSEPMAX  @BASEBOARD_FAB2_LIB.BASEBOARD_FAB2(SCH_1):VSENSE_PMAX_CPU1
  BN80  PVCCIN_CPU1    VCCIN<129>  @BASEBOARD_FAB2_LIB.BASEBOARD_FAB2(SCH_1):PVCCIN_CPU1
  BN82  PVCCIN_CPU1    VCCIN<128>  @BASEBOARD_FAB2_LIB.BASEBOARD_FAB2(SCH_1):PVCCIN_CPU1
  BN84  PVCCIN_CPU1    VCCIN<127>  @BASEBOARD_FAB2_LIB.BASEBOARD_FAB2(SCH_1):PVCCIN_CPU1
  BP61  PVCCIN_CPU1    VCCIN<126>  @BASEBOARD_FAB2_LIB.BASEBOARD_FAB2(SCH_1):PVCCIN_CPU1
  BP63  PVCCIN_CPU1    VCCIN<125>  @BASEBOARD_FAB2_LIB.BASEBOARD_FAB2(SCH_1):PVCCIN_CPU1
  BP65  PVCCIN_CPU1    VCCIN<124>  @BASEBOARD_FAB2_LIB.BASEBOARD_FAB2(SCH_1):PVCCIN_CPU1
  BP67  PVCCIN_CPU1    VCCIN<123>  @BASEBOARD_FAB2_LIB.BASEBOARD_FAB2(SCH_1):PVCCIN_CPU1
  BP69  PVCCIN_CPU1    VCCIN<122>  @BASEBOARD_FAB2_LIB.BASEBOARD_FAB2(SCH_1):PVCCIN_CPU1
  BP71  PVCCIN_CPU1    VCCIN<121>  @BASEBOARD_FAB2_LIB.BASEBOARD_FAB2(SCH_1):PVCCIN_CPU1
  BP73  PVCCIN_CPU1    VCCIN<120>  @BASEBOARD_FAB2_LIB.BASEBOARD_FAB2(SCH_1):PVCCIN_CPU1
  BP75  PVCCIN_CPU1    VCCIN<119>  @BASEBOARD_FAB2_LIB.BASEBOARD_FAB2(SCH_1):PVCCIN_CPU1
  BP77  PVCCIN_CPU1    VCCIN<118>  @BASEBOARD_FAB2_LIB.BASEBOARD_FAB2(SCH_1):PVCCIN_CPU1
  BP79  PVCCIN_CPU1    VCCIN<117>  @BASEBOARD_FAB2_LIB.BASEBOARD_FAB2(SCH_1):PVCCIN_CPU1
  BP81  PVCCIN_CPU1    VCCIN<116>  @BASEBOARD_FAB2_LIB.BASEBOARD_FAB2(SCH_1):PVCCIN_CPU1
  BP83  PVCCIN_CPU1    VCCIN<115>  @BASEBOARD_FAB2_LIB.BASEBOARD_FAB2(SCH_1):PVCCIN_CPU1
  BR60  PVCCIN_CPU1    VCCIN<114>  @BASEBOARD_FAB2_LIB.BASEBOARD_FAB2(SCH_1):PVCCIN_CPU1
  BR62  PVCCIN_CPU1    VCCIN<113>  @BASEBOARD_FAB2_LIB.BASEBOARD_FAB2(SCH_1):PVCCIN_CPU1
  BR84  PVCCIN_CPU1    VCCIN<112>  @BASEBOARD_FAB2_LIB.BASEBOARD_FAB2(SCH_1):PVCCIN_CPU1
  BT61  PVCCIN_CPU1    VCCIN<111>  @BASEBOARD_FAB2_LIB.BASEBOARD_FAB2(SCH_1):PVCCIN_CPU1
  BT63  PVCCIN_CPU1    VCCIN<110>  @BASEBOARD_FAB2_LIB.BASEBOARD_FAB2(SCH_1):PVCCIN_CPU1
  BT65  PVCCIN_CPU1    VCCIN<109>  @BASEBOARD_FAB2_LIB.BASEBOARD_FAB2(SCH_1):PVCCIN_CPU1
  BT67  PVCCIN_CPU1    VCCIN<108>  @BASEBOARD_FAB2_LIB.BASEBOARD_FAB2(SCH_1):PVCCIN_CPU1
  BT69  PVCCIN_CPU1    VCCIN<107>  @BASEBOARD_FAB2_LIB.BASEBOARD_FAB2(SCH_1):PVCCIN_CPU1
  BT71  PVCCIN_CPU1    VCCIN<106>  @BASEBOARD_FAB2_LIB.BASEBOARD_FAB2(SCH_1):PVCCIN_CPU1
  BT73  PVCCIN_CPU1    VCCIN<105>  @BASEBOARD_FAB2_LIB.BASEBOARD_FAB2(SCH_1):PVCCIN_CPU1
  BT75  PVCCIN_CPU1    VCCIN<104>  @BASEBOARD_FAB2_LIB.BASEBOARD_FAB2(SCH_1):PVCCIN_CPU1
  BT77  PVCCIN_CPU1    VCCIN<103>  @BASEBOARD_FAB2_LIB.BASEBOARD_FAB2(SCH_1):PVCCIN_CPU1
  BT79  PVCCIN_CPU1    VCCIN<102>  @BASEBOARD_FAB2_LIB.BASEBOARD_FAB2(SCH_1):PVCCIN_CPU1
  BT81  PVCCIN_CPU1    VCCIN<101>  @BASEBOARD_FAB2_LIB.BASEBOARD_FAB2(SCH_1):PVCCIN_CPU1
  BT83  PVCCIN_CPU1    VCCIN<100>  @BASEBOARD_FAB2_LIB.BASEBOARD_FAB2(SCH_1):PVCCIN_CPU1
  BU60  PVCCIN_CPU1    VCCIN<99>  @BASEBOARD_FAB2_LIB.BASEBOARD_FAB2(SCH_1):PVCCIN_CPU1
  BU62  PVCCIN_CPU1    VCCIN<98>  @BASEBOARD_FAB2_LIB.BASEBOARD_FAB2(SCH_1):PVCCIN_CPU1
  BU64  PVCCIN_CPU1    VCCIN<97>  @BASEBOARD_FAB2_LIB.BASEBOARD_FAB2(SCH_1):PVCCIN_CPU1
  BU66  PVCCIN_CPU1    VCCIN<96>  @BASEBOARD_FAB2_LIB.BASEBOARD_FAB2(SCH_1):PVCCIN_CPU1
  BU68  PVCCIN_CPU1    VCCIN<95>  @BASEBOARD_FAB2_LIB.BASEBOARD_FAB2(SCH_1):PVCCIN_CPU1
  BU70  PVCCIN_CPU1    VCCIN<94>  @BASEBOARD_FAB2_LIB.BASEBOARD_FAB2(SCH_1):PVCCIN_CPU1
  BU72  PVCCIN_CPU1    VCCIN<93>  @BASEBOARD_FAB2_LIB.BASEBOARD_FAB2(SCH_1):PVCCIN_CPU1
  BU74  PVCCIN_CPU1    VCCIN<92>  @BASEBOARD_FAB2_LIB.BASEBOARD_FAB2(SCH_1):PVCCIN_CPU1
  BU76  PVCCIN_CPU1    VCCIN<91>  @BASEBOARD_FAB2_LIB.BASEBOARD_FAB2(SCH_1):PVCCIN_CPU1
  BU78  PVCCIN_CPU1    VCCIN<90>  @BASEBOARD_FAB2_LIB.BASEBOARD_FAB2(SCH_1):PVCCIN_CPU1
  BU80  PVCCIN_CPU1    VCCIN<89>  @BASEBOARD_FAB2_LIB.BASEBOARD_FAB2(SCH_1):PVCCIN_CPU1
  BU82  PVCCIN_CPU1    VCCIN<88>  @BASEBOARD_FAB2_LIB.BASEBOARD_FAB2(SCH_1):PVCCIN_CPU1
  BU84  PVCCIN_CPU1    VCCIN<87>  @BASEBOARD_FAB2_LIB.BASEBOARD_FAB2(SCH_1):PVCCIN_CPU1
  BV61  PVCCIN_CPU1    VCCIN<86>  @BASEBOARD_FAB2_LIB.BASEBOARD_FAB2(SCH_1):PVCCIN_CPU1
  BV63  PVCCIN_CPU1    VCCIN<85>  @BASEBOARD_FAB2_LIB.BASEBOARD_FAB2(SCH_1):PVCCIN_CPU1
  BV65  PVCCIN_CPU1    VCCIN<84>  @BASEBOARD_FAB2_LIB.BASEBOARD_FAB2(SCH_1):PVCCIN_CPU1
  BV67  PVCCIN_CPU1    VCCIN<83>  @BASEBOARD_FAB2_LIB.BASEBOARD_FAB2(SCH_1):PVCCIN_CPU1
  BV69  PVCCIN_CPU1    VCCIN<82>  @BASEBOARD_FAB2_LIB.BASEBOARD_FAB2(SCH_1):PVCCIN_CPU1
  BV71  PVCCIN_CPU1    VCCIN<81>  @BASEBOARD_FAB2_LIB.BASEBOARD_FAB2(SCH_1):PVCCIN_CPU1
  BV73  PVCCIN_CPU1    VCCIN<80>  @BASEBOARD_FAB2_LIB.BASEBOARD_FAB2(SCH_1):PVCCIN_CPU1
  BV75  PVCCIN_CPU1    VCCIN<79>  @BASEBOARD_FAB2_LIB.BASEBOARD_FAB2(SCH_1):PVCCIN_CPU1
  BV77  PVCCIN_CPU1    VCCIN<78>  @BASEBOARD_FAB2_LIB.BASEBOARD_FAB2(SCH_1):PVCCIN_CPU1
  BV79  PVCCIN_CPU1    VCCIN<77>  @BASEBOARD_FAB2_LIB.BASEBOARD_FAB2(SCH_1):PVCCIN_CPU1
  BV81  PVCCIN_CPU1    VCCIN<76>  @BASEBOARD_FAB2_LIB.BASEBOARD_FAB2(SCH_1):PVCCIN_CPU1
  BV83  PVCCIN_CPU1    VCCIN<75>  @BASEBOARD_FAB2_LIB.BASEBOARD_FAB2(SCH_1):PVCCIN_CPU1
  BW60  PVCCIN_CPU1    VCCIN<74>  @BASEBOARD_FAB2_LIB.BASEBOARD_FAB2(SCH_1):PVCCIN_CPU1
  BW62  PVCCIN_CPU1    VCCIN<73>  @BASEBOARD_FAB2_LIB.BASEBOARD_FAB2(SCH_1):PVCCIN_CPU1
  BW64  PVCCIN_CPU1    VCCIN<72>  @BASEBOARD_FAB2_LIB.BASEBOARD_FAB2(SCH_1):PVCCIN_CPU1
  BW66  PVCCIN_CPU1    VCCIN<71>  @BASEBOARD_FAB2_LIB.BASEBOARD_FAB2(SCH_1):PVCCIN_CPU1
  BW68  PVCCIN_CPU1    VCCIN<70>  @BASEBOARD_FAB2_LIB.BASEBOARD_FAB2(SCH_1):PVCCIN_CPU1
  BW70  PVCCIN_CPU1    VCCIN<69>  @BASEBOARD_FAB2_LIB.BASEBOARD_FAB2(SCH_1):PVCCIN_CPU1
  BW84  PVCCIN_CPU1    VCCIN<68>  @BASEBOARD_FAB2_LIB.BASEBOARD_FAB2(SCH_1):PVCCIN_CPU1
  BY61  PVCCIN_CPU1    VCCIN<67>  @BASEBOARD_FAB2_LIB.BASEBOARD_FAB2(SCH_1):PVCCIN_CPU1
  BY73  PVCCIN_CPU1    VCCIN<66>  @BASEBOARD_FAB2_LIB.BASEBOARD_FAB2(SCH_1):PVCCIN_CPU1
  BY75  PVCCIN_CPU1    VCCIN<65>  @BASEBOARD_FAB2_LIB.BASEBOARD_FAB2(SCH_1):PVCCIN_CPU1
  BY77  PVCCIN_CPU1    VCCIN<64>  @BASEBOARD_FAB2_LIB.BASEBOARD_FAB2(SCH_1):PVCCIN_CPU1
  BY79  PVCCIN_CPU1    VCCIN<63>  @BASEBOARD_FAB2_LIB.BASEBOARD_FAB2(SCH_1):PVCCIN_CPU1
  BY81  PVCCIN_CPU1    VCCIN<62>  @BASEBOARD_FAB2_LIB.BASEBOARD_FAB2(SCH_1):PVCCIN_CPU1
  BY83  PVCCIN_CPU1    VCCIN<61>  @BASEBOARD_FAB2_LIB.BASEBOARD_FAB2(SCH_1):PVCCIN_CPU1
  CA60  PVCCIN_CPU1    VCCIN<60>  @BASEBOARD_FAB2_LIB.BASEBOARD_FAB2(SCH_1):PVCCIN_CPU1
  CA62  PVCCIN_CPU1    VCCIN<59>  @BASEBOARD_FAB2_LIB.BASEBOARD_FAB2(SCH_1):PVCCIN_CPU1
  CA72  PVCCIN_CPU1    VCCIN<58>  @BASEBOARD_FAB2_LIB.BASEBOARD_FAB2(SCH_1):PVCCIN_CPU1
  CA74  PVCCIN_CPU1    VCCIN<57>  @BASEBOARD_FAB2_LIB.BASEBOARD_FAB2(SCH_1):PVCCIN_CPU1
  CA76  PVCCIN_CPU1    VCCIN<56>  @BASEBOARD_FAB2_LIB.BASEBOARD_FAB2(SCH_1):PVCCIN_CPU1
  CA78  PVCCIN_CPU1    VCCIN<55>  @BASEBOARD_FAB2_LIB.BASEBOARD_FAB2(SCH_1):PVCCIN_CPU1
  CA80  PVCCIN_CPU1    VCCIN<54>  @BASEBOARD_FAB2_LIB.BASEBOARD_FAB2(SCH_1):PVCCIN_CPU1
  CA82  PVCCIN_CPU1    VCCIN<53>  @BASEBOARD_FAB2_LIB.BASEBOARD_FAB2(SCH_1):PVCCIN_CPU1
  CA84  PVCCIN_CPU1    VCCIN<52>  @BASEBOARD_FAB2_LIB.BASEBOARD_FAB2(SCH_1):PVCCIN_CPU1
  CB61  PVCCIN_CPU1    VCCIN<51>  @BASEBOARD_FAB2_LIB.BASEBOARD_FAB2(SCH_1):PVCCIN_CPU1
  CB73  PVCCIN_CPU1    VCCIN<50>  @BASEBOARD_FAB2_LIB.BASEBOARD_FAB2(SCH_1):PVCCIN_CPU1
  CB75  PVCCIN_CPU1    VCCIN<49>  @BASEBOARD_FAB2_LIB.BASEBOARD_FAB2(SCH_1):PVCCIN_CPU1
  CB77  PVCCIN_CPU1    VCCIN<48>  @BASEBOARD_FAB2_LIB.BASEBOARD_FAB2(SCH_1):PVCCIN_CPU1
  CB79  PVCCIN_CPU1    VCCIN<47>  @BASEBOARD_FAB2_LIB.BASEBOARD_FAB2(SCH_1):PVCCIN_CPU1
  CB81  PVCCIN_CPU1    VCCIN<46>  @BASEBOARD_FAB2_LIB.BASEBOARD_FAB2(SCH_1):PVCCIN_CPU1
  CB83  PVCCIN_CPU1    VCCIN<45>  @BASEBOARD_FAB2_LIB.BASEBOARD_FAB2(SCH_1):PVCCIN_CPU1
  CC60  PVCCIN_CPU1    VCCIN<44>  @BASEBOARD_FAB2_LIB.BASEBOARD_FAB2(SCH_1):PVCCIN_CPU1
  CC62  PVCCIN_CPU1    VCCIN<43>  @BASEBOARD_FAB2_LIB.BASEBOARD_FAB2(SCH_1):PVCCIN_CPU1
  CC84  PVCCIN_CPU1    VCCIN<42>  @BASEBOARD_FAB2_LIB.BASEBOARD_FAB2(SCH_1):PVCCIN_CPU1
  CD61  PVCCIN_CPU1    VCCIN<41>  @BASEBOARD_FAB2_LIB.BASEBOARD_FAB2(SCH_1):PVCCIN_CPU1
  CD83  PVCCIN_CPU1    VCCIN<40>  @BASEBOARD_FAB2_LIB.BASEBOARD_FAB2(SCH_1):PVCCIN_CPU1
  CD85  PVCCIN_CPU1    VCCIN<39>  @BASEBOARD_FAB2_LIB.BASEBOARD_FAB2(SCH_1):PVCCIN_CPU1
  CE60  PVCCIN_CPU1    VCCIN<38>  @BASEBOARD_FAB2_LIB.BASEBOARD_FAB2(SCH_1):PVCCIN_CPU1
  CE84  PVCCIN_CPU1    VCCIN<37>  @BASEBOARD_FAB2_LIB.BASEBOARD_FAB2(SCH_1):PVCCIN_CPU1
  CF61  PVCCIN_CPU1    VCCIN<36>  @BASEBOARD_FAB2_LIB.BASEBOARD_FAB2(SCH_1):PVCCIN_CPU1
  CF85  PVCCIN_CPU1    VCCIN<35>  @BASEBOARD_FAB2_LIB.BASEBOARD_FAB2(SCH_1):PVCCIN_CPU1
  CG60  PVCCIN_CPU1    VCCIN<34>  @BASEBOARD_FAB2_LIB.BASEBOARD_FAB2(SCH_1):PVCCIN_CPU1
  CG84  PVCCIN_CPU1    VCCIN<33>  @BASEBOARD_FAB2_LIB.BASEBOARD_FAB2(SCH_1):PVCCIN_CPU1
  CH61  PVCCIN_CPU1    VCCIN<32>  @BASEBOARD_FAB2_LIB.BASEBOARD_FAB2(SCH_1):PVCCIN_CPU1
  CH85  PVCCIN_CPU1    VCCIN<31>  @BASEBOARD_FAB2_LIB.BASEBOARD_FAB2(SCH_1):PVCCIN_CPU1
  CJ60  PVCCIN_CPU1    VCCIN<30>  @BASEBOARD_FAB2_LIB.BASEBOARD_FAB2(SCH_1):PVCCIN_CPU1
  CK59  PVCCIN_CPU1    VCCIN<29>  @BASEBOARD_FAB2_LIB.BASEBOARD_FAB2(SCH_1):PVCCIN_CPU1
  CK61  PVCCIN_CPU1    VCCIN<28>  @BASEBOARD_FAB2_LIB.BASEBOARD_FAB2(SCH_1):PVCCIN_CPU1
  CL58  PVCCIN_CPU1    VCCIN<27>  @BASEBOARD_FAB2_LIB.BASEBOARD_FAB2(SCH_1):PVCCIN_CPU1
  CL60  PVCCIN_CPU1    VCCIN<26>  @BASEBOARD_FAB2_LIB.BASEBOARD_FAB2(SCH_1):PVCCIN_CPU1
  CM57  PVCCIN_CPU1    VCCIN<25>  @BASEBOARD_FAB2_LIB.BASEBOARD_FAB2(SCH_1):PVCCIN_CPU1
  CM59  PVCCIN_CPU1    VCCIN<24>  @BASEBOARD_FAB2_LIB.BASEBOARD_FAB2(SCH_1):PVCCIN_CPU1
  CN56  PVCCIN_CPU1    VCCIN<23>  @BASEBOARD_FAB2_LIB.BASEBOARD_FAB2(SCH_1):PVCCIN_CPU1
  CN58  PVCCIN_CPU1    VCCIN<22>  @BASEBOARD_FAB2_LIB.BASEBOARD_FAB2(SCH_1):PVCCIN_CPU1
  CP33  PVCCIN_CPU1    VCCIN<21>  @BASEBOARD_FAB2_LIB.BASEBOARD_FAB2(SCH_1):PVCCIN_CPU1
  CP55  PVCCIN_CPU1    VCCIN<20>  @BASEBOARD_FAB2_LIB.BASEBOARD_FAB2(SCH_1):PVCCIN_CPU1
  CP57  PVCCIN_CPU1    VCCIN<19>  @BASEBOARD_FAB2_LIB.BASEBOARD_FAB2(SCH_1):PVCCIN_CPU1
  CR34  PVCCIN_CPU1    VCCIN<18>  @BASEBOARD_FAB2_LIB.BASEBOARD_FAB2(SCH_1):PVCCIN_CPU1
  CR54  PVCCIN_CPU1    VCCIN<17>  @BASEBOARD_FAB2_LIB.BASEBOARD_FAB2(SCH_1):PVCCIN_CPU1
  CR56  PVCCIN_CPU1    VCCIN<16>  @BASEBOARD_FAB2_LIB.BASEBOARD_FAB2(SCH_1):PVCCIN_CPU1
  CT37  PVCCIN_CPU1    VCCIN<15>  @BASEBOARD_FAB2_LIB.BASEBOARD_FAB2(SCH_1):PVCCIN_CPU1
  CT39  PVCCIN_CPU1    VCCIN<14>  @BASEBOARD_FAB2_LIB.BASEBOARD_FAB2(SCH_1):PVCCIN_CPU1
  CT41  PVCCIN_CPU1    VCCIN<13>  @BASEBOARD_FAB2_LIB.BASEBOARD_FAB2(SCH_1):PVCCIN_CPU1
  CT53  PVCCIN_CPU1    VCCIN<12>  @BASEBOARD_FAB2_LIB.BASEBOARD_FAB2(SCH_1):PVCCIN_CPU1
  CT55  PVCCIN_CPU1    VCCIN<11>  @BASEBOARD_FAB2_LIB.BASEBOARD_FAB2(SCH_1):PVCCIN_CPU1
  CU38  PVCCIN_CPU1    VCCIN<10>  @BASEBOARD_FAB2_LIB.BASEBOARD_FAB2(SCH_1):PVCCIN_CPU1
  CU40  PVCCIN_CPU1    VCCIN<9>  @BASEBOARD_FAB2_LIB.BASEBOARD_FAB2(SCH_1):PVCCIN_CPU1
  CU42  PVCCIN_CPU1    VCCIN<8>  @BASEBOARD_FAB2_LIB.BASEBOARD_FAB2(SCH_1):PVCCIN_CPU1
  CU52  PVCCIN_CPU1    VCCIN<7>  @BASEBOARD_FAB2_LIB.BASEBOARD_FAB2(SCH_1):PVCCIN_CPU1
  CU54  PVCCIN_CPU1    VCCIN<6>  @BASEBOARD_FAB2_LIB.BASEBOARD_FAB2(SCH_1):PVCCIN_CPU1
  CV51  PVCCIN_CPU1    VCCIN<5>  @BASEBOARD_FAB2_LIB.BASEBOARD_FAB2(SCH_1):PVCCIN_CPU1
  CW46  PVCCIN_CPU1    VCCIN<4>  @BASEBOARD_FAB2_LIB.BASEBOARD_FAB2(SCH_1):PVCCIN_CPU1
  CW48  PVCCIN_CPU1    VCCIN<3>  @BASEBOARD_FAB2_LIB.BASEBOARD_FAB2(SCH_1):PVCCIN_CPU1
  CW50  PVCCIN_CPU1    VCCIN<2>  @BASEBOARD_FAB2_LIB.BASEBOARD_FAB2(SCH_1):PVCCIN_CPU1
  CY47  PVCCIN_CPU1    VCCIN<1>  @BASEBOARD_FAB2_LIB.BASEBOARD_FAB2(SCH_1):PVCCIN_CPU1
  CY49  PVCCIN_CPU1    VCCIN<0>  @BASEBOARD_FAB2_LIB.BASEBOARD_FAB2(SCH_1):PVCCIN_CPU1

SKX_EXT_B_BGA1  I50  U2D1   [SKX_EXT_B_BGA1-IC,TBD]
  AF43  PVCCIN_CPU1    VCCIN<267>  @BASEBOARD_FAB2_LIB.BASEBOARD_FAB2(SCH_1):PVCCIN_CPU1
  AG38  PVCCIN_CPU1    VCCIN<266>  @BASEBOARD_FAB2_LIB.BASEBOARD_FAB2(SCH_1):PVCCIN_CPU1
  AG40  PVCCIN_CPU1    VCCIN<265>  @BASEBOARD_FAB2_LIB.BASEBOARD_FAB2(SCH_1):PVCCIN_CPU1
  AG42  PVCCIN_CPU1    VCCIN<264>  @BASEBOARD_FAB2_LIB.BASEBOARD_FAB2(SCH_1):PVCCIN_CPU1
  AH37  PVCCIN_CPU1    VCCIN<263>  @BASEBOARD_FAB2_LIB.BASEBOARD_FAB2(SCH_1):PVCCIN_CPU1
  AH39  PVCCIN_CPU1    VCCIN<262>  @BASEBOARD_FAB2_LIB.BASEBOARD_FAB2(SCH_1):PVCCIN_CPU1
  AH41  PVCCIN_CPU1    VCCIN<261>  @BASEBOARD_FAB2_LIB.BASEBOARD_FAB2(SCH_1):PVCCIN_CPU1
  AJ36  PVCCIN_CPU1    VCCIN<260>  @BASEBOARD_FAB2_LIB.BASEBOARD_FAB2(SCH_1):PVCCIN_CPU1
  AK35  PVCCIN_CPU1    VCCIN<259>  @BASEBOARD_FAB2_LIB.BASEBOARD_FAB2(SCH_1):PVCCIN_CPU1
  AK45  PVCCIN_CPU1    VCCIN<258>  @BASEBOARD_FAB2_LIB.BASEBOARD_FAB2(SCH_1):PVCCIN_CPU1
  AK47  PVCCIN_CPU1    VCCIN<257>  @BASEBOARD_FAB2_LIB.BASEBOARD_FAB2(SCH_1):PVCCIN_CPU1
  AK49  PVCCIN_CPU1    VCCIN<256>  @BASEBOARD_FAB2_LIB.BASEBOARD_FAB2(SCH_1):PVCCIN_CPU1
  AK51  PVCCIN_CPU1    VCCIN<255>  @BASEBOARD_FAB2_LIB.BASEBOARD_FAB2(SCH_1):PVCCIN_CPU1
  AK53  PVCCIN_CPU1    VCCIN<254>  @BASEBOARD_FAB2_LIB.BASEBOARD_FAB2(SCH_1):PVCCIN_CPU1
  AL34  PVCCIN_CPU1    VCCIN<253>  @BASEBOARD_FAB2_LIB.BASEBOARD_FAB2(SCH_1):PVCCIN_CPU1
  AL46  PVCCIN_CPU1    VCCIN<252>  @BASEBOARD_FAB2_LIB.BASEBOARD_FAB2(SCH_1):PVCCIN_CPU1
  AL48  PVCCIN_CPU1    VCCIN<251>  @BASEBOARD_FAB2_LIB.BASEBOARD_FAB2(SCH_1):PVCCIN_CPU1
  AL50  PVCCIN_CPU1    VCCIN<250>  @BASEBOARD_FAB2_LIB.BASEBOARD_FAB2(SCH_1):PVCCIN_CPU1
  AL52  PVCCIN_CPU1    VCCIN<249>  @BASEBOARD_FAB2_LIB.BASEBOARD_FAB2(SCH_1):PVCCIN_CPU1
  AL54  PVCCIN_CPU1    VCCIN<248>  @BASEBOARD_FAB2_LIB.BASEBOARD_FAB2(SCH_1):PVCCIN_CPU1
  AM33  PVCCIN_CPU1    VCCIN<247>  @BASEBOARD_FAB2_LIB.BASEBOARD_FAB2(SCH_1):PVCCIN_CPU1
  AM53  PVCCIN_CPU1    VCCIN<246>  @BASEBOARD_FAB2_LIB.BASEBOARD_FAB2(SCH_1):PVCCIN_CPU1
  AM55  PVCCIN_CPU1    VCCIN<245>  @BASEBOARD_FAB2_LIB.BASEBOARD_FAB2(SCH_1):PVCCIN_CPU1
  AN32  PVCCIN_CPU1    VCCIN<244>  @BASEBOARD_FAB2_LIB.BASEBOARD_FAB2(SCH_1):PVCCIN_CPU1
  AN54  PVCCIN_CPU1    VCCIN<243>  @BASEBOARD_FAB2_LIB.BASEBOARD_FAB2(SCH_1):PVCCIN_CPU1
  AN56  PVCCIN_CPU1    VCCIN<242>  @BASEBOARD_FAB2_LIB.BASEBOARD_FAB2(SCH_1):PVCCIN_CPU1
  AP55  PVCCIN_CPU1    VCCIN<241>  @BASEBOARD_FAB2_LIB.BASEBOARD_FAB2(SCH_1):PVCCIN_CPU1
  AP57  PVCCIN_CPU1    VCCIN<240>  @BASEBOARD_FAB2_LIB.BASEBOARD_FAB2(SCH_1):PVCCIN_CPU1
  AR56  PVCCIN_CPU1    VCCIN<239>  @BASEBOARD_FAB2_LIB.BASEBOARD_FAB2(SCH_1):PVCCIN_CPU1
  AR58  PVCCIN_CPU1    VCCIN<238>  @BASEBOARD_FAB2_LIB.BASEBOARD_FAB2(SCH_1):PVCCIN_CPU1
  AT57  PVCCIN_CPU1    VCCIN<237>  @BASEBOARD_FAB2_LIB.BASEBOARD_FAB2(SCH_1):PVCCIN_CPU1
  AT59  PVCCIN_CPU1    VCCIN<236>  @BASEBOARD_FAB2_LIB.BASEBOARD_FAB2(SCH_1):PVCCIN_CPU1
  AU58  PVCCIN_CPU1    VCCIN<235>  @BASEBOARD_FAB2_LIB.BASEBOARD_FAB2(SCH_1):PVCCIN_CPU1
  AU60  PVCCIN_CPU1    VCCIN<234>  @BASEBOARD_FAB2_LIB.BASEBOARD_FAB2(SCH_1):PVCCIN_CPU1
  AV59  PVCCIN_CPU1    VCCIN<233>  @BASEBOARD_FAB2_LIB.BASEBOARD_FAB2(SCH_1):PVCCIN_CPU1
  AV61  PVCCIN_CPU1    VCCIN<232>  @BASEBOARD_FAB2_LIB.BASEBOARD_FAB2(SCH_1):PVCCIN_CPU1
  AW60  PVCCIN_CPU1    VCCIN<231>  @BASEBOARD_FAB2_LIB.BASEBOARD_FAB2(SCH_1):PVCCIN_CPU1
  AY61  PVCCIN_CPU1    VCCIN<230>  @BASEBOARD_FAB2_LIB.BASEBOARD_FAB2(SCH_1):PVCCIN_CPU1
  BA60  PVCCIN_CPU1    VCCIN<229>  @BASEBOARD_FAB2_LIB.BASEBOARD_FAB2(SCH_1):PVCCIN_CPU1
  BB61  PVCCIN_CPU1    VCCIN<228>  @BASEBOARD_FAB2_LIB.BASEBOARD_FAB2(SCH_1):PVCCIN_CPU1
  BB85  PVCCIN_CPU1    VCCIN<227>  @BASEBOARD_FAB2_LIB.BASEBOARD_FAB2(SCH_1):PVCCIN_CPU1
  BC60  PVCCIN_CPU1    VCCIN<226>  @BASEBOARD_FAB2_LIB.BASEBOARD_FAB2(SCH_1):PVCCIN_CPU1
  BC62  PVCCIN_CPU1    VCCIN<225>  @BASEBOARD_FAB2_LIB.BASEBOARD_FAB2(SCH_1):PVCCIN_CPU1
  BC84  PVCCIN_CPU1    VCCIN<224>  @BASEBOARD_FAB2_LIB.BASEBOARD_FAB2(SCH_1):PVCCIN_CPU1
  BD61  PVCCIN_CPU1    VCCIN<223>  @BASEBOARD_FAB2_LIB.BASEBOARD_FAB2(SCH_1):PVCCIN_CPU1
  BD73  PVCCIN_CPU1    VCCIN<222>  @BASEBOARD_FAB2_LIB.BASEBOARD_FAB2(SCH_1):PVCCIN_CPU1
  BD75  PVCCIN_CPU1    VCCIN<221>  @BASEBOARD_FAB2_LIB.BASEBOARD_FAB2(SCH_1):PVCCIN_CPU1
  BD77  PVCCIN_CPU1    VCCIN<220>  @BASEBOARD_FAB2_LIB.BASEBOARD_FAB2(SCH_1):PVCCIN_CPU1
  BD79  PVCCIN_CPU1    VCCIN<219>  @BASEBOARD_FAB2_LIB.BASEBOARD_FAB2(SCH_1):PVCCIN_CPU1
  BD81  PVCCIN_CPU1    VCCIN<218>  @BASEBOARD_FAB2_LIB.BASEBOARD_FAB2(SCH_1):PVCCIN_CPU1
  BD83  PVCCIN_CPU1    VCCIN<217>  @BASEBOARD_FAB2_LIB.BASEBOARD_FAB2(SCH_1):PVCCIN_CPU1
  BD85  PVCCIN_CPU1    VCCIN<216>  @BASEBOARD_FAB2_LIB.BASEBOARD_FAB2(SCH_1):PVCCIN_CPU1
  BE60  PVCCIN_CPU1    VCCIN<215>  @BASEBOARD_FAB2_LIB.BASEBOARD_FAB2(SCH_1):PVCCIN_CPU1
  BE62  PVCCIN_CPU1    VCCIN<214>  @BASEBOARD_FAB2_LIB.BASEBOARD_FAB2(SCH_1):PVCCIN_CPU1
  BE72  PVCCIN_CPU1    VCCIN<213>  @BASEBOARD_FAB2_LIB.BASEBOARD_FAB2(SCH_1):PVCCIN_CPU1
  BE74  PVCCIN_CPU1    VCCIN<212>  @BASEBOARD_FAB2_LIB.BASEBOARD_FAB2(SCH_1):PVCCIN_CPU1
  BE76  PVCCIN_CPU1    VCCIN<211>  @BASEBOARD_FAB2_LIB.BASEBOARD_FAB2(SCH_1):PVCCIN_CPU1
  BE78  PVCCIN_CPU1    VCCIN<210>  @BASEBOARD_FAB2_LIB.BASEBOARD_FAB2(SCH_1):PVCCIN_CPU1
  BE80  PVCCIN_CPU1    VCCIN<209>  @BASEBOARD_FAB2_LIB.BASEBOARD_FAB2(SCH_1):PVCCIN_CPU1
  BE82  PVCCIN_CPU1    VCCIN<208>  @BASEBOARD_FAB2_LIB.BASEBOARD_FAB2(SCH_1):PVCCIN_CPU1
  BE84  PVCCIN_CPU1    VCCIN<207>  @BASEBOARD_FAB2_LIB.BASEBOARD_FAB2(SCH_1):PVCCIN_CPU1
  BF61  PVCCIN_CPU1    VCCIN<206>  @BASEBOARD_FAB2_LIB.BASEBOARD_FAB2(SCH_1):PVCCIN_CPU1
  BF73  PVCCIN_CPU1    VCCIN<205>  @BASEBOARD_FAB2_LIB.BASEBOARD_FAB2(SCH_1):PVCCIN_CPU1
  BF75  PVCCIN_CPU1    VCCIN<204>  @BASEBOARD_FAB2_LIB.BASEBOARD_FAB2(SCH_1):PVCCIN_CPU1
  BF77  PVCCIN_CPU1    VCCIN<203>  @BASEBOARD_FAB2_LIB.BASEBOARD_FAB2(SCH_1):PVCCIN_CPU1
  BF79  PVCCIN_CPU1    VCCIN<202>  @BASEBOARD_FAB2_LIB.BASEBOARD_FAB2(SCH_1):PVCCIN_CPU1
  BF81  PVCCIN_CPU1    VCCIN<201>  @BASEBOARD_FAB2_LIB.BASEBOARD_FAB2(SCH_1):PVCCIN_CPU1
  BF83  PVCCIN_CPU1    VCCIN<200>  @BASEBOARD_FAB2_LIB.BASEBOARD_FAB2(SCH_1):PVCCIN_CPU1
  BF85  PVCCIN_CPU1    VCCIN<199>  @BASEBOARD_FAB2_LIB.BASEBOARD_FAB2(SCH_1):PVCCIN_CPU1
  BG60  PVCCIN_CPU1    VCCIN<198>  @BASEBOARD_FAB2_LIB.BASEBOARD_FAB2(SCH_1):PVCCIN_CPU1
  BG62  PVCCIN_CPU1    VCCIN<197>  @BASEBOARD_FAB2_LIB.BASEBOARD_FAB2(SCH_1):PVCCIN_CPU1
  BG64  PVCCIN_CPU1    VCCIN<196>  @BASEBOARD_FAB2_LIB.BASEBOARD_FAB2(SCH_1):PVCCIN_CPU1
  BG66  PVCCIN_CPU1    VCCIN<195>  @BASEBOARD_FAB2_LIB.BASEBOARD_FAB2(SCH_1):PVCCIN_CPU1
  BG68  PVCCIN_CPU1    VCCIN<194>  @BASEBOARD_FAB2_LIB.BASEBOARD_FAB2(SCH_1):PVCCIN_CPU1
  BG70  PVCCIN_CPU1    VCCIN<193>  @BASEBOARD_FAB2_LIB.BASEBOARD_FAB2(SCH_1):PVCCIN_CPU1
  BG84  PVCCIN_CPU1    VCCIN<192>  @BASEBOARD_FAB2_LIB.BASEBOARD_FAB2(SCH_1):PVCCIN_CPU1
  BH61  PVCCIN_CPU1    VCCIN<191>  @BASEBOARD_FAB2_LIB.BASEBOARD_FAB2(SCH_1):PVCCIN_CPU1
  BH63  PVCCIN_CPU1    VCCIN<190>  @BASEBOARD_FAB2_LIB.BASEBOARD_FAB2(SCH_1):PVCCIN_CPU1
  BH65  PVCCIN_CPU1    VCCIN<189>  @BASEBOARD_FAB2_LIB.BASEBOARD_FAB2(SCH_1):PVCCIN_CPU1
  BH67  PVCCIN_CPU1    VCCIN<188>  @BASEBOARD_FAB2_LIB.BASEBOARD_FAB2(SCH_1):PVCCIN_CPU1
  BH69  PVCCIN_CPU1    VCCIN<187>  @BASEBOARD_FAB2_LIB.BASEBOARD_FAB2(SCH_1):PVCCIN_CPU1
  BH71  PVCCIN_CPU1    VCCIN<186>  @BASEBOARD_FAB2_LIB.BASEBOARD_FAB2(SCH_1):PVCCIN_CPU1
  BH73  PVCCIN_CPU1    VCCIN<185>  @BASEBOARD_FAB2_LIB.BASEBOARD_FAB2(SCH_1):PVCCIN_CPU1
  BH75  PVCCIN_CPU1    VCCIN<184>  @BASEBOARD_FAB2_LIB.BASEBOARD_FAB2(SCH_1):PVCCIN_CPU1
  BH77  PVCCIN_CPU1    VCCIN<183>  @BASEBOARD_FAB2_LIB.BASEBOARD_FAB2(SCH_1):PVCCIN_CPU1
  BH79  PVCCIN_CPU1    VCCIN<182>  @BASEBOARD_FAB2_LIB.BASEBOARD_FAB2(SCH_1):PVCCIN_CPU1
  BH81  PVCCIN_CPU1    VCCIN<181>  @BASEBOARD_FAB2_LIB.BASEBOARD_FAB2(SCH_1):PVCCIN_CPU1
  BH83  PVCCIN_CPU1    VCCIN<180>  @BASEBOARD_FAB2_LIB.BASEBOARD_FAB2(SCH_1):PVCCIN_CPU1
  BJ60  PVCCIN_CPU1    VCCIN<179>  @BASEBOARD_FAB2_LIB.BASEBOARD_FAB2(SCH_1):PVCCIN_CPU1
  BJ62  PVCCIN_CPU1    VCCIN<178>  @BASEBOARD_FAB2_LIB.BASEBOARD_FAB2(SCH_1):PVCCIN_CPU1
  BJ64  PVCCIN_CPU1    VCCIN<177>  @BASEBOARD_FAB2_LIB.BASEBOARD_FAB2(SCH_1):PVCCIN_CPU1
  BJ66  PVCCIN_CPU1    VCCIN<176>  @BASEBOARD_FAB2_LIB.BASEBOARD_FAB2(SCH_1):PVCCIN_CPU1
  BJ68  PVCCIN_CPU1    VCCIN<175>  @BASEBOARD_FAB2_LIB.BASEBOARD_FAB2(SCH_1):PVCCIN_CPU1
  BJ70  PVCCIN_CPU1    VCCIN<174>  @BASEBOARD_FAB2_LIB.BASEBOARD_FAB2(SCH_1):PVCCIN_CPU1
  BJ72  PVCCIN_CPU1    VCCIN<173>  @BASEBOARD_FAB2_LIB.BASEBOARD_FAB2(SCH_1):PVCCIN_CPU1
  BJ74  PVCCIN_CPU1    VCCIN<172>  @BASEBOARD_FAB2_LIB.BASEBOARD_FAB2(SCH_1):PVCCIN_CPU1
  BJ76  PVCCIN_CPU1    VCCIN<171>  @BASEBOARD_FAB2_LIB.BASEBOARD_FAB2(SCH_1):PVCCIN_CPU1
  BJ78  PVCCIN_CPU1    VCCIN<170>  @BASEBOARD_FAB2_LIB.BASEBOARD_FAB2(SCH_1):PVCCIN_CPU1
  BJ80  PVCCIN_CPU1    VCCIN<169>  @BASEBOARD_FAB2_LIB.BASEBOARD_FAB2(SCH_1):PVCCIN_CPU1
  BJ82  PVCCIN_CPU1    VCCIN<168>  @BASEBOARD_FAB2_LIB.BASEBOARD_FAB2(SCH_1):PVCCIN_CPU1
  BJ84  PVCCIN_CPU1    VCCIN<167>  @BASEBOARD_FAB2_LIB.BASEBOARD_FAB2(SCH_1):PVCCIN_CPU1
  BK61  PVCCIN_CPU1    VCCIN<166>  @BASEBOARD_FAB2_LIB.BASEBOARD_FAB2(SCH_1):PVCCIN_CPU1
  BK63  PVCCIN_CPU1    VCCIN<165>  @BASEBOARD_FAB2_LIB.BASEBOARD_FAB2(SCH_1):PVCCIN_CPU1
  BK65  PVCCIN_CPU1    VCCIN<164>  @BASEBOARD_FAB2_LIB.BASEBOARD_FAB2(SCH_1):PVCCIN_CPU1
  BK67  PVCCIN_CPU1    VCCIN<163>  @BASEBOARD_FAB2_LIB.BASEBOARD_FAB2(SCH_1):PVCCIN_CPU1
  BK69  PVCCIN_CPU1    VCCIN<162>  @BASEBOARD_FAB2_LIB.BASEBOARD_FAB2(SCH_1):PVCCIN_CPU1
  BK71  PVCCIN_CPU1    VCCIN<161>  @BASEBOARD_FAB2_LIB.BASEBOARD_FAB2(SCH_1):PVCCIN_CPU1
  BK73  PVCCIN_CPU1    VCCIN<160>  @BASEBOARD_FAB2_LIB.BASEBOARD_FAB2(SCH_1):PVCCIN_CPU1
  BK75  PVCCIN_CPU1    VCCIN<159>  @BASEBOARD_FAB2_LIB.BASEBOARD_FAB2(SCH_1):PVCCIN_CPU1
  BK77  PVCCIN_CPU1    VCCIN<158>  @BASEBOARD_FAB2_LIB.BASEBOARD_FAB2(SCH_1):PVCCIN_CPU1
  BK79  PVCCIN_CPU1    VCCIN<157>  @BASEBOARD_FAB2_LIB.BASEBOARD_FAB2(SCH_1):PVCCIN_CPU1
  BK81  PVCCIN_CPU1    VCCIN<156>  @BASEBOARD_FAB2_LIB.BASEBOARD_FAB2(SCH_1):PVCCIN_CPU1
  BK83  PVCCIN_CPU1    VCCIN<155>  @BASEBOARD_FAB2_LIB.BASEBOARD_FAB2(SCH_1):PVCCIN_CPU1
  BL60  PVCCIN_CPU1    VCCIN<154>  @BASEBOARD_FAB2_LIB.BASEBOARD_FAB2(SCH_1):PVCCIN_CPU1
  BL62  PVCCIN_CPU1    VCCIN<153>  @BASEBOARD_FAB2_LIB.BASEBOARD_FAB2(SCH_1):PVCCIN_CPU1
  BL84  PVCCIN_CPU1    VCCIN<152>  @BASEBOARD_FAB2_LIB.BASEBOARD_FAB2(SCH_1):PVCCIN_CPU1
  BM61  PVCCIN_CPU1    VCCIN<151>  @BASEBOARD_FAB2_LIB.BASEBOARD_FAB2(SCH_1):PVCCIN_CPU1
  BM63  PVCCIN_CPU1    VCCIN<150>  @BASEBOARD_FAB2_LIB.BASEBOARD_FAB2(SCH_1):PVCCIN_CPU1
  BM65  PVCCIN_CPU1    VCCIN<149>  @BASEBOARD_FAB2_LIB.BASEBOARD_FAB2(SCH_1):PVCCIN_CPU1
  BM67  PVCCIN_CPU1    VCCIN<148>  @BASEBOARD_FAB2_LIB.BASEBOARD_FAB2(SCH_1):PVCCIN_CPU1
  BM69  PVCCIN_CPU1    VCCIN<147>  @BASEBOARD_FAB2_LIB.BASEBOARD_FAB2(SCH_1):PVCCIN_CPU1
  BM71  PVCCIN_CPU1    VCCIN<146>  @BASEBOARD_FAB2_LIB.BASEBOARD_FAB2(SCH_1):PVCCIN_CPU1
  BM73  PVCCIN_CPU1    VCCIN<145>  @BASEBOARD_FAB2_LIB.BASEBOARD_FAB2(SCH_1):PVCCIN_CPU1
  BM75  PVCCIN_CPU1    VCCIN<144>  @BASEBOARD_FAB2_LIB.BASEBOARD_FAB2(SCH_1):PVCCIN_CPU1
  BM77  PVCCIN_CPU1    VCCIN<143>  @BASEBOARD_FAB2_LIB.BASEBOARD_FAB2(SCH_1):PVCCIN_CPU1
  BM79  PVCCIN_CPU1    VCCIN<142>  @BASEBOARD_FAB2_LIB.BASEBOARD_FAB2(SCH_1):PVCCIN_CPU1
  BM81  PVCCIN_CPU1    VCCIN<141>  @BASEBOARD_FAB2_LIB.BASEBOARD_FAB2(SCH_1):PVCCIN_CPU1
  BM83  PVCCIN_CPU1    VCCIN<140>  @BASEBOARD_FAB2_LIB.BASEBOARD_FAB2(SCH_1):PVCCIN_CPU1
  BN60  PVCCIN_CPU1    VCCIN<139>  @BASEBOARD_FAB2_LIB.BASEBOARD_FAB2(SCH_1):PVCCIN_CPU1
  BN62  PVCCIN_CPU1    VCCIN<138>  @BASEBOARD_FAB2_LIB.BASEBOARD_FAB2(SCH_1):PVCCIN_CPU1
  BN64  PVCCIN_CPU1    VCCIN<137>  @BASEBOARD_FAB2_LIB.BASEBOARD_FAB2(SCH_1):PVCCIN_CPU1
  BN66  PVCCIN_CPU1    VCCIN<136>  @BASEBOARD_FAB2_LIB.BASEBOARD_FAB2(SCH_1):PVCCIN_CPU1
  BN68  PVCCIN_CPU1    VCCIN<135>  @BASEBOARD_FAB2_LIB.BASEBOARD_FAB2(SCH_1):PVCCIN_CPU1
  BN70  PVCCIN_CPU1    VCCIN<134>  @BASEBOARD_FAB2_LIB.BASEBOARD_FAB2(SCH_1):PVCCIN_CPU1
  BN72  PVCCIN_CPU1    VCCIN<133>  @BASEBOARD_FAB2_LIB.BASEBOARD_FAB2(SCH_1):PVCCIN_CPU1
  BN74  PVCCIN_CPU1    VCCIN<132>  @BASEBOARD_FAB2_LIB.BASEBOARD_FAB2(SCH_1):PVCCIN_CPU1
  BN76  PVCCIN_CPU1    VCCIN<131>  @BASEBOARD_FAB2_LIB.BASEBOARD_FAB2(SCH_1):PVCCIN_CPU1
  BN78  PVCCIN_CPU1    VCCIN<130>  @BASEBOARD_FAB2_LIB.BASEBOARD_FAB2(SCH_1):PVCCIN_CPU1

SKX_EXT_B_BGA1  I10  U2D1   [SKX_EXT_B_BGA1-IC,TBD]
  AW20  TP_CPU1_TEST_9  TEST_9  @BASEBOARD_FAB2_LIB.BASEBOARD_FAB2(SCH_1):TP_CPU1_TEST_9
  AW16  TP_CPU1_TEST_8  TEST_8  @BASEBOARD_FAB2_LIB.BASEBOARD_FAB2(SCH_1):TP_CPU1_TEST_8
  AU18  TP_CPU1_TEST_7  TEST_7  @BASEBOARD_FAB2_LIB.BASEBOARD_FAB2(SCH_1):TP_CPU1_TEST_7
  AR16  TP_CPU1_TEST_6  TEST_6  @BASEBOARD_FAB2_LIB.BASEBOARD_FAB2(SCH_1):TP_CPU1_TEST_6
  AW22  TP_CPU1_TEST_10  TEST_10  @BASEBOARD_FAB2_LIB.BASEBOARD_FAB2(SCH_1):TP_CPU1_TEST_10
  CH25  TP_CPU1_RSVD_91  RSVD<91>  @BASEBOARD_FAB2_LIB.BASEBOARD_FAB2(SCH_1):TP_CPU1_RSVD_91
  CH77  TP_CPU1_RSVD_90  RSVD<90>  @BASEBOARD_FAB2_LIB.BASEBOARD_FAB2(SCH_1):TP_CPU1_RSVD_90
  CK19  TP_CPU1_RSVD_85  RSVD<85>  @BASEBOARD_FAB2_LIB.BASEBOARD_FAB2(SCH_1):TP_CPU1_RSVD_85
  CK77  TP_CPU1_RSVD_82  RSVD<82>  @BASEBOARD_FAB2_LIB.BASEBOARD_FAB2(SCH_1):TP_CPU1_RSVD_82
  CJ20  PVCCMCP_CPU1   RSVD<89>  @BASEBOARD_FAB2_LIB.BASEBOARD_FAB2(SCH_1):PVCCMCP_CPU1
  CJ22  PVCCMCP_CPU1   RSVD<88>  @BASEBOARD_FAB2_LIB.BASEBOARD_FAB2(SCH_1):PVCCMCP_CPU1
  CJ24  PVCCMCP_CPU1   RSVD<87>  @BASEBOARD_FAB2_LIB.BASEBOARD_FAB2(SCH_1):PVCCMCP_CPU1
  CJ26  PVCCMCP_CPU1   RSVD<86>  @BASEBOARD_FAB2_LIB.BASEBOARD_FAB2(SCH_1):PVCCMCP_CPU1
  CK23  PVCCMCP_CPU1   RSVD<84>  @BASEBOARD_FAB2_LIB.BASEBOARD_FAB2(SCH_1):PVCCMCP_CPU1
  CK25  PVCCMCP_CPU1   RSVD<83>  @BASEBOARD_FAB2_LIB.BASEBOARD_FAB2(SCH_1):PVCCMCP_CPU1
  CL24  PVCCMCP_CPU1   RSVD<81>  @BASEBOARD_FAB2_LIB.BASEBOARD_FAB2(SCH_1):PVCCMCP_CPU1

SKX_EXT_B_BGA1  I9   U2D1   [SKX_EXT_B_BGA1-IC,TBD]
  CG10  TP_CPU1_RSVD_99  RSVD<99>  @BASEBOARD_FAB2_LIB.BASEBOARD_FAB2(SCH_1):TP_CPU1_RSVD_99
  CG24  TP_CPU1_RSVD_97  RSVD<97>  @BASEBOARD_FAB2_LIB.BASEBOARD_FAB2(SCH_1):TP_CPU1_RSVD_97
  CG78  TP_CPU1_RSVD_95  RSVD<95>  @BASEBOARD_FAB2_LIB.BASEBOARD_FAB2(SCH_1):TP_CPU1_RSVD_95
  CG82  TP_CPU1_RSVD_94  RSVD<94>  @BASEBOARD_FAB2_LIB.BASEBOARD_FAB2(SCH_1):TP_CPU1_RSVD_94
  AY83  TP_CPU1_RSVD_255  RSVD<255>  @BASEBOARD_FAB2_LIB.BASEBOARD_FAB2(SCH_1):TP_CPU1_RSVD_255
  BA78  TP_CPU1_RSVD_171  RSVD<171>  @BASEBOARD_FAB2_LIB.BASEBOARD_FAB2(SCH_1):TP_CPU1_RSVD_171
  BA82  TP_CPU1_RSVD_170  RSVD<170>  @BASEBOARD_FAB2_LIB.BASEBOARD_FAB2(SCH_1):TP_CPU1_RSVD_170
  BB13  TP_CPU1_RSVD_169  RSVD<169>  @BASEBOARD_FAB2_LIB.BASEBOARD_FAB2(SCH_1):TP_CPU1_RSVD_169
  BB15  TP_CPU1_RSVD_168  RSVD<168>  @BASEBOARD_FAB2_LIB.BASEBOARD_FAB2(SCH_1):TP_CPU1_RSVD_168
  BB17  TP_CPU1_RSVD_167  RSVD<167>  @BASEBOARD_FAB2_LIB.BASEBOARD_FAB2(SCH_1):TP_CPU1_RSVD_167
  BB21  TP_CPU1_RSVD_166  RSVD<166>  @BASEBOARD_FAB2_LIB.BASEBOARD_FAB2(SCH_1):TP_CPU1_RSVD_166
  BB65  TP_CPU1_RSVD_164  RSVD<164>  @BASEBOARD_FAB2_LIB.BASEBOARD_FAB2(SCH_1):TP_CPU1_RSVD_164
  BB67  TP_CPU1_RSVD_163  RSVD<163>  @BASEBOARD_FAB2_LIB.BASEBOARD_FAB2(SCH_1):TP_CPU1_RSVD_163
  BC14  TP_CPU1_RSVD_162  RSVD<162>  @BASEBOARD_FAB2_LIB.BASEBOARD_FAB2(SCH_1):TP_CPU1_RSVD_162
  BC18  TP_CPU1_RSVD_161  RSVD<161>  @BASEBOARD_FAB2_LIB.BASEBOARD_FAB2(SCH_1):TP_CPU1_RSVD_161
  BC20  TP_CPU1_RSVD_160  RSVD<160>  @BASEBOARD_FAB2_LIB.BASEBOARD_FAB2(SCH_1):TP_CPU1_RSVD_160
  BC22  TP_CPU1_RSVD_159  RSVD<159>  @BASEBOARD_FAB2_LIB.BASEBOARD_FAB2(SCH_1):TP_CPU1_RSVD_159
  BC64  TP_CPU1_RSVD_158  RSVD<158>  @BASEBOARD_FAB2_LIB.BASEBOARD_FAB2(SCH_1):TP_CPU1_RSVD_158
  BC66  TP_CPU1_RSVD_157  RSVD<157>  @BASEBOARD_FAB2_LIB.BASEBOARD_FAB2(SCH_1):TP_CPU1_RSVD_157
  BC68  TP_CPU1_RSVD_156  RSVD<156>  @BASEBOARD_FAB2_LIB.BASEBOARD_FAB2(SCH_1):TP_CPU1_RSVD_156
  BD17  TP_CPU1_RSVD_155  RSVD<155>  @BASEBOARD_FAB2_LIB.BASEBOARD_FAB2(SCH_1):TP_CPU1_RSVD_155
  BD19  TP_CPU1_RSVD_154  RSVD<154>  @BASEBOARD_FAB2_LIB.BASEBOARD_FAB2(SCH_1):TP_CPU1_RSVD_154
  BD65  TP_CPU1_RSVD_152  RSVD<152>  @BASEBOARD_FAB2_LIB.BASEBOARD_FAB2(SCH_1):TP_CPU1_RSVD_152
  BD67  TP_CPU1_RSVD_151  RSVD<151>  @BASEBOARD_FAB2_LIB.BASEBOARD_FAB2(SCH_1):TP_CPU1_RSVD_151
  BD69  TP_CPU1_RSVD_150  RSVD<150>  @BASEBOARD_FAB2_LIB.BASEBOARD_FAB2(SCH_1):TP_CPU1_RSVD_150
  BE18  TP_CPU1_RSVD_149  RSVD<149>  @BASEBOARD_FAB2_LIB.BASEBOARD_FAB2(SCH_1):TP_CPU1_RSVD_149
  BE20  TP_CPU1_RSVD_148  RSVD<148>  @BASEBOARD_FAB2_LIB.BASEBOARD_FAB2(SCH_1):TP_CPU1_RSVD_148
  BE22  TP_CPU1_RSVD_147  RSVD<147>  @BASEBOARD_FAB2_LIB.BASEBOARD_FAB2(SCH_1):TP_CPU1_RSVD_147
  BF21  TP_CPU1_RSVD_146  RSVD<146>  @BASEBOARD_FAB2_LIB.BASEBOARD_FAB2(SCH_1):TP_CPU1_RSVD_146
  BG18  TP_CPU1_RSVD_145  RSVD<145>  @BASEBOARD_FAB2_LIB.BASEBOARD_FAB2(SCH_1):TP_CPU1_RSVD_145
  BG20  TP_CPU1_RSVD_144  RSVD<144>  @BASEBOARD_FAB2_LIB.BASEBOARD_FAB2(SCH_1):TP_CPU1_RSVD_144
  BV23  TP_CPU1_RSVD_124  RSVD<124>  @BASEBOARD_FAB2_LIB.BASEBOARD_FAB2(SCH_1):TP_CPU1_RSVD_124
  BW10  TP_CPU1_RSVD_123  RSVD<123>  @BASEBOARD_FAB2_LIB.BASEBOARD_FAB2(SCH_1):TP_CPU1_RSVD_123
  BW22  TP_CPU1_RSVD_121  RSVD<121>  @BASEBOARD_FAB2_LIB.BASEBOARD_FAB2(SCH_1):TP_CPU1_RSVD_121
  BY25  TP_CPU1_RSVD_119  RSVD<119>  @BASEBOARD_FAB2_LIB.BASEBOARD_FAB2(SCH_1):TP_CPU1_RSVD_119
  CA24  TP_CPU1_RSVD_117  RSVD<117>  @BASEBOARD_FAB2_LIB.BASEBOARD_FAB2(SCH_1):TP_CPU1_RSVD_117
  CB25  TP_CPU1_RSVD_114  RSVD<114>  @BASEBOARD_FAB2_LIB.BASEBOARD_FAB2(SCH_1):TP_CPU1_RSVD_114
  CB5  TP_CPU1_RSVD_113  RSVD<113>  @BASEBOARD_FAB2_LIB.BASEBOARD_FAB2(SCH_1):TP_CPU1_RSVD_113
  CC6  TP_CPU1_RSVD_111  RSVD<111>  @BASEBOARD_FAB2_LIB.BASEBOARD_FAB2(SCH_1):TP_CPU1_RSVD_111
  CD25  TP_CPU1_RSVD_108  RSVD<108>  @BASEBOARD_FAB2_LIB.BASEBOARD_FAB2(SCH_1):TP_CPU1_RSVD_108
  CE78  TP_CPU1_RSVD_106  RSVD<106>  @BASEBOARD_FAB2_LIB.BASEBOARD_FAB2(SCH_1):TP_CPU1_RSVD_106
  CE80  TP_CPU1_RSVD_105  RSVD<105>  @BASEBOARD_FAB2_LIB.BASEBOARD_FAB2(SCH_1):TP_CPU1_RSVD_105
  CF79  TP_CPU1_RSVD_101  RSVD<101>  @BASEBOARD_FAB2_LIB.BASEBOARD_FAB2(SCH_1):TP_CPU1_RSVD_101
  CF81  TP_CPU1_RSVD_100  RSVD<100>  @BASEBOARD_FAB2_LIB.BASEBOARD_FAB2(SCH_1):TP_CPU1_RSVD_100
  BH19  PVCCMCP_CPU1   RSVD<143>  @BASEBOARD_FAB2_LIB.BASEBOARD_FAB2(SCH_1):PVCCMCP_CPU1
  BJ16  PVCCMCP_CPU1   RSVD<142>  @BASEBOARD_FAB2_LIB.BASEBOARD_FAB2(SCH_1):PVCCMCP_CPU1
  BJ18  PVCCMCP_CPU1   RSVD<141>  @BASEBOARD_FAB2_LIB.BASEBOARD_FAB2(SCH_1):PVCCMCP_CPU1
  BJ20  PVCCMCP_CPU1   RSVD<140>  @BASEBOARD_FAB2_LIB.BASEBOARD_FAB2(SCH_1):PVCCMCP_CPU1
  BK17  PVCCMCP_CPU1   RSVD<139>  @BASEBOARD_FAB2_LIB.BASEBOARD_FAB2(SCH_1):PVCCMCP_CPU1
  BL18  PVCCMCP_CPU1   RSVD<138>  @BASEBOARD_FAB2_LIB.BASEBOARD_FAB2(SCH_1):PVCCMCP_CPU1
  BL20  PVCCMCP_CPU1   RSVD<137>  @BASEBOARD_FAB2_LIB.BASEBOARD_FAB2(SCH_1):PVCCMCP_CPU1
  BM17  PVCCMCP_CPU1   RSVD<136>  @BASEBOARD_FAB2_LIB.BASEBOARD_FAB2(SCH_1):PVCCMCP_CPU1
  BM19  PVCCMCP_CPU1   RSVD<135>  @BASEBOARD_FAB2_LIB.BASEBOARD_FAB2(SCH_1):PVCCMCP_CPU1
  BN18  PVCCMCP_CPU1   RSVD<134>  @BASEBOARD_FAB2_LIB.BASEBOARD_FAB2(SCH_1):PVCCMCP_CPU1
  BP17  PVCCMCP_CPU1   RSVD<133>  @BASEBOARD_FAB2_LIB.BASEBOARD_FAB2(SCH_1):PVCCMCP_CPU1
  BP21  PVCCMCP_CPU1   RSVD<132>  @BASEBOARD_FAB2_LIB.BASEBOARD_FAB2(SCH_1):PVCCMCP_CPU1
  BR22  PVCCMCP_CPU1   RSVD<131>  @BASEBOARD_FAB2_LIB.BASEBOARD_FAB2(SCH_1):PVCCMCP_CPU1
  BR24  PVCCMCP_CPU1   RSVD<130>  @BASEBOARD_FAB2_LIB.BASEBOARD_FAB2(SCH_1):PVCCMCP_CPU1
  BU18  PVCCMCP_CPU1   RSVD<129>  @BASEBOARD_FAB2_LIB.BASEBOARD_FAB2(SCH_1):PVCCMCP_CPU1
  BU20  PVCCMCP_CPU1   RSVD<128>  @BASEBOARD_FAB2_LIB.BASEBOARD_FAB2(SCH_1):PVCCMCP_CPU1
  BU22  PVCCMCP_CPU1   RSVD<127>  @BASEBOARD_FAB2_LIB.BASEBOARD_FAB2(SCH_1):PVCCMCP_CPU1
  BV19  PVCCMCP_CPU1   RSVD<126>  @BASEBOARD_FAB2_LIB.BASEBOARD_FAB2(SCH_1):PVCCMCP_CPU1
  BV21  PVCCMCP_CPU1   RSVD<125>  @BASEBOARD_FAB2_LIB.BASEBOARD_FAB2(SCH_1):PVCCMCP_CPU1
  BW20  PVCCMCP_CPU1   RSVD<122>  @BASEBOARD_FAB2_LIB.BASEBOARD_FAB2(SCH_1):PVCCMCP_CPU1
  BY19  PVCCMCP_CPU1   RSVD<120>  @BASEBOARD_FAB2_LIB.BASEBOARD_FAB2(SCH_1):PVCCMCP_CPU1
  CA22  PVCCMCP_CPU1   RSVD<118>  @BASEBOARD_FAB2_LIB.BASEBOARD_FAB2(SCH_1):PVCCMCP_CPU1
  CB19  PVCCMCP_CPU1   RSVD<116>  @BASEBOARD_FAB2_LIB.BASEBOARD_FAB2(SCH_1):PVCCMCP_CPU1
  CB21  PVCCMCP_CPU1   RSVD<115>  @BASEBOARD_FAB2_LIB.BASEBOARD_FAB2(SCH_1):PVCCMCP_CPU1
  CC20  PVCCMCP_CPU1   RSVD<112>  @BASEBOARD_FAB2_LIB.BASEBOARD_FAB2(SCH_1):PVCCMCP_CPU1
  CD19  PVCCMCP_CPU1   RSVD<110>  @BASEBOARD_FAB2_LIB.BASEBOARD_FAB2(SCH_1):PVCCMCP_CPU1
  CD21  PVCCMCP_CPU1   RSVD<109>  @BASEBOARD_FAB2_LIB.BASEBOARD_FAB2(SCH_1):PVCCMCP_CPU1
  CE22  PVCCMCP_CPU1   RSVD<107>  @BASEBOARD_FAB2_LIB.BASEBOARD_FAB2(SCH_1):PVCCMCP_CPU1
  CF19  PVCCMCP_CPU1   RSVD<104>  @BASEBOARD_FAB2_LIB.BASEBOARD_FAB2(SCH_1):PVCCMCP_CPU1
  CF21  PVCCMCP_CPU1   RSVD<103>  @BASEBOARD_FAB2_LIB.BASEBOARD_FAB2(SCH_1):PVCCMCP_CPU1
  CF23  PVCCMCP_CPU1   RSVD<102>  @BASEBOARD_FAB2_LIB.BASEBOARD_FAB2(SCH_1):PVCCMCP_CPU1
  CG20  PVCCMCP_CPU1   RSVD<98>  @BASEBOARD_FAB2_LIB.BASEBOARD_FAB2(SCH_1):PVCCMCP_CPU1
  CG26  PVCCMCP_CPU1   RSVD<96>  @BASEBOARD_FAB2_LIB.BASEBOARD_FAB2(SCH_1):PVCCMCP_CPU1
  CH21  PVCCMCP_CPU1   RSVD<93>  @BASEBOARD_FAB2_LIB.BASEBOARD_FAB2(SCH_1):PVCCMCP_CPU1
  CH23  PVCCMCP_CPU1   RSVD<92>  @BASEBOARD_FAB2_LIB.BASEBOARD_FAB2(SCH_1):PVCCMCP_CPU1
  BD25  CLK_100M_CPU1_RC_REFCLK1_DP  RSVD<153>  @BASEBOARD_FAB2_LIB.BASEBOARD_FAB2(SCH_1):CLK_100M_CPU1_RC_REFCLK1_DP
  BB25  CLK_100M_CPU1_RC_REFCLK1_DN  RSVD<165>  @BASEBOARD_FAB2_LIB.BASEBOARD_FAB2(SCH_1):CLK_100M_CPU1_RC_REFCLK1_DN

SKX_EXT_B_BGA1  I1   U2D1   [SKX_EXT_B_BGA1-IC,TBD]
  CC12  TP_CPU1_UPI2_RSVD_DT21  UPI2_TX_DN<19>  @BASEBOARD_FAB2_LIB.BASEBOARD_FAB2(SCH_1):TP_CPU1_UPI2_RSVD_DT21
  CA12  TP_CPU1_UPI2_RSVD_DP21  UPI2_TX_DP<19>  @BASEBOARD_FAB2_LIB.BASEBOARD_FAB2(SCH_1):TP_CPU1_UPI2_RSVD_DP21
  CB11  TP_CPU1_UPI2_RSVD_DN20  UPI2_TX_DP<18>  @BASEBOARD_FAB2_LIB.BASEBOARD_FAB2(SCH_1):TP_CPU1_UPI2_RSVD_DN20
  CC10  TP_CPU1_UPI2_RSVD_DM21  UPI2_TX_DN<18>  @BASEBOARD_FAB2_LIB.BASEBOARD_FAB2(SCH_1):TP_CPU1_UPI2_RSVD_DM21
  CE12  TP_CPU1_UPI2_RSVD_DL20  UPI2_TX_DN<17>  @BASEBOARD_FAB2_LIB.BASEBOARD_FAB2(SCH_1):TP_CPU1_UPI2_RSVD_DL20
  CD11  TP_CPU1_UPI2_RSVD_DK19  UPI2_TX_DP<17>  @BASEBOARD_FAB2_LIB.BASEBOARD_FAB2(SCH_1):TP_CPU1_UPI2_RSVD_DK19
  CJ14  TP_CPU1_UPI2_RSVD_DK17  UPI2_TX_DN<14>  @BASEBOARD_FAB2_LIB.BASEBOARD_FAB2(SCH_1):TP_CPU1_UPI2_RSVD_DK17
  CF11  TP_CPU1_UPI2_RSVD_DJ20  UPI2_TX_DP<16>  @BASEBOARD_FAB2_LIB.BASEBOARD_FAB2(SCH_1):TP_CPU1_UPI2_RSVD_DJ20
  CG12  TP_CPU1_UPI2_RSVD_DJ18  UPI2_TX_DP<15>  @BASEBOARD_FAB2_LIB.BASEBOARD_FAB2(SCH_1):TP_CPU1_UPI2_RSVD_DJ18
  CF13  TP_CPU1_UPI2_RSVD_DH19  UPI2_TX_DN<15>  @BASEBOARD_FAB2_LIB.BASEBOARD_FAB2(SCH_1):TP_CPU1_UPI2_RSVD_DH19
  CH13  TP_CPU1_UPI2_RSVD_DH17  UPI2_TX_DP<14>  @BASEBOARD_FAB2_LIB.BASEBOARD_FAB2(SCH_1):TP_CPU1_UPI2_RSVD_DH17
  CH11  TP_CPU1_UPI2_RSVD_DG20  UPI2_TX_DN<16>  @BASEBOARD_FAB2_LIB.BASEBOARD_FAB2(SCH_1):TP_CPU1_UPI2_RSVD_DG20
  CM13  TP_CPU1_UPI2_RSVD_DG18  UPI2_TX_DN<13>  @BASEBOARD_FAB2_LIB.BASEBOARD_FAB2(SCH_1):TP_CPU1_UPI2_RSVD_DG18
  CK13  TP_CPU1_UPI2_RSVD_DF17  UPI2_TX_DP<13>  @BASEBOARD_FAB2_LIB.BASEBOARD_FAB2(SCH_1):TP_CPU1_UPI2_RSVD_DF17
  CW14  TP_CPU1_UPI2_RSVD_DF15  UPI2_TX_DN<11>  @BASEBOARD_FAB2_LIB.BASEBOARD_FAB2(SCH_1):TP_CPU1_UPI2_RSVD_DF15
  CR14  TP_CPU1_UPI2_RSVD_DE16  UPI2_TX_DP<12>  @BASEBOARD_FAB2_LIB.BASEBOARD_FAB2(SCH_1):TP_CPU1_UPI2_RSVD_DE16
  CU14  TP_CPU1_UPI2_RSVD_DD17  UPI2_TX_DN<12>  @BASEBOARD_FAB2_LIB.BASEBOARD_FAB2(SCH_1):TP_CPU1_UPI2_RSVD_DD17
  CV13  TP_CPU1_UPI2_RSVD_DD15  UPI2_TX_DP<11>  @BASEBOARD_FAB2_LIB.BASEBOARD_FAB2(SCH_1):TP_CPU1_UPI2_RSVD_DD15
  DA16  TP_CPU1_UPI2_RSVD_DC16  UPI2_TX_DN<10>  @BASEBOARD_FAB2_LIB.BASEBOARD_FAB2(SCH_1):TP_CPU1_UPI2_RSVD_DC16
  CW16  TP_CPU1_UPI2_RSVD_DB15  UPI2_TX_DP<10>  @BASEBOARD_FAB2_LIB.BASEBOARD_FAB2(SCH_1):TP_CPU1_UPI2_RSVD_DB15
  DC16  TP_CPU1_UPI2_RSVD_DA16  UPI2_TX_DN<9>  @BASEBOARD_FAB2_LIB.BASEBOARD_FAB2(SCH_1):TP_CPU1_UPI2_RSVD_DA16
  DB15  TP_CPU1_UPI2_RSVD_CW16  UPI2_TX_DP<9>  @BASEBOARD_FAB2_LIB.BASEBOARD_FAB2(SCH_1):TP_CPU1_UPI2_RSVD_CW16
  DF15  TP_CPU1_UPI2_RSVD_CW14  UPI2_TX_DN<8>  @BASEBOARD_FAB2_LIB.BASEBOARD_FAB2(SCH_1):TP_CPU1_UPI2_RSVD_CW14
  DD15  TP_CPU1_UPI2_RSVD_CV13  UPI2_TX_DP<8>  @BASEBOARD_FAB2_LIB.BASEBOARD_FAB2(SCH_1):TP_CPU1_UPI2_RSVD_CV13
  DD17  TP_CPU1_UPI2_RSVD_CU14  UPI2_TX_DN<7>  @BASEBOARD_FAB2_LIB.BASEBOARD_FAB2(SCH_1):TP_CPU1_UPI2_RSVD_CU14
  DE16  TP_CPU1_UPI2_RSVD_CR14  UPI2_TX_DP<7>  @BASEBOARD_FAB2_LIB.BASEBOARD_FAB2(SCH_1):TP_CPU1_UPI2_RSVD_CR14
  DG18  TP_CPU1_UPI2_RSVD_CM13  UPI2_TX_DN<6>  @BASEBOARD_FAB2_LIB.BASEBOARD_FAB2(SCH_1):TP_CPU1_UPI2_RSVD_CM13
  DF17  TP_CPU1_UPI2_RSVD_CK13  UPI2_TX_DP<6>  @BASEBOARD_FAB2_LIB.BASEBOARD_FAB2(SCH_1):TP_CPU1_UPI2_RSVD_CK13
  DK17  TP_CPU1_UPI2_RSVD_CJ14  UPI2_TX_DN<5>  @BASEBOARD_FAB2_LIB.BASEBOARD_FAB2(SCH_1):TP_CPU1_UPI2_RSVD_CJ14
  DH17  TP_CPU1_UPI2_RSVD_CH13  UPI2_TX_DP<5>  @BASEBOARD_FAB2_LIB.BASEBOARD_FAB2(SCH_1):TP_CPU1_UPI2_RSVD_CH13
  DG20  TP_CPU1_UPI2_RSVD_CH11  UPI2_TX_DN<3>  @BASEBOARD_FAB2_LIB.BASEBOARD_FAB2(SCH_1):TP_CPU1_UPI2_RSVD_CH11
  DJ18  TP_CPU1_UPI2_RSVD_CG12  UPI2_TX_DP<4>  @BASEBOARD_FAB2_LIB.BASEBOARD_FAB2(SCH_1):TP_CPU1_UPI2_RSVD_CG12
  DH19  TP_CPU1_UPI2_RSVD_CF13  UPI2_TX_DN<4>  @BASEBOARD_FAB2_LIB.BASEBOARD_FAB2(SCH_1):TP_CPU1_UPI2_RSVD_CF13
  DJ20  TP_CPU1_UPI2_RSVD_CF11  UPI2_TX_DP<3>  @BASEBOARD_FAB2_LIB.BASEBOARD_FAB2(SCH_1):TP_CPU1_UPI2_RSVD_CF11
  DL20  TP_CPU1_UPI2_RSVD_CE12  UPI2_TX_DN<2>  @BASEBOARD_FAB2_LIB.BASEBOARD_FAB2(SCH_1):TP_CPU1_UPI2_RSVD_CE12
  DK19  TP_CPU1_UPI2_RSVD_CD11  UPI2_TX_DP<2>  @BASEBOARD_FAB2_LIB.BASEBOARD_FAB2(SCH_1):TP_CPU1_UPI2_RSVD_CD11
  DT21  TP_CPU1_UPI2_RSVD_CC12  UPI2_TX_DN<0>  @BASEBOARD_FAB2_LIB.BASEBOARD_FAB2(SCH_1):TP_CPU1_UPI2_RSVD_CC12
  DM21  TP_CPU1_UPI2_RSVD_CC10  UPI2_TX_DN<1>  @BASEBOARD_FAB2_LIB.BASEBOARD_FAB2(SCH_1):TP_CPU1_UPI2_RSVD_CC10
  DN20  TP_CPU1_UPI2_RSVD_CB11  UPI2_TX_DP<1>  @BASEBOARD_FAB2_LIB.BASEBOARD_FAB2(SCH_1):TP_CPU1_UPI2_RSVD_CB11
  DP21  TP_CPU1_UPI2_RSVD_CA12  UPI2_TX_DP<0>  @BASEBOARD_FAB2_LIB.BASEBOARD_FAB2(SCH_1):TP_CPU1_UPI2_RSVD_CA12
  CA16  GND            UPI2_RX_DP<19>  @BASEBOARD_FAB2_LIB.BASEBOARD_FAB2(SCH_1):GND
  BY15  GND            UPI2_RX_DP<18>  @BASEBOARD_FAB2_LIB.BASEBOARD_FAB2(SCH_1):GND
  CD17  GND            UPI2_RX_DP<17>  @BASEBOARD_FAB2_LIB.BASEBOARD_FAB2(SCH_1):GND
  CC14  GND            UPI2_RX_DP<16>  @BASEBOARD_FAB2_LIB.BASEBOARD_FAB2(SCH_1):GND
  CF15  GND            UPI2_RX_DP<15>  @BASEBOARD_FAB2_LIB.BASEBOARD_FAB2(SCH_1):GND
  CG16  GND            UPI2_RX_DP<14>  @BASEBOARD_FAB2_LIB.BASEBOARD_FAB2(SCH_1):GND
  CK17  GND            UPI2_RX_DP<13>  @BASEBOARD_FAB2_LIB.BASEBOARD_FAB2(SCH_1):GND
  CJ16  GND            UPI2_RX_DP<12>  @BASEBOARD_FAB2_LIB.BASEBOARD_FAB2(SCH_1):GND
  CM21  GND            UPI2_RX_DP<11>  @BASEBOARD_FAB2_LIB.BASEBOARD_FAB2(SCH_1):GND
  CP19  GND            UPI2_RX_DP<10>  @BASEBOARD_FAB2_LIB.BASEBOARD_FAB2(SCH_1):GND
  CN18  GND            UPI2_RX_DP<9>  @BASEBOARD_FAB2_LIB.BASEBOARD_FAB2(SCH_1):GND
  CR20  GND            UPI2_RX_DP<8>  @BASEBOARD_FAB2_LIB.BASEBOARD_FAB2(SCH_1):GND
  CW18  GND            UPI2_RX_DP<7>  @BASEBOARD_FAB2_LIB.BASEBOARD_FAB2(SCH_1):GND
  CU20  GND            UPI2_RX_DP<6>  @BASEBOARD_FAB2_LIB.BASEBOARD_FAB2(SCH_1):GND
  CY19  GND            UPI2_RX_DP<5>  @BASEBOARD_FAB2_LIB.BASEBOARD_FAB2(SCH_1):GND
  DB19  GND            UPI2_RX_DP<4>  @BASEBOARD_FAB2_LIB.BASEBOARD_FAB2(SCH_1):GND
  DC20  GND            UPI2_RX_DP<3>  @BASEBOARD_FAB2_LIB.BASEBOARD_FAB2(SCH_1):GND
  DA22  GND            UPI2_RX_DP<2>  @BASEBOARD_FAB2_LIB.BASEBOARD_FAB2(SCH_1):GND
  DD21  GND            UPI2_RX_DP<1>  @BASEBOARD_FAB2_LIB.BASEBOARD_FAB2(SCH_1):GND
  DG22  GND            UPI2_RX_DP<0>  @BASEBOARD_FAB2_LIB.BASEBOARD_FAB2(SCH_1):GND
  BY17  GND            UPI2_RX_DN<19>  @BASEBOARD_FAB2_LIB.BASEBOARD_FAB2(SCH_1):GND
  CB15  GND            UPI2_RX_DN<18>  @BASEBOARD_FAB2_LIB.BASEBOARD_FAB2(SCH_1):GND
  CF17  GND            UPI2_RX_DN<17>  @BASEBOARD_FAB2_LIB.BASEBOARD_FAB2(SCH_1):GND
  CD15  GND            UPI2_RX_DN<16>  @BASEBOARD_FAB2_LIB.BASEBOARD_FAB2(SCH_1):GND
  CE16  GND            UPI2_RX_DN<15>  @BASEBOARD_FAB2_LIB.BASEBOARD_FAB2(SCH_1):GND
  CH17  GND            UPI2_RX_DN<14>  @BASEBOARD_FAB2_LIB.BASEBOARD_FAB2(SCH_1):GND
  CJ18  GND            UPI2_RX_DN<13>  @BASEBOARD_FAB2_LIB.BASEBOARD_FAB2(SCH_1):GND
  CL16  GND            UPI2_RX_DN<12>  @BASEBOARD_FAB2_LIB.BASEBOARD_FAB2(SCH_1):GND
  CP21  GND            UPI2_RX_DN<11>  @BASEBOARD_FAB2_LIB.BASEBOARD_FAB2(SCH_1):GND
  CN20  GND            UPI2_RX_DN<10>  @BASEBOARD_FAB2_LIB.BASEBOARD_FAB2(SCH_1):GND
  CR18  GND            UPI2_RX_DN<9>  @BASEBOARD_FAB2_LIB.BASEBOARD_FAB2(SCH_1):GND
  CT21  GND            UPI2_RX_DN<8>  @BASEBOARD_FAB2_LIB.BASEBOARD_FAB2(SCH_1):GND
  CV19  GND            UPI2_RX_DN<7>  @BASEBOARD_FAB2_LIB.BASEBOARD_FAB2(SCH_1):GND
  CW20  GND            UPI2_RX_DN<6>  @BASEBOARD_FAB2_LIB.BASEBOARD_FAB2(SCH_1):GND
  DA20  GND            UPI2_RX_DN<5>  @BASEBOARD_FAB2_LIB.BASEBOARD_FAB2(SCH_1):GND
  DD19  GND            UPI2_RX_DN<4>  @BASEBOARD_FAB2_LIB.BASEBOARD_FAB2(SCH_1):GND
  DB21  GND            UPI2_RX_DN<3>  @BASEBOARD_FAB2_LIB.BASEBOARD_FAB2(SCH_1):GND
  DC22  GND            UPI2_RX_DN<2>  @BASEBOARD_FAB2_LIB.BASEBOARD_FAB2(SCH_1):GND
  DE22  GND            UPI2_RX_DN<1>  @BASEBOARD_FAB2_LIB.BASEBOARD_FAB2(SCH_1):GND
  DF23  GND            UPI2_RX_DN<0>  @BASEBOARD_FAB2_LIB.BASEBOARD_FAB2(SCH_1):GND

SKX_EXT_B_BGA1  I125  U2D1   [SKX_EXT_B_BGA1-IC,TBD]
   H9  UPI_CPU1_CPU0_P1P1_DP<9>  UPI1_TX_DP<9>  @BASEBOARD_FAB2_LIB.BASEBOARD_FAB2(SCH_1):UPI_CPU1_CPU0_P1P1_DP<9>
  F11  UPI_CPU1_CPU0_P1P1_DP<8>  UPI1_TX_DN<8>  @BASEBOARD_FAB2_LIB.BASEBOARD_FAB2(SCH_1):UPI_CPU1_CPU0_P1P1_DP<8>
   D9  UPI_CPU1_CPU0_P1P1_DP<7>  UPI1_TX_DN<7>  @BASEBOARD_FAB2_LIB.BASEBOARD_FAB2(SCH_1):UPI_CPU1_CPU0_P1P1_DP<7>
   K9  UPI_CPU1_CPU0_P1P1_DP<6>  UPI1_TX_DN<6>  @BASEBOARD_FAB2_LIB.BASEBOARD_FAB2(SCH_1):UPI_CPU1_CPU0_P1P1_DP<6>
   K7  UPI_CPU1_CPU0_P1P1_DP<5>  UPI1_TX_DP<5>  @BASEBOARD_FAB2_LIB.BASEBOARD_FAB2(SCH_1):UPI_CPU1_CPU0_P1P1_DP<5>
   F7  UPI_CPU1_CPU0_P1P1_DP<4>  UPI1_TX_DP<4>  @BASEBOARD_FAB2_LIB.BASEBOARD_FAB2(SCH_1):UPI_CPU1_CPU0_P1P1_DP<4>
   H5  UPI_CPU1_CPU0_P1P1_DP<3>  UPI1_TX_DP<3>  @BASEBOARD_FAB2_LIB.BASEBOARD_FAB2(SCH_1):UPI_CPU1_CPU0_P1P1_DP<3>
   M5  UPI_CPU1_CPU0_P1P1_DP<2>  UPI1_TX_DP<2>  @BASEBOARD_FAB2_LIB.BASEBOARD_FAB2(SCH_1):UPI_CPU1_CPU0_P1P1_DP<2>
   L4  UPI_CPU1_CPU0_P1P1_DP<1>  UPI1_TX_DN<1>  @BASEBOARD_FAB2_LIB.BASEBOARD_FAB2(SCH_1):UPI_CPU1_CPU0_P1P1_DP<1>
  H21  UPI_CPU1_CPU0_P1P1_DP<19>  UPI1_TX_DN<19>  @BASEBOARD_FAB2_LIB.BASEBOARD_FAB2(SCH_1):UPI_CPU1_CPU0_P1P1_DP<19>
  F21  UPI_CPU1_CPU0_P1P1_DP<18>  UPI1_TX_DN<18>  @BASEBOARD_FAB2_LIB.BASEBOARD_FAB2(SCH_1):UPI_CPU1_CPU0_P1P1_DP<18>
  H19  UPI_CPU1_CPU0_P1P1_DP<17>  UPI1_TX_DP<17>  @BASEBOARD_FAB2_LIB.BASEBOARD_FAB2(SCH_1):UPI_CPU1_CPU0_P1P1_DP<17>
  J18  UPI_CPU1_CPU0_P1P1_DP<16>  UPI1_TX_DP<16>  @BASEBOARD_FAB2_LIB.BASEBOARD_FAB2(SCH_1):UPI_CPU1_CPU0_P1P1_DP<16>
  L18  UPI_CPU1_CPU0_P1P1_DP<15>  UPI1_TX_DP<15>  @BASEBOARD_FAB2_LIB.BASEBOARD_FAB2(SCH_1):UPI_CPU1_CPU0_P1P1_DP<15>
  G16  UPI_CPU1_CPU0_P1P1_DP<14>  UPI1_TX_DP<14>  @BASEBOARD_FAB2_LIB.BASEBOARD_FAB2(SCH_1):UPI_CPU1_CPU0_P1P1_DP<14>
  H15  UPI_CPU1_CPU0_P1P1_DP<13>  UPI1_TX_DP<13>  @BASEBOARD_FAB2_LIB.BASEBOARD_FAB2(SCH_1):UPI_CPU1_CPU0_P1P1_DP<13>
  E14  UPI_CPU1_CPU0_P1P1_DP<12>  UPI1_TX_DP<12>  @BASEBOARD_FAB2_LIB.BASEBOARD_FAB2(SCH_1):UPI_CPU1_CPU0_P1P1_DP<12>
  G14  UPI_CPU1_CPU0_P1P1_DP<11>  UPI1_TX_DN<11>  @BASEBOARD_FAB2_LIB.BASEBOARD_FAB2(SCH_1):UPI_CPU1_CPU0_P1P1_DP<11>
  G12  UPI_CPU1_CPU0_P1P1_DP<10>  UPI1_TX_DP<10>  @BASEBOARD_FAB2_LIB.BASEBOARD_FAB2(SCH_1):UPI_CPU1_CPU0_P1P1_DP<10>
   M3  UPI_CPU1_CPU0_P1P1_DP<0>  UPI1_TX_DN<0>  @BASEBOARD_FAB2_LIB.BASEBOARD_FAB2(SCH_1):UPI_CPU1_CPU0_P1P1_DP<0>
  G10  UPI_CPU1_CPU0_P1P1_DN<9>  UPI1_TX_DN<9>  @BASEBOARD_FAB2_LIB.BASEBOARD_FAB2(SCH_1):UPI_CPU1_CPU0_P1P1_DN<9>
  E10  UPI_CPU1_CPU0_P1P1_DN<8>  UPI1_TX_DP<8>  @BASEBOARD_FAB2_LIB.BASEBOARD_FAB2(SCH_1):UPI_CPU1_CPU0_P1P1_DN<8>
   F9  UPI_CPU1_CPU0_P1P1_DN<7>  UPI1_TX_DP<7>  @BASEBOARD_FAB2_LIB.BASEBOARD_FAB2(SCH_1):UPI_CPU1_CPU0_P1P1_DN<7>
   J8  UPI_CPU1_CPU0_P1P1_DN<6>  UPI1_TX_DP<6>  @BASEBOARD_FAB2_LIB.BASEBOARD_FAB2(SCH_1):UPI_CPU1_CPU0_P1P1_DN<6>
   H7  UPI_CPU1_CPU0_P1P1_DN<5>  UPI1_TX_DN<5>  @BASEBOARD_FAB2_LIB.BASEBOARD_FAB2(SCH_1):UPI_CPU1_CPU0_P1P1_DN<5>
   G6  UPI_CPU1_CPU0_P1P1_DN<4>  UPI1_TX_DN<4>  @BASEBOARD_FAB2_LIB.BASEBOARD_FAB2(SCH_1):UPI_CPU1_CPU0_P1P1_DN<4>
   J6  UPI_CPU1_CPU0_P1P1_DN<3>  UPI1_TX_DN<3>  @BASEBOARD_FAB2_LIB.BASEBOARD_FAB2(SCH_1):UPI_CPU1_CPU0_P1P1_DN<3>
   K5  UPI_CPU1_CPU0_P1P1_DN<2>  UPI1_TX_DN<2>  @BASEBOARD_FAB2_LIB.BASEBOARD_FAB2(SCH_1):UPI_CPU1_CPU0_P1P1_DN<2>
   K3  UPI_CPU1_CPU0_P1P1_DN<1>  UPI1_TX_DP<1>  @BASEBOARD_FAB2_LIB.BASEBOARD_FAB2(SCH_1):UPI_CPU1_CPU0_P1P1_DN<1>
  K21  UPI_CPU1_CPU0_P1P1_DN<19>  UPI1_TX_DP<19>  @BASEBOARD_FAB2_LIB.BASEBOARD_FAB2(SCH_1):UPI_CPU1_CPU0_P1P1_DN<19>
  G20  UPI_CPU1_CPU0_P1P1_DN<18>  UPI1_TX_DP<18>  @BASEBOARD_FAB2_LIB.BASEBOARD_FAB2(SCH_1):UPI_CPU1_CPU0_P1P1_DN<18>
  J20  UPI_CPU1_CPU0_P1P1_DN<17>  UPI1_TX_DN<17>  @BASEBOARD_FAB2_LIB.BASEBOARD_FAB2(SCH_1):UPI_CPU1_CPU0_P1P1_DN<17>
  G18  UPI_CPU1_CPU0_P1P1_DN<16>  UPI1_TX_DN<16>  @BASEBOARD_FAB2_LIB.BASEBOARD_FAB2(SCH_1):UPI_CPU1_CPU0_P1P1_DN<16>
  K19  UPI_CPU1_CPU0_P1P1_DN<15>  UPI1_TX_DN<15>  @BASEBOARD_FAB2_LIB.BASEBOARD_FAB2(SCH_1):UPI_CPU1_CPU0_P1P1_DN<15>
  H17  UPI_CPU1_CPU0_P1P1_DN<14>  UPI1_TX_DN<14>  @BASEBOARD_FAB2_LIB.BASEBOARD_FAB2(SCH_1):UPI_CPU1_CPU0_P1P1_DN<14>
  F15  UPI_CPU1_CPU0_P1P1_DN<13>  UPI1_TX_DN<13>  @BASEBOARD_FAB2_LIB.BASEBOARD_FAB2(SCH_1):UPI_CPU1_CPU0_P1P1_DN<13>
  D15  UPI_CPU1_CPU0_P1P1_DN<12>  UPI1_TX_DN<12>  @BASEBOARD_FAB2_LIB.BASEBOARD_FAB2(SCH_1):UPI_CPU1_CPU0_P1P1_DN<12>
  F13  UPI_CPU1_CPU0_P1P1_DN<11>  UPI1_TX_DP<11>  @BASEBOARD_FAB2_LIB.BASEBOARD_FAB2(SCH_1):UPI_CPU1_CPU0_P1P1_DN<11>
  E12  UPI_CPU1_CPU0_P1P1_DN<10>  UPI1_TX_DN<10>  @BASEBOARD_FAB2_LIB.BASEBOARD_FAB2(SCH_1):UPI_CPU1_CPU0_P1P1_DN<10>
   P3  UPI_CPU1_CPU0_P1P1_DN<0>  UPI1_TX_DP<0>  @BASEBOARD_FAB2_LIB.BASEBOARD_FAB2(SCH_1):UPI_CPU1_CPU0_P1P1_DN<0>
  P13  UPI_CPU0_CPU1_P1P1_DP<9>  UPI1_RX_DP<9>  @BASEBOARD_FAB2_LIB.BASEBOARD_FAB2(SCH_1):UPI_CPU0_CPU1_P1P1_DP<9>
  N14  UPI_CPU0_CPU1_P1P1_DP<8>  UPI1_RX_DN<8>  @BASEBOARD_FAB2_LIB.BASEBOARD_FAB2(SCH_1):UPI_CPU0_CPU1_P1P1_DP<8>
  N12  UPI_CPU0_CPU1_P1P1_DP<7>  UPI1_RX_DP<7>  @BASEBOARD_FAB2_LIB.BASEBOARD_FAB2(SCH_1):UPI_CPU0_CPU1_P1P1_DP<7>
  T11  UPI_CPU0_CPU1_P1P1_DP<6>  UPI1_RX_DP<6>  @BASEBOARD_FAB2_LIB.BASEBOARD_FAB2(SCH_1):UPI_CPU0_CPU1_P1P1_DP<6>
  U10  UPI_CPU0_CPU1_P1P1_DP<5>  UPI1_RX_DP<5>  @BASEBOARD_FAB2_LIB.BASEBOARD_FAB2(SCH_1):UPI_CPU0_CPU1_P1P1_DP<5>
  N10  UPI_CPU0_CPU1_P1P1_DP<4>  UPI1_RX_DP<4>  @BASEBOARD_FAB2_LIB.BASEBOARD_FAB2(SCH_1):UPI_CPU0_CPU1_P1P1_DP<4>
   R8  UPI_CPU0_CPU1_P1P1_DP<3>  UPI1_RX_DP<3>  @BASEBOARD_FAB2_LIB.BASEBOARD_FAB2(SCH_1):UPI_CPU0_CPU1_P1P1_DP<3>
   U8  UPI_CPU0_CPU1_P1P1_DP<2>  UPI1_RX_DP<2>  @BASEBOARD_FAB2_LIB.BASEBOARD_FAB2(SCH_1):UPI_CPU0_CPU1_P1P1_DP<2>
   T7  UPI_CPU0_CPU1_P1P1_DP<1>  UPI1_RX_DP<1>  @BASEBOARD_FAB2_LIB.BASEBOARD_FAB2(SCH_1):UPI_CPU0_CPU1_P1P1_DP<1>
  AB19  UPI_CPU0_CPU1_P1P1_DP<19>  UPI1_RX_DN<19>  @BASEBOARD_FAB2_LIB.BASEBOARD_FAB2(SCH_1):UPI_CPU0_CPU1_P1P1_DP<19>
  Y21  UPI_CPU0_CPU1_P1P1_DP<18>  UPI1_RX_DN<18>  @BASEBOARD_FAB2_LIB.BASEBOARD_FAB2(SCH_1):UPI_CPU0_CPU1_P1P1_DP<18>
  Y19  UPI_CPU0_CPU1_P1P1_DP<17>  UPI1_RX_DP<17>  @BASEBOARD_FAB2_LIB.BASEBOARD_FAB2(SCH_1):UPI_CPU0_CPU1_P1P1_DP<17>
  T21  UPI_CPU0_CPU1_P1P1_DP<16>  UPI1_RX_DP<16>  @BASEBOARD_FAB2_LIB.BASEBOARD_FAB2(SCH_1):UPI_CPU0_CPU1_P1P1_DP<16>
  T19  UPI_CPU0_CPU1_P1P1_DP<15>  UPI1_RX_DP<15>  @BASEBOARD_FAB2_LIB.BASEBOARD_FAB2(SCH_1):UPI_CPU0_CPU1_P1P1_DP<15>
  P19  UPI_CPU0_CPU1_P1P1_DP<14>  UPI1_RX_DP<14>  @BASEBOARD_FAB2_LIB.BASEBOARD_FAB2(SCH_1):UPI_CPU0_CPU1_P1P1_DP<14>
  W18  UPI_CPU0_CPU1_P1P1_DP<13>  UPI1_RX_DN<13>  @BASEBOARD_FAB2_LIB.BASEBOARD_FAB2(SCH_1):UPI_CPU0_CPU1_P1P1_DP<13>
  U16  UPI_CPU0_CPU1_P1P1_DP<12>  UPI1_RX_DN<12>  @BASEBOARD_FAB2_LIB.BASEBOARD_FAB2(SCH_1):UPI_CPU0_CPU1_P1P1_DP<12>
  P17  UPI_CPU0_CPU1_P1P1_DP<11>  UPI1_RX_DN<11>  @BASEBOARD_FAB2_LIB.BASEBOARD_FAB2(SCH_1):UPI_CPU0_CPU1_P1P1_DP<11>
  T15  UPI_CPU0_CPU1_P1P1_DP<10>  UPI1_RX_DP<10>  @BASEBOARD_FAB2_LIB.BASEBOARD_FAB2(SCH_1):UPI_CPU0_CPU1_P1P1_DP<10>
   T5  UPI_CPU0_CPU1_P1P1_DP<0>  UPI1_RX_DN<0>  @BASEBOARD_FAB2_LIB.BASEBOARD_FAB2(SCH_1):UPI_CPU0_CPU1_P1P1_DP<0>
  R12  UPI_CPU0_CPU1_P1P1_DN<9>  UPI1_RX_DN<9>  @BASEBOARD_FAB2_LIB.BASEBOARD_FAB2(SCH_1):UPI_CPU0_CPU1_P1P1_DN<9>
  M13  UPI_CPU0_CPU1_P1P1_DN<8>  UPI1_RX_DP<8>  @BASEBOARD_FAB2_LIB.BASEBOARD_FAB2(SCH_1):UPI_CPU0_CPU1_P1P1_DN<8>
  L12  UPI_CPU0_CPU1_P1P1_DN<7>  UPI1_RX_DN<7>  @BASEBOARD_FAB2_LIB.BASEBOARD_FAB2(SCH_1):UPI_CPU0_CPU1_P1P1_DN<7>
  U12  UPI_CPU0_CPU1_P1P1_DN<6>  UPI1_RX_DN<6>  @BASEBOARD_FAB2_LIB.BASEBOARD_FAB2(SCH_1):UPI_CPU0_CPU1_P1P1_DN<6>
  R10  UPI_CPU0_CPU1_P1P1_DN<5>  UPI1_RX_DN<5>  @BASEBOARD_FAB2_LIB.BASEBOARD_FAB2(SCH_1):UPI_CPU0_CPU1_P1P1_DN<5>
   P9  UPI_CPU0_CPU1_P1P1_DN<4>  UPI1_RX_DN<4>  @BASEBOARD_FAB2_LIB.BASEBOARD_FAB2(SCH_1):UPI_CPU0_CPU1_P1P1_DN<4>
   T9  UPI_CPU0_CPU1_P1P1_DN<3>  UPI1_RX_DN<3>  @BASEBOARD_FAB2_LIB.BASEBOARD_FAB2(SCH_1):UPI_CPU0_CPU1_P1P1_DN<3>
   V7  UPI_CPU0_CPU1_P1P1_DN<2>  UPI1_RX_DN<2>  @BASEBOARD_FAB2_LIB.BASEBOARD_FAB2(SCH_1):UPI_CPU0_CPU1_P1P1_DN<2>
   P7  UPI_CPU0_CPU1_P1P1_DN<1>  UPI1_RX_DN<1>  @BASEBOARD_FAB2_LIB.BASEBOARD_FAB2(SCH_1):UPI_CPU0_CPU1_P1P1_DN<1>
  AA20  UPI_CPU0_CPU1_P1P1_DN<19>  UPI1_RX_DP<19>  @BASEBOARD_FAB2_LIB.BASEBOARD_FAB2(SCH_1):UPI_CPU0_CPU1_P1P1_DN<19>
  W20  UPI_CPU0_CPU1_P1P1_DN<18>  UPI1_RX_DP<18>  @BASEBOARD_FAB2_LIB.BASEBOARD_FAB2(SCH_1):UPI_CPU0_CPU1_P1P1_DN<18>
  V19  UPI_CPU0_CPU1_P1P1_DN<17>  UPI1_RX_DN<17>  @BASEBOARD_FAB2_LIB.BASEBOARD_FAB2(SCH_1):UPI_CPU0_CPU1_P1P1_DN<17>
  P21  UPI_CPU0_CPU1_P1P1_DN<16>  UPI1_RX_DN<16>  @BASEBOARD_FAB2_LIB.BASEBOARD_FAB2(SCH_1):UPI_CPU0_CPU1_P1P1_DN<16>
  U18  UPI_CPU0_CPU1_P1P1_DN<15>  UPI1_RX_DN<15>  @BASEBOARD_FAB2_LIB.BASEBOARD_FAB2(SCH_1):UPI_CPU0_CPU1_P1P1_DN<15>
  R20  UPI_CPU0_CPU1_P1P1_DN<14>  UPI1_RX_DN<14>  @BASEBOARD_FAB2_LIB.BASEBOARD_FAB2(SCH_1):UPI_CPU0_CPU1_P1P1_DN<14>
  V17  UPI_CPU0_CPU1_P1P1_DN<13>  UPI1_RX_DP<13>  @BASEBOARD_FAB2_LIB.BASEBOARD_FAB2(SCH_1):UPI_CPU0_CPU1_P1P1_DN<13>
  W16  UPI_CPU0_CPU1_P1P1_DN<12>  UPI1_RX_DP<12>  @BASEBOARD_FAB2_LIB.BASEBOARD_FAB2(SCH_1):UPI_CPU0_CPU1_P1P1_DN<12>
  N16  UPI_CPU0_CPU1_P1P1_DN<11>  UPI1_RX_DP<11>  @BASEBOARD_FAB2_LIB.BASEBOARD_FAB2(SCH_1):UPI_CPU0_CPU1_P1P1_DN<11>
  R16  UPI_CPU0_CPU1_P1P1_DN<10>  UPI1_RX_DN<10>  @BASEBOARD_FAB2_LIB.BASEBOARD_FAB2(SCH_1):UPI_CPU0_CPU1_P1P1_DN<10>
   R6  UPI_CPU0_CPU1_P1P1_DN<0>  UPI1_RX_DP<0>  @BASEBOARD_FAB2_LIB.BASEBOARD_FAB2(SCH_1):UPI_CPU0_CPU1_P1P1_DN<0>

SKX_EXT_B_BGA1  I132  U2D1   [SKX_EXT_B_BGA1-IC,TBD]
  AK1  UPI_CPU1_CPU0_P0P0_DP<9>  UPI0_TX_DP<9>  @BASEBOARD_FAB2_LIB.BASEBOARD_FAB2(SCH_1):UPI_CPU1_CPU0_P0P0_DP<9>
  AH3  UPI_CPU1_CPU0_P0P0_DP<8>  UPI0_TX_DN<8>  @BASEBOARD_FAB2_LIB.BASEBOARD_FAB2(SCH_1):UPI_CPU1_CPU0_P0P0_DP<8>
  AG2  UPI_CPU1_CPU0_P0P0_DP<7>  UPI0_TX_DP<7>  @BASEBOARD_FAB2_LIB.BASEBOARD_FAB2(SCH_1):UPI_CPU1_CPU0_P0P0_DP<7>
  AF3  UPI_CPU1_CPU0_P0P0_DP<6>  UPI0_TX_DP<6>  @BASEBOARD_FAB2_LIB.BASEBOARD_FAB2(SCH_1):UPI_CPU1_CPU0_P0P0_DP<6>
  AC2  UPI_CPU1_CPU0_P0P0_DP<5>  UPI0_TX_DN<5>  @BASEBOARD_FAB2_LIB.BASEBOARD_FAB2(SCH_1):UPI_CPU1_CPU0_P0P0_DP<5>
  AA2  UPI_CPU1_CPU0_P0P0_DP<4>  UPI0_TX_DP<4>  @BASEBOARD_FAB2_LIB.BASEBOARD_FAB2(SCH_1):UPI_CPU1_CPU0_P0P0_DP<4>
   W2  UPI_CPU1_CPU0_P0P0_DP<3>  UPI0_TX_DP<3>  @BASEBOARD_FAB2_LIB.BASEBOARD_FAB2(SCH_1):UPI_CPU1_CPU0_P0P0_DP<3>
   Y3  UPI_CPU1_CPU0_P0P0_DP<2>  UPI0_TX_DP<2>  @BASEBOARD_FAB2_LIB.BASEBOARD_FAB2(SCH_1):UPI_CPU1_CPU0_P0P0_DP<2>
   P1  UPI_CPU1_CPU0_P0P0_DP<1>  UPI0_TX_DN<1>  @BASEBOARD_FAB2_LIB.BASEBOARD_FAB2(SCH_1):UPI_CPU1_CPU0_P0P0_DP<1>
  BG4  UPI_CPU1_CPU0_P0P0_DP<19>  UPI0_TX_DN<19>  @BASEBOARD_FAB2_LIB.BASEBOARD_FAB2(SCH_1):UPI_CPU1_CPU0_P0P0_DP<19>
  BD3  UPI_CPU1_CPU0_P0P0_DP<18>  UPI0_TX_DP<18>  @BASEBOARD_FAB2_LIB.BASEBOARD_FAB2(SCH_1):UPI_CPU1_CPU0_P0P0_DP<18>
  BC2  UPI_CPU1_CPU0_P0P0_DP<17>  UPI0_TX_DP<17>  @BASEBOARD_FAB2_LIB.BASEBOARD_FAB2(SCH_1):UPI_CPU1_CPU0_P0P0_DP<17>
  BA4  UPI_CPU1_CPU0_P0P0_DP<16>  UPI0_TX_DN<16>  @BASEBOARD_FAB2_LIB.BASEBOARD_FAB2(SCH_1):UPI_CPU1_CPU0_P0P0_DP<16>
  AV5  UPI_CPU1_CPU0_P0P0_DP<15>  UPI0_TX_DN<15>  @BASEBOARD_FAB2_LIB.BASEBOARD_FAB2(SCH_1):UPI_CPU1_CPU0_P0P0_DP<15>
  AU4  UPI_CPU1_CPU0_P0P0_DP<14>  UPI0_TX_DN<14>  @BASEBOARD_FAB2_LIB.BASEBOARD_FAB2(SCH_1):UPI_CPU1_CPU0_P0P0_DP<14>
  AT3  UPI_CPU1_CPU0_P0P0_DP<13>  UPI0_TX_DN<13>  @BASEBOARD_FAB2_LIB.BASEBOARD_FAB2(SCH_1):UPI_CPU1_CPU0_P0P0_DP<13>
  AT1  UPI_CPU1_CPU0_P0P0_DP<12>  UPI0_TX_DN<12>  @BASEBOARD_FAB2_LIB.BASEBOARD_FAB2(SCH_1):UPI_CPU1_CPU0_P0P0_DP<12>
  AN4  UPI_CPU1_CPU0_P0P0_DP<11>  UPI0_TX_DN<11>  @BASEBOARD_FAB2_LIB.BASEBOARD_FAB2(SCH_1):UPI_CPU1_CPU0_P0P0_DP<11>
  AM3  UPI_CPU1_CPU0_P0P0_DP<10>  UPI0_TX_DN<10>  @BASEBOARD_FAB2_LIB.BASEBOARD_FAB2(SCH_1):UPI_CPU1_CPU0_P0P0_DP<10>
   N2  UPI_CPU1_CPU0_P0P0_DP<0>  UPI0_TX_DN<0>  @BASEBOARD_FAB2_LIB.BASEBOARD_FAB2(SCH_1):UPI_CPU1_CPU0_P0P0_DP<0>
  AL2  UPI_CPU1_CPU0_P0P0_DN<9>  UPI0_TX_DN<9>  @BASEBOARD_FAB2_LIB.BASEBOARD_FAB2(SCH_1):UPI_CPU1_CPU0_P0P0_DN<9>
  AJ2  UPI_CPU1_CPU0_P0P0_DN<8>  UPI0_TX_DP<8>  @BASEBOARD_FAB2_LIB.BASEBOARD_FAB2(SCH_1):UPI_CPU1_CPU0_P0P0_DN<8>
  AE2  UPI_CPU1_CPU0_P0P0_DN<7>  UPI0_TX_DN<7>  @BASEBOARD_FAB2_LIB.BASEBOARD_FAB2(SCH_1):UPI_CPU1_CPU0_P0P0_DN<7>
  AG4  UPI_CPU1_CPU0_P0P0_DN<6>  UPI0_TX_DN<6>  @BASEBOARD_FAB2_LIB.BASEBOARD_FAB2(SCH_1):UPI_CPU1_CPU0_P0P0_DN<6>
  AD1  UPI_CPU1_CPU0_P0P0_DN<5>  UPI0_TX_DP<5>  @BASEBOARD_FAB2_LIB.BASEBOARD_FAB2(SCH_1):UPI_CPU1_CPU0_P0P0_DN<5>
  AB3  UPI_CPU1_CPU0_P0P0_DN<4>  UPI0_TX_DN<4>  @BASEBOARD_FAB2_LIB.BASEBOARD_FAB2(SCH_1):UPI_CPU1_CPU0_P0P0_DN<4>
   Y1  UPI_CPU1_CPU0_P0P0_DN<3>  UPI0_TX_DN<3>  @BASEBOARD_FAB2_LIB.BASEBOARD_FAB2(SCH_1):UPI_CPU1_CPU0_P0P0_DN<3>
   V3  UPI_CPU1_CPU0_P0P0_DN<2>  UPI0_TX_DN<2>  @BASEBOARD_FAB2_LIB.BASEBOARD_FAB2(SCH_1):UPI_CPU1_CPU0_P0P0_DN<2>
   T1  UPI_CPU1_CPU0_P0P0_DN<1>  UPI0_TX_DP<1>  @BASEBOARD_FAB2_LIB.BASEBOARD_FAB2(SCH_1):UPI_CPU1_CPU0_P0P0_DN<1>
  BH3  UPI_CPU1_CPU0_P0P0_DN<19>  UPI0_TX_DP<19>  @BASEBOARD_FAB2_LIB.BASEBOARD_FAB2(SCH_1):UPI_CPU1_CPU0_P0P0_DN<19>
  BF3  UPI_CPU1_CPU0_P0P0_DN<18>  UPI0_TX_DN<18>  @BASEBOARD_FAB2_LIB.BASEBOARD_FAB2(SCH_1):UPI_CPU1_CPU0_P0P0_DN<18>
  BB3  UPI_CPU1_CPU0_P0P0_DN<17>  UPI0_TX_DN<17>  @BASEBOARD_FAB2_LIB.BASEBOARD_FAB2(SCH_1):UPI_CPU1_CPU0_P0P0_DN<17>
  AY3  UPI_CPU1_CPU0_P0P0_DN<16>  UPI0_TX_DP<16>  @BASEBOARD_FAB2_LIB.BASEBOARD_FAB2(SCH_1):UPI_CPU1_CPU0_P0P0_DN<16>
  AW4  UPI_CPU1_CPU0_P0P0_DN<15>  UPI0_TX_DP<15>  @BASEBOARD_FAB2_LIB.BASEBOARD_FAB2(SCH_1):UPI_CPU1_CPU0_P0P0_DN<15>
  AR4  UPI_CPU1_CPU0_P0P0_DN<14>  UPI0_TX_DP<14>  @BASEBOARD_FAB2_LIB.BASEBOARD_FAB2(SCH_1):UPI_CPU1_CPU0_P0P0_DN<14>
  AR2  UPI_CPU1_CPU0_P0P0_DN<13>  UPI0_TX_DP<13>  @BASEBOARD_FAB2_LIB.BASEBOARD_FAB2(SCH_1):UPI_CPU1_CPU0_P0P0_DN<13>
  AP1  UPI_CPU1_CPU0_P0P0_DN<12>  UPI0_TX_DP<12>  @BASEBOARD_FAB2_LIB.BASEBOARD_FAB2(SCH_1):UPI_CPU1_CPU0_P0P0_DN<12>
  AP3  UPI_CPU1_CPU0_P0P0_DN<11>  UPI0_TX_DP<11>  @BASEBOARD_FAB2_LIB.BASEBOARD_FAB2(SCH_1):UPI_CPU1_CPU0_P0P0_DN<11>
  AK3  UPI_CPU1_CPU0_P0P0_DN<10>  UPI0_TX_DP<10>  @BASEBOARD_FAB2_LIB.BASEBOARD_FAB2(SCH_1):UPI_CPU1_CPU0_P0P0_DN<10>
   M1  UPI_CPU1_CPU0_P0P0_DN<0>  UPI0_TX_DP<0>  @BASEBOARD_FAB2_LIB.BASEBOARD_FAB2(SCH_1):UPI_CPU1_CPU0_P0P0_DN<0>
  AM9  UPI_CPU0_CPU1_P0P0_DP<9>  UPI0_RX_DN<9>  @BASEBOARD_FAB2_LIB.BASEBOARD_FAB2(SCH_1):UPI_CPU0_CPU1_P0P0_DP<9>
  AK7  UPI_CPU0_CPU1_P0P0_DP<8>  UPI0_RX_DN<8>  @BASEBOARD_FAB2_LIB.BASEBOARD_FAB2(SCH_1):UPI_CPU0_CPU1_P0P0_DP<8>
  AL6  UPI_CPU0_CPU1_P0P0_DP<7>  UPI0_RX_DN<7>  @BASEBOARD_FAB2_LIB.BASEBOARD_FAB2(SCH_1):UPI_CPU0_CPU1_P0P0_DP<7>
  AJ6  UPI_CPU0_CPU1_P0P0_DP<6>  UPI0_RX_DN<6>  @BASEBOARD_FAB2_LIB.BASEBOARD_FAB2(SCH_1):UPI_CPU0_CPU1_P0P0_DP<6>
  AG8  UPI_CPU0_CPU1_P0P0_DP<5>  UPI0_RX_DN<5>  @BASEBOARD_FAB2_LIB.BASEBOARD_FAB2(SCH_1):UPI_CPU0_CPU1_P0P0_DP<5>
  AE6  UPI_CPU0_CPU1_P0P0_DP<4>  UPI0_RX_DN<4>  @BASEBOARD_FAB2_LIB.BASEBOARD_FAB2(SCH_1):UPI_CPU0_CPU1_P0P0_DP<4>
  AD5  UPI_CPU0_CPU1_P0P0_DP<3>  UPI0_RX_DN<3>  @BASEBOARD_FAB2_LIB.BASEBOARD_FAB2(SCH_1):UPI_CPU0_CPU1_P0P0_DP<3>
  AA6  UPI_CPU0_CPU1_P0P0_DP<2>  UPI0_RX_DP<2>  @BASEBOARD_FAB2_LIB.BASEBOARD_FAB2(SCH_1):UPI_CPU0_CPU1_P0P0_DP<2>
  AC8  UPI_CPU0_CPU1_P0P0_DP<1>  UPI0_RX_DP<1>  @BASEBOARD_FAB2_LIB.BASEBOARD_FAB2(SCH_1):UPI_CPU0_CPU1_P0P0_DP<1>
  BB11  UPI_CPU0_CPU1_P0P0_DP<19>  UPI0_RX_DN<19>  @BASEBOARD_FAB2_LIB.BASEBOARD_FAB2(SCH_1):UPI_CPU0_CPU1_P0P0_DP<19>
  BD9  UPI_CPU0_CPU1_P0P0_DP<18>  UPI0_RX_DN<18>  @BASEBOARD_FAB2_LIB.BASEBOARD_FAB2(SCH_1):UPI_CPU0_CPU1_P0P0_DP<18>
  BB9  UPI_CPU0_CPU1_P0P0_DP<17>  UPI0_RX_DP<17>  @BASEBOARD_FAB2_LIB.BASEBOARD_FAB2(SCH_1):UPI_CPU0_CPU1_P0P0_DP<17>
  AV9  UPI_CPU0_CPU1_P0P0_DP<16>  UPI0_RX_DP<16>  @BASEBOARD_FAB2_LIB.BASEBOARD_FAB2(SCH_1):UPI_CPU0_CPU1_P0P0_DP<16>
  BF7  UPI_CPU0_CPU1_P0P0_DP<15>  UPI0_RX_DP<15>  @BASEBOARD_FAB2_LIB.BASEBOARD_FAB2(SCH_1):UPI_CPU0_CPU1_P0P0_DP<15>
  BC6  UPI_CPU0_CPU1_P0P0_DP<14>  UPI0_RX_DN<14>  @BASEBOARD_FAB2_LIB.BASEBOARD_FAB2(SCH_1):UPI_CPU0_CPU1_P0P0_DP<14>
  AY7  UPI_CPU0_CPU1_P0P0_DP<13>  UPI0_RX_DP<13>  @BASEBOARD_FAB2_LIB.BASEBOARD_FAB2(SCH_1):UPI_CPU0_CPU1_P0P0_DP<13>
  AT9  UPI_CPU0_CPU1_P0P0_DP<12>  UPI0_RX_DP<12>  @BASEBOARD_FAB2_LIB.BASEBOARD_FAB2(SCH_1):UPI_CPU0_CPU1_P0P0_DP<12>
  AR8  UPI_CPU0_CPU1_P0P0_DP<11>  UPI0_RX_DN<11>  @BASEBOARD_FAB2_LIB.BASEBOARD_FAB2(SCH_1):UPI_CPU0_CPU1_P0P0_DP<11>
  AN8  UPI_CPU0_CPU1_P0P0_DP<10>  UPI0_RX_DP<10>  @BASEBOARD_FAB2_LIB.BASEBOARD_FAB2(SCH_1):UPI_CPU0_CPU1_P0P0_DP<10>
  AC10  UPI_CPU0_CPU1_P0P0_DP<0>  UPI0_RX_DN<0>  @BASEBOARD_FAB2_LIB.BASEBOARD_FAB2(SCH_1):UPI_CPU0_CPU1_P0P0_DP<0>
  AL8  UPI_CPU0_CPU1_P0P0_DN<9>  UPI0_RX_DP<9>  @BASEBOARD_FAB2_LIB.BASEBOARD_FAB2(SCH_1):UPI_CPU0_CPU1_P0P0_DN<9>
  AM7  UPI_CPU0_CPU1_P0P0_DN<8>  UPI0_RX_DP<8>  @BASEBOARD_FAB2_LIB.BASEBOARD_FAB2(SCH_1):UPI_CPU0_CPU1_P0P0_DN<8>
  AK5  UPI_CPU0_CPU1_P0P0_DN<7>  UPI0_RX_DP<7>  @BASEBOARD_FAB2_LIB.BASEBOARD_FAB2(SCH_1):UPI_CPU0_CPU1_P0P0_DN<7>
  AH7  UPI_CPU0_CPU1_P0P0_DN<6>  UPI0_RX_DP<6>  @BASEBOARD_FAB2_LIB.BASEBOARD_FAB2(SCH_1):UPI_CPU0_CPU1_P0P0_DN<6>
  AF7  UPI_CPU0_CPU1_P0P0_DN<5>  UPI0_RX_DP<5>  @BASEBOARD_FAB2_LIB.BASEBOARD_FAB2(SCH_1):UPI_CPU0_CPU1_P0P0_DN<5>
  AG6  UPI_CPU0_CPU1_P0P0_DN<4>  UPI0_RX_DP<4>  @BASEBOARD_FAB2_LIB.BASEBOARD_FAB2(SCH_1):UPI_CPU0_CPU1_P0P0_DN<4>
  AC6  UPI_CPU0_CPU1_P0P0_DN<3>  UPI0_RX_DP<3>  @BASEBOARD_FAB2_LIB.BASEBOARD_FAB2(SCH_1):UPI_CPU0_CPU1_P0P0_DN<3>
  AB7  UPI_CPU0_CPU1_P0P0_DN<2>  UPI0_RX_DN<2>  @BASEBOARD_FAB2_LIB.BASEBOARD_FAB2(SCH_1):UPI_CPU0_CPU1_P0P0_DN<2>
  AA8  UPI_CPU0_CPU1_P0P0_DN<1>  UPI0_RX_DN<1>  @BASEBOARD_FAB2_LIB.BASEBOARD_FAB2(SCH_1):UPI_CPU0_CPU1_P0P0_DN<1>
  BA10  UPI_CPU0_CPU1_P0P0_DN<19>  UPI0_RX_DP<19>  @BASEBOARD_FAB2_LIB.BASEBOARD_FAB2(SCH_1):UPI_CPU0_CPU1_P0P0_DN<19>
  BC10  UPI_CPU0_CPU1_P0P0_DN<18>  UPI0_RX_DP<18>  @BASEBOARD_FAB2_LIB.BASEBOARD_FAB2(SCH_1):UPI_CPU0_CPU1_P0P0_DN<18>
  AY9  UPI_CPU0_CPU1_P0P0_DN<17>  UPI0_RX_DN<17>  @BASEBOARD_FAB2_LIB.BASEBOARD_FAB2(SCH_1):UPI_CPU0_CPU1_P0P0_DN<17>
  AW8  UPI_CPU0_CPU1_P0P0_DN<16>  UPI0_RX_DN<16>  @BASEBOARD_FAB2_LIB.BASEBOARD_FAB2(SCH_1):UPI_CPU0_CPU1_P0P0_DN<16>
  BD7  UPI_CPU0_CPU1_P0P0_DN<15>  UPI0_RX_DN<15>  @BASEBOARD_FAB2_LIB.BASEBOARD_FAB2(SCH_1):UPI_CPU0_CPU1_P0P0_DN<15>
  BB7  UPI_CPU0_CPU1_P0P0_DN<14>  UPI0_RX_DP<14>  @BASEBOARD_FAB2_LIB.BASEBOARD_FAB2(SCH_1):UPI_CPU0_CPU1_P0P0_DN<14>
  BA8  UPI_CPU0_CPU1_P0P0_DN<13>  UPI0_RX_DN<13>  @BASEBOARD_FAB2_LIB.BASEBOARD_FAB2(SCH_1):UPI_CPU0_CPU1_P0P0_DN<13>
  AU10  UPI_CPU0_CPU1_P0P0_DN<12>  UPI0_RX_DN<12>  @BASEBOARD_FAB2_LIB.BASEBOARD_FAB2(SCH_1):UPI_CPU0_CPU1_P0P0_DN<12>
  AU8  UPI_CPU0_CPU1_P0P0_DN<11>  UPI0_RX_DP<11>  @BASEBOARD_FAB2_LIB.BASEBOARD_FAB2(SCH_1):UPI_CPU0_CPU1_P0P0_DN<11>
  AP7  UPI_CPU0_CPU1_P0P0_DN<10>  UPI0_RX_DN<10>  @BASEBOARD_FAB2_LIB.BASEBOARD_FAB2(SCH_1):UPI_CPU0_CPU1_P0P0_DN<10>
  AB9  UPI_CPU0_CPU1_P0P0_DN<0>  UPI0_RX_DP<0>  @BASEBOARD_FAB2_LIB.BASEBOARD_FAB2(SCH_1):UPI_CPU0_CPU1_P0P0_DN<0>

SKX_EXT_B_BGA1  I84  U2D1   [SKX_EXT_B_BGA1-IC,TBD]
  DM5  P3E_CPU1_PE3_MP_TXP<9>  PE3_TX_DP<9>  @BASEBOARD_FAB2_LIB.BASEBOARD_FAB2(SCH_1):P3E_CPU1_PE3_MP_TXP<9>
  DN6  P3E_CPU1_PE3_MP_TXP<8>  PE3_TX_DP<8>  @BASEBOARD_FAB2_LIB.BASEBOARD_FAB2(SCH_1):P3E_CPU1_PE3_MP_TXP<8>
  DP7  P3E_CPU1_PE3_MP_TXP<7>  PE3_TX_DP<7>  @BASEBOARD_FAB2_LIB.BASEBOARD_FAB2(SCH_1):P3E_CPU1_PE3_MP_TXP<7>
  DT9  P3E_CPU1_PE3_MP_TXP<6>  PE3_TX_DP<6>  @BASEBOARD_FAB2_LIB.BASEBOARD_FAB2(SCH_1):P3E_CPU1_PE3_MP_TXP<6>
  DV9  P3E_CPU1_PE3_MP_TXP<5>  PE3_TX_DP<5>  @BASEBOARD_FAB2_LIB.BASEBOARD_FAB2(SCH_1):P3E_CPU1_PE3_MP_TXP<5>
  DY9  P3E_CPU1_PE3_MP_TXP<4>  PE3_TX_DP<4>  @BASEBOARD_FAB2_LIB.BASEBOARD_FAB2(SCH_1):P3E_CPU1_PE3_MP_TXP<4>
  EA10  P3E_CPU1_PE3_MP_TXP<3>  PE3_TX_DP<3>  @BASEBOARD_FAB2_LIB.BASEBOARD_FAB2(SCH_1):P3E_CPU1_PE3_MP_TXP<3>
  EB11  P3E_CPU1_PE3_MP_TXP<2>  PE3_TX_DP<2>  @BASEBOARD_FAB2_LIB.BASEBOARD_FAB2(SCH_1):P3E_CPU1_PE3_MP_TXP<2>
  ED13  P3E_CPU1_PE3_MP_TXP<1>  PE3_TX_DP<1>  @BASEBOARD_FAB2_LIB.BASEBOARD_FAB2(SCH_1):P3E_CPU1_PE3_MP_TXP<1>
  CV5  P3E_CPU1_PE3_MP_TXP<15>  PE3_TX_DP<15>  @BASEBOARD_FAB2_LIB.BASEBOARD_FAB2(SCH_1):P3E_CPU1_PE3_MP_TXP<15>
  DA4  P3E_CPU1_PE3_MP_TXP<14>  PE3_TX_DP<14>  @BASEBOARD_FAB2_LIB.BASEBOARD_FAB2(SCH_1):P3E_CPU1_PE3_MP_TXP<14>
  DC6  P3E_CPU1_PE3_MP_TXP<13>  PE3_TX_DP<13>  @BASEBOARD_FAB2_LIB.BASEBOARD_FAB2(SCH_1):P3E_CPU1_PE3_MP_TXP<13>
  DG6  P3E_CPU1_PE3_MP_TXP<12>  PE3_TX_DP<12>  @BASEBOARD_FAB2_LIB.BASEBOARD_FAB2(SCH_1):P3E_CPU1_PE3_MP_TXP<12>
  DH5  P3E_CPU1_PE3_MP_TXP<11>  PE3_TX_DP<11>  @BASEBOARD_FAB2_LIB.BASEBOARD_FAB2(SCH_1):P3E_CPU1_PE3_MP_TXP<11>
  DK5  P3E_CPU1_PE3_MP_TXP<10>  PE3_TX_DP<10>  @BASEBOARD_FAB2_LIB.BASEBOARD_FAB2(SCH_1):P3E_CPU1_PE3_MP_TXP<10>
  EC14  P3E_CPU1_PE3_MP_TXP<0>  PE3_TX_DP<0>  @BASEBOARD_FAB2_LIB.BASEBOARD_FAB2(SCH_1):P3E_CPU1_PE3_MP_TXP<0>
  DP5  P3E_CPU1_PE3_MP_TXN<9>  PE3_TX_DN<9>  @BASEBOARD_FAB2_LIB.BASEBOARD_FAB2(SCH_1):P3E_CPU1_PE3_MP_TXN<9>
  DM7  P3E_CPU1_PE3_MP_TXN<8>  PE3_TX_DN<8>  @BASEBOARD_FAB2_LIB.BASEBOARD_FAB2(SCH_1):P3E_CPU1_PE3_MP_TXN<8>
  DR8  P3E_CPU1_PE3_MP_TXN<7>  PE3_TX_DN<7>  @BASEBOARD_FAB2_LIB.BASEBOARD_FAB2(SCH_1):P3E_CPU1_PE3_MP_TXN<7>
  DU8  P3E_CPU1_PE3_MP_TXN<6>  PE3_TX_DN<6>  @BASEBOARD_FAB2_LIB.BASEBOARD_FAB2(SCH_1):P3E_CPU1_PE3_MP_TXN<6>
  DW10  P3E_CPU1_PE3_MP_TXN<5>  PE3_TX_DN<5>  @BASEBOARD_FAB2_LIB.BASEBOARD_FAB2(SCH_1):P3E_CPU1_PE3_MP_TXN<5>
  EB9  P3E_CPU1_PE3_MP_TXN<4>  PE3_TX_DN<4>  @BASEBOARD_FAB2_LIB.BASEBOARD_FAB2(SCH_1):P3E_CPU1_PE3_MP_TXN<4>
  DY11  P3E_CPU1_PE3_MP_TXN<3>  PE3_TX_DN<3>  @BASEBOARD_FAB2_LIB.BASEBOARD_FAB2(SCH_1):P3E_CPU1_PE3_MP_TXN<3>
  EC12  P3E_CPU1_PE3_MP_TXN<2>  PE3_TX_DN<2>  @BASEBOARD_FAB2_LIB.BASEBOARD_FAB2(SCH_1):P3E_CPU1_PE3_MP_TXN<2>
  EE12  P3E_CPU1_PE3_MP_TXN<1>  PE3_TX_DN<1>  @BASEBOARD_FAB2_LIB.BASEBOARD_FAB2(SCH_1):P3E_CPU1_PE3_MP_TXN<1>
  CY5  P3E_CPU1_PE3_MP_TXN<15>  PE3_TX_DN<15>  @BASEBOARD_FAB2_LIB.BASEBOARD_FAB2(SCH_1):P3E_CPU1_PE3_MP_TXN<15>
  DB5  P3E_CPU1_PE3_MP_TXN<14>  PE3_TX_DN<14>  @BASEBOARD_FAB2_LIB.BASEBOARD_FAB2(SCH_1):P3E_CPU1_PE3_MP_TXN<14>
  DD5  P3E_CPU1_PE3_MP_TXN<13>  PE3_TX_DN<13>  @BASEBOARD_FAB2_LIB.BASEBOARD_FAB2(SCH_1):P3E_CPU1_PE3_MP_TXN<13>
  DJ6  P3E_CPU1_PE3_MP_TXN<12>  PE3_TX_DN<12>  @BASEBOARD_FAB2_LIB.BASEBOARD_FAB2(SCH_1):P3E_CPU1_PE3_MP_TXN<12>
  DJ4  P3E_CPU1_PE3_MP_TXN<11>  PE3_TX_DN<11>  @BASEBOARD_FAB2_LIB.BASEBOARD_FAB2(SCH_1):P3E_CPU1_PE3_MP_TXN<11>
  DL6  P3E_CPU1_PE3_MP_TXN<10>  PE3_TX_DN<10>  @BASEBOARD_FAB2_LIB.BASEBOARD_FAB2(SCH_1):P3E_CPU1_PE3_MP_TXN<10>
  EE14  P3E_CPU1_PE3_MP_TXN<0>  PE3_TX_DN<0>  @BASEBOARD_FAB2_LIB.BASEBOARD_FAB2(SCH_1):P3E_CPU1_PE3_MP_TXN<0>
  DH11  P3E_CPU1_PE3_MP_RXP<9>  PE3_RX_DP<9>  @BASEBOARD_FAB2_LIB.BASEBOARD_FAB2(SCH_1):P3E_CPU1_PE3_MP_RXP<9>
  DK13  P3E_CPU1_PE3_MP_RXP<8>  PE3_RX_DP<8>  @BASEBOARD_FAB2_LIB.BASEBOARD_FAB2(SCH_1):P3E_CPU1_PE3_MP_RXP<8>
  DJ14  P3E_CPU1_PE3_MP_RXP<7>  PE3_RX_DP<7>  @BASEBOARD_FAB2_LIB.BASEBOARD_FAB2(SCH_1):P3E_CPU1_PE3_MP_RXP<7>
  DM13  P3E_CPU1_PE3_MP_RXP<6>  PE3_RX_DP<6>  @BASEBOARD_FAB2_LIB.BASEBOARD_FAB2(SCH_1):P3E_CPU1_PE3_MP_RXP<6>
  DP15  P3E_CPU1_PE3_MP_RXP<5>  PE3_RX_DP<5>  @BASEBOARD_FAB2_LIB.BASEBOARD_FAB2(SCH_1):P3E_CPU1_PE3_MP_RXP<5>
  DN16  P3E_CPU1_PE3_MP_RXP<4>  PE3_RX_DP<4>  @BASEBOARD_FAB2_LIB.BASEBOARD_FAB2(SCH_1):P3E_CPU1_PE3_MP_RXP<4>
  DR18  P3E_CPU1_PE3_MP_RXP<3>  PE3_RX_DP<3>  @BASEBOARD_FAB2_LIB.BASEBOARD_FAB2(SCH_1):P3E_CPU1_PE3_MP_RXP<3>
  DV17  P3E_CPU1_PE3_MP_RXP<2>  PE3_RX_DP<2>  @BASEBOARD_FAB2_LIB.BASEBOARD_FAB2(SCH_1):P3E_CPU1_PE3_MP_RXP<2>
  DU18  P3E_CPU1_PE3_MP_RXP<1>  PE3_RX_DP<1>  @BASEBOARD_FAB2_LIB.BASEBOARD_FAB2(SCH_1):P3E_CPU1_PE3_MP_RXP<1>
  CU10  P3E_CPU1_PE3_MP_RXP<15>  PE3_RX_DP<15>  @BASEBOARD_FAB2_LIB.BASEBOARD_FAB2(SCH_1):P3E_CPU1_PE3_MP_RXP<15>
  CW10  P3E_CPU1_PE3_MP_RXP<14>  PE3_RX_DP<14>  @BASEBOARD_FAB2_LIB.BASEBOARD_FAB2(SCH_1):P3E_CPU1_PE3_MP_RXP<14>
  DA12  P3E_CPU1_PE3_MP_RXP<13>  PE3_RX_DP<13>  @BASEBOARD_FAB2_LIB.BASEBOARD_FAB2(SCH_1):P3E_CPU1_PE3_MP_RXP<13>
  DD13  P3E_CPU1_PE3_MP_RXP<12>  PE3_RX_DN<12>  @BASEBOARD_FAB2_LIB.BASEBOARD_FAB2(SCH_1):P3E_CPU1_PE3_MP_RXP<12>
  DF11  P3E_CPU1_PE3_MP_RXP<11>  PE3_RX_DP<11>  @BASEBOARD_FAB2_LIB.BASEBOARD_FAB2(SCH_1):P3E_CPU1_PE3_MP_RXP<11>
  DE12  P3E_CPU1_PE3_MP_RXP<10>  PE3_RX_DP<10>  @BASEBOARD_FAB2_LIB.BASEBOARD_FAB2(SCH_1):P3E_CPU1_PE3_MP_RXP<10>
  DY17  P3E_CPU1_PE3_MP_RXP<0>  PE3_RX_DP<0>  @BASEBOARD_FAB2_LIB.BASEBOARD_FAB2(SCH_1):P3E_CPU1_PE3_MP_RXP<0>
  DJ12  P3E_CPU1_PE3_MP_RXN<9>  PE3_RX_DN<9>  @BASEBOARD_FAB2_LIB.BASEBOARD_FAB2(SCH_1):P3E_CPU1_PE3_MP_RXN<9>
  DL12  P3E_CPU1_PE3_MP_RXN<8>  PE3_RX_DN<8>  @BASEBOARD_FAB2_LIB.BASEBOARD_FAB2(SCH_1):P3E_CPU1_PE3_MP_RXN<8>
  DL14  P3E_CPU1_PE3_MP_RXN<7>  PE3_RX_DN<7>  @BASEBOARD_FAB2_LIB.BASEBOARD_FAB2(SCH_1):P3E_CPU1_PE3_MP_RXN<7>
  DN14  P3E_CPU1_PE3_MP_RXN<6>  PE3_RX_DN<6>  @BASEBOARD_FAB2_LIB.BASEBOARD_FAB2(SCH_1):P3E_CPU1_PE3_MP_RXN<6>
  DR14  P3E_CPU1_PE3_MP_RXN<5>  PE3_RX_DN<5>  @BASEBOARD_FAB2_LIB.BASEBOARD_FAB2(SCH_1):P3E_CPU1_PE3_MP_RXN<5>
  DR16  P3E_CPU1_PE3_MP_RXN<4>  PE3_RX_DN<4>  @BASEBOARD_FAB2_LIB.BASEBOARD_FAB2(SCH_1):P3E_CPU1_PE3_MP_RXN<4>
  DT19  P3E_CPU1_PE3_MP_RXN<3>  PE3_RX_DN<3>  @BASEBOARD_FAB2_LIB.BASEBOARD_FAB2(SCH_1):P3E_CPU1_PE3_MP_RXN<3>
  DW16  P3E_CPU1_PE3_MP_RXN<2>  PE3_RX_DN<2>  @BASEBOARD_FAB2_LIB.BASEBOARD_FAB2(SCH_1):P3E_CPU1_PE3_MP_RXN<2>
  DW18  P3E_CPU1_PE3_MP_RXN<1>  PE3_RX_DN<1>  @BASEBOARD_FAB2_LIB.BASEBOARD_FAB2(SCH_1):P3E_CPU1_PE3_MP_RXN<1>
  CV9  P3E_CPU1_PE3_MP_RXN<15>  PE3_RX_DN<15>  @BASEBOARD_FAB2_LIB.BASEBOARD_FAB2(SCH_1):P3E_CPU1_PE3_MP_RXN<15>
  CY11  P3E_CPU1_PE3_MP_RXN<14>  PE3_RX_DN<14>  @BASEBOARD_FAB2_LIB.BASEBOARD_FAB2(SCH_1):P3E_CPU1_PE3_MP_RXN<14>
  DB11  P3E_CPU1_PE3_MP_RXN<13>  PE3_RX_DN<13>  @BASEBOARD_FAB2_LIB.BASEBOARD_FAB2(SCH_1):P3E_CPU1_PE3_MP_RXN<13>
  DC12  P3E_CPU1_PE3_MP_RXN<12>  PE3_RX_DP<12>  @BASEBOARD_FAB2_LIB.BASEBOARD_FAB2(SCH_1):P3E_CPU1_PE3_MP_RXN<12>
  DG10  P3E_CPU1_PE3_MP_RXN<11>  PE3_RX_DN<11>  @BASEBOARD_FAB2_LIB.BASEBOARD_FAB2(SCH_1):P3E_CPU1_PE3_MP_RXN<11>
  DG12  P3E_CPU1_PE3_MP_RXN<10>  PE3_RX_DN<10>  @BASEBOARD_FAB2_LIB.BASEBOARD_FAB2(SCH_1):P3E_CPU1_PE3_MP_RXN<10>
  EA18  P3E_CPU1_PE3_MP_RXN<0>  PE3_RX_DN<0>  @BASEBOARD_FAB2_LIB.BASEBOARD_FAB2(SCH_1):P3E_CPU1_PE3_MP_RXN<0>

SKX_EXT_B_BGA1  I68  U2D1   [SKX_EXT_B_BGA1-IC,TBD]
  BY3  TP_P3E_CPU1_PE2_RSR_TXP<9>  PE2_TX_DP<9>  @BASEBOARD_FAB2_LIB.BASEBOARD_FAB2(SCH_1):TP_P3E_CPU1_PE2_RSR_TXP<9>
  CD3  TP_P3E_CPU1_PE2_RSR_TXP<8>  PE2_TX_DP<8>  @BASEBOARD_FAB2_LIB.BASEBOARD_FAB2(SCH_1):TP_P3E_CPU1_PE2_RSR_TXP<8>
  CE4  TP_P3E_CPU1_PE2_RSR_TXP<7>  PE2_TX_DP<7>  @BASEBOARD_FAB2_LIB.BASEBOARD_FAB2(SCH_1):TP_P3E_CPU1_PE2_RSR_TXP<7>
  CE2  TP_P3E_CPU1_PE2_RSR_TXP<6>  PE2_TX_DP<6>  @BASEBOARD_FAB2_LIB.BASEBOARD_FAB2(SCH_1):TP_P3E_CPU1_PE2_RSR_TXP<6>
  CK3  TP_P3E_CPU1_PE2_RSR_TXP<5>  PE2_TX_DP<5>  @BASEBOARD_FAB2_LIB.BASEBOARD_FAB2(SCH_1):TP_P3E_CPU1_PE2_RSR_TXP<5>
  CK1  TP_P3E_CPU1_PE2_RSR_TXP<4>  PE2_TX_DP<4>  @BASEBOARD_FAB2_LIB.BASEBOARD_FAB2(SCH_1):TP_P3E_CPU1_PE2_RSR_TXP<4>
  CP3  TP_P3E_CPU1_PE2_RSR_TXP<3>  PE2_TX_DP<3>  @BASEBOARD_FAB2_LIB.BASEBOARD_FAB2(SCH_1):TP_P3E_CPU1_PE2_RSR_TXP<3>
  CR2  TP_P3E_CPU1_PE2_RSR_TXP<2>  PE2_TX_DP<2>  @BASEBOARD_FAB2_LIB.BASEBOARD_FAB2(SCH_1):TP_P3E_CPU1_PE2_RSR_TXP<2>
  CU2  TP_P3E_CPU1_PE2_RSR_TXP<1>  PE2_TX_DP<1>  @BASEBOARD_FAB2_LIB.BASEBOARD_FAB2(SCH_1):TP_P3E_CPU1_PE2_RSR_TXP<1>
  BK5  TP_P3E_CPU1_PE2_RSR_TXP<15>  PE2_TX_DP<15>  @BASEBOARD_FAB2_LIB.BASEBOARD_FAB2(SCH_1):TP_P3E_CPU1_PE2_RSR_TXP<15>
  BM3  TP_P3E_CPU1_PE2_RSR_TXP<14>  PE2_TX_DP<14>  @BASEBOARD_FAB2_LIB.BASEBOARD_FAB2(SCH_1):TP_P3E_CPU1_PE2_RSR_TXP<14>
  BN4  TP_P3E_CPU1_PE2_RSR_TXP<13>  PE2_TX_DP<13>  @BASEBOARD_FAB2_LIB.BASEBOARD_FAB2(SCH_1):TP_P3E_CPU1_PE2_RSR_TXP<13>
  BR4  TP_P3E_CPU1_PE2_RSR_TXP<12>  PE2_TX_DP<12>  @BASEBOARD_FAB2_LIB.BASEBOARD_FAB2(SCH_1):TP_P3E_CPU1_PE2_RSR_TXP<12>
  BV3  TP_P3E_CPU1_PE2_RSR_TXP<11>  PE2_TX_DP<11>  @BASEBOARD_FAB2_LIB.BASEBOARD_FAB2(SCH_1):TP_P3E_CPU1_PE2_RSR_TXP<11>
  BY5  TP_P3E_CPU1_PE2_RSR_TXP<10>  PE2_TX_DP<10>  @BASEBOARD_FAB2_LIB.BASEBOARD_FAB2(SCH_1):TP_P3E_CPU1_PE2_RSR_TXP<10>
  CW4  TP_P3E_CPU1_PE2_RSR_TXP<0>  PE2_TX_DP<0>  @BASEBOARD_FAB2_LIB.BASEBOARD_FAB2(SCH_1):TP_P3E_CPU1_PE2_RSR_TXP<0>
  CB3  TP_P3E_CPU1_PE2_RSR_TXN<9>  PE2_TX_DN<9>  @BASEBOARD_FAB2_LIB.BASEBOARD_FAB2(SCH_1):TP_P3E_CPU1_PE2_RSR_TXN<9>
  CC2  TP_P3E_CPU1_PE2_RSR_TXN<8>  PE2_TX_DN<8>  @BASEBOARD_FAB2_LIB.BASEBOARD_FAB2(SCH_1):TP_P3E_CPU1_PE2_RSR_TXN<8>
  CF3  TP_P3E_CPU1_PE2_RSR_TXN<7>  PE2_TX_DN<7>  @BASEBOARD_FAB2_LIB.BASEBOARD_FAB2(SCH_1):TP_P3E_CPU1_PE2_RSR_TXN<7>
  CG2  TP_P3E_CPU1_PE2_RSR_TXN<6>  PE2_TX_DN<6>  @BASEBOARD_FAB2_LIB.BASEBOARD_FAB2(SCH_1):TP_P3E_CPU1_PE2_RSR_TXN<6>
  CL2  TP_P3E_CPU1_PE2_RSR_TXN<5>  PE2_TX_DN<5>  @BASEBOARD_FAB2_LIB.BASEBOARD_FAB2(SCH_1):TP_P3E_CPU1_PE2_RSR_TXN<5>
  CM1  TP_P3E_CPU1_PE2_RSR_TXN<4>  PE2_TX_DN<4>  @BASEBOARD_FAB2_LIB.BASEBOARD_FAB2(SCH_1):TP_P3E_CPU1_PE2_RSR_TXN<4>
  CT3  TP_P3E_CPU1_PE2_RSR_TXN<3>  PE2_TX_DN<3>  @BASEBOARD_FAB2_LIB.BASEBOARD_FAB2(SCH_1):TP_P3E_CPU1_PE2_RSR_TXN<3>
  CT1  TP_P3E_CPU1_PE2_RSR_TXN<2>  PE2_TX_DN<2>  @BASEBOARD_FAB2_LIB.BASEBOARD_FAB2(SCH_1):TP_P3E_CPU1_PE2_RSR_TXN<2>
  CV3  TP_P3E_CPU1_PE2_RSR_TXN<1>  PE2_TX_DN<1>  @BASEBOARD_FAB2_LIB.BASEBOARD_FAB2(SCH_1):TP_P3E_CPU1_PE2_RSR_TXN<1>
  BM5  TP_P3E_CPU1_PE2_RSR_TXN<15>  PE2_TX_DN<15>  @BASEBOARD_FAB2_LIB.BASEBOARD_FAB2(SCH_1):TP_P3E_CPU1_PE2_RSR_TXN<15>
  BL4  TP_P3E_CPU1_PE2_RSR_TXN<14>  PE2_TX_DN<14>  @BASEBOARD_FAB2_LIB.BASEBOARD_FAB2(SCH_1):TP_P3E_CPU1_PE2_RSR_TXN<14>
  BP5  TP_P3E_CPU1_PE2_RSR_TXN<13>  PE2_TX_DN<13>  @BASEBOARD_FAB2_LIB.BASEBOARD_FAB2(SCH_1):TP_P3E_CPU1_PE2_RSR_TXN<13>
  BU4  TP_P3E_CPU1_PE2_RSR_TXN<12>  PE2_TX_DN<12>  @BASEBOARD_FAB2_LIB.BASEBOARD_FAB2(SCH_1):TP_P3E_CPU1_PE2_RSR_TXN<12>
  BW4  TP_P3E_CPU1_PE2_RSR_TXN<11>  PE2_TX_DN<11>  @BASEBOARD_FAB2_LIB.BASEBOARD_FAB2(SCH_1):TP_P3E_CPU1_PE2_RSR_TXN<11>
  CA4  TP_P3E_CPU1_PE2_RSR_TXN<10>  PE2_TX_DN<10>  @BASEBOARD_FAB2_LIB.BASEBOARD_FAB2(SCH_1):TP_P3E_CPU1_PE2_RSR_TXN<10>
  CY3  TP_P3E_CPU1_PE2_RSR_TXN<0>  PE2_TX_DN<0>  @BASEBOARD_FAB2_LIB.BASEBOARD_FAB2(SCH_1):TP_P3E_CPU1_PE2_RSR_TXN<0>
  BW8  TP_P3E_CPU1_PE2_RSR_RXP<9>  PE2_RX_DP<9>  @BASEBOARD_FAB2_LIB.BASEBOARD_FAB2(SCH_1):TP_P3E_CPU1_PE2_RSR_RXP<9>
  BV9  TP_P3E_CPU1_PE2_RSR_RXP<8>  PE2_RX_DP<8>  @BASEBOARD_FAB2_LIB.BASEBOARD_FAB2(SCH_1):TP_P3E_CPU1_PE2_RSR_RXP<8>
  CC8  TP_P3E_CPU1_PE2_RSR_RXP<7>  PE2_RX_DP<7>  @BASEBOARD_FAB2_LIB.BASEBOARD_FAB2(SCH_1):TP_P3E_CPU1_PE2_RSR_RXP<7>
  CD7  TP_P3E_CPU1_PE2_RSR_RXP<6>  PE2_RX_DP<6>  @BASEBOARD_FAB2_LIB.BASEBOARD_FAB2(SCH_1):TP_P3E_CPU1_PE2_RSR_RXP<6>
  CF7  TP_P3E_CPU1_PE2_RSR_RXP<5>  PE2_RX_DP<5>  @BASEBOARD_FAB2_LIB.BASEBOARD_FAB2(SCH_1):TP_P3E_CPU1_PE2_RSR_RXP<5>
  CH7  TP_P3E_CPU1_PE2_RSR_RXP<4>  PE2_RX_DP<4>  @BASEBOARD_FAB2_LIB.BASEBOARD_FAB2(SCH_1):TP_P3E_CPU1_PE2_RSR_RXP<4>
  CL6  TP_P3E_CPU1_PE2_RSR_RXP<3>  PE2_RX_DP<3>  @BASEBOARD_FAB2_LIB.BASEBOARD_FAB2(SCH_1):TP_P3E_CPU1_PE2_RSR_RXP<3>
  CN8  TP_P3E_CPU1_PE2_RSR_RXP<2>  PE2_RX_DP<2>  @BASEBOARD_FAB2_LIB.BASEBOARD_FAB2(SCH_1):TP_P3E_CPU1_PE2_RSR_RXP<2>
  CM9  TP_P3E_CPU1_PE2_RSR_RXP<1>  PE2_RX_DP<1>  @BASEBOARD_FAB2_LIB.BASEBOARD_FAB2(SCH_1):TP_P3E_CPU1_PE2_RSR_RXP<1>
  BJ10  TP_P3E_CPU1_PE2_RSR_RXP<15>  PE2_RX_DP<15>  @BASEBOARD_FAB2_LIB.BASEBOARD_FAB2(SCH_1):TP_P3E_CPU1_PE2_RSR_RXP<15>
  BJ8  TP_P3E_CPU1_PE2_RSR_RXP<14>  PE2_RX_DP<14>  @BASEBOARD_FAB2_LIB.BASEBOARD_FAB2(SCH_1):TP_P3E_CPU1_PE2_RSR_RXP<14>
  BM7  TP_P3E_CPU1_PE2_RSR_RXP<13>  PE2_RX_DP<13>  @BASEBOARD_FAB2_LIB.BASEBOARD_FAB2(SCH_1):TP_P3E_CPU1_PE2_RSR_RXP<13>
  BP9  TP_P3E_CPU1_PE2_RSR_RXP<12>  PE2_RX_DP<12>  @BASEBOARD_FAB2_LIB.BASEBOARD_FAB2(SCH_1):TP_P3E_CPU1_PE2_RSR_RXP<12>
  BP7  TP_P3E_CPU1_PE2_RSR_RXP<11>  PE2_RX_DP<11>  @BASEBOARD_FAB2_LIB.BASEBOARD_FAB2(SCH_1):TP_P3E_CPU1_PE2_RSR_RXP<11>
  BU6  TP_P3E_CPU1_PE2_RSR_RXP<10>  PE2_RX_DP<10>  @BASEBOARD_FAB2_LIB.BASEBOARD_FAB2(SCH_1):TP_P3E_CPU1_PE2_RSR_RXP<10>
  CR8  TP_P3E_CPU1_PE2_RSR_RXP<0>  PE2_RX_DP<0>  @BASEBOARD_FAB2_LIB.BASEBOARD_FAB2(SCH_1):TP_P3E_CPU1_PE2_RSR_RXP<0>
  BY7  TP_P3E_CPU1_PE2_RSR_RXN<9>  PE2_RX_DN<9>  @BASEBOARD_FAB2_LIB.BASEBOARD_FAB2(SCH_1):TP_P3E_CPU1_PE2_RSR_RXN<9>
  BY9  TP_P3E_CPU1_PE2_RSR_RXN<8>  PE2_RX_DN<8>  @BASEBOARD_FAB2_LIB.BASEBOARD_FAB2(SCH_1):TP_P3E_CPU1_PE2_RSR_RXN<8>
  CE8  TP_P3E_CPU1_PE2_RSR_RXN<7>  PE2_RX_DN<7>  @BASEBOARD_FAB2_LIB.BASEBOARD_FAB2(SCH_1):TP_P3E_CPU1_PE2_RSR_RXN<7>
  CE6  TP_P3E_CPU1_PE2_RSR_RXN<6>  PE2_RX_DN<6>  @BASEBOARD_FAB2_LIB.BASEBOARD_FAB2(SCH_1):TP_P3E_CPU1_PE2_RSR_RXN<6>
  CG8  TP_P3E_CPU1_PE2_RSR_RXN<5>  PE2_RX_DN<5>  @BASEBOARD_FAB2_LIB.BASEBOARD_FAB2(SCH_1):TP_P3E_CPU1_PE2_RSR_RXN<5>
  CK7  TP_P3E_CPU1_PE2_RSR_RXN<4>  PE2_RX_DN<4>  @BASEBOARD_FAB2_LIB.BASEBOARD_FAB2(SCH_1):TP_P3E_CPU1_PE2_RSR_RXN<4>
  CM7  TP_P3E_CPU1_PE2_RSR_RXN<3>  PE2_RX_DN<3>  @BASEBOARD_FAB2_LIB.BASEBOARD_FAB2(SCH_1):TP_P3E_CPU1_PE2_RSR_RXN<3>
  CP7  TP_P3E_CPU1_PE2_RSR_RXN<2>  PE2_RX_DN<2>  @BASEBOARD_FAB2_LIB.BASEBOARD_FAB2(SCH_1):TP_P3E_CPU1_PE2_RSR_RXN<2>
  CP9  TP_P3E_CPU1_PE2_RSR_RXN<1>  PE2_RX_DN<1>  @BASEBOARD_FAB2_LIB.BASEBOARD_FAB2(SCH_1):TP_P3E_CPU1_PE2_RSR_RXN<1>
  BK9  TP_P3E_CPU1_PE2_RSR_RXN<15>  PE2_RX_DN<15>  @BASEBOARD_FAB2_LIB.BASEBOARD_FAB2(SCH_1):TP_P3E_CPU1_PE2_RSR_RXN<15>
  BL8  TP_P3E_CPU1_PE2_RSR_RXN<14>  PE2_RX_DN<14>  @BASEBOARD_FAB2_LIB.BASEBOARD_FAB2(SCH_1):TP_P3E_CPU1_PE2_RSR_RXN<14>
  BN8  TP_P3E_CPU1_PE2_RSR_RXN<13>  PE2_RX_DN<13>  @BASEBOARD_FAB2_LIB.BASEBOARD_FAB2(SCH_1):TP_P3E_CPU1_PE2_RSR_RXN<13>
  BR8  TP_P3E_CPU1_PE2_RSR_RXN<12>  PE2_RX_DN<12>  @BASEBOARD_FAB2_LIB.BASEBOARD_FAB2(SCH_1):TP_P3E_CPU1_PE2_RSR_RXN<12>
  BT7  TP_P3E_CPU1_PE2_RSR_RXN<11>  PE2_RX_DN<11>  @BASEBOARD_FAB2_LIB.BASEBOARD_FAB2(SCH_1):TP_P3E_CPU1_PE2_RSR_RXN<11>
  BV7  TP_P3E_CPU1_PE2_RSR_RXN<10>  PE2_RX_DN<10>  @BASEBOARD_FAB2_LIB.BASEBOARD_FAB2(SCH_1):TP_P3E_CPU1_PE2_RSR_RXN<10>
  CT9  TP_P3E_CPU1_PE2_RSR_RXN<0>  PE2_RX_DN<0>  @BASEBOARD_FAB2_LIB.BASEBOARD_FAB2(SCH_1):TP_P3E_CPU1_PE2_RSR_RXN<0>

SKX_EXT_B_BGA1  I68  U2D1   [SKX_EXT_B_BGA1-IC,TBD]
  DU2  TP_P3E_CPU1_PE1_RSR3_TXP<9>  PE1_TX_DP<9>  @BASEBOARD_FAB2_LIB.BASEBOARD_FAB2(SCH_1):TP_P3E_CPU1_PE1_RSR3_TXP<9>
  DR4  TP_P3E_CPU1_PE1_RSR3_TXP<8>  PE1_TX_DP<8>  @BASEBOARD_FAB2_LIB.BASEBOARD_FAB2(SCH_1):TP_P3E_CPU1_PE1_RSR3_TXP<8>
  EC8  TP_P3E_CPU1_PE1_RSR3_TXP<15>  PE1_TX_DP<15>  @BASEBOARD_FAB2_LIB.BASEBOARD_FAB2(SCH_1):TP_P3E_CPU1_PE1_RSR3_TXP<15>
  EB7  TP_P3E_CPU1_PE1_RSR3_TXP<14>  PE1_TX_DP<14>  @BASEBOARD_FAB2_LIB.BASEBOARD_FAB2(SCH_1):TP_P3E_CPU1_PE1_RSR3_TXP<14>
  DW6  TP_P3E_CPU1_PE1_RSR3_TXP<13>  PE1_TX_DP<13>  @BASEBOARD_FAB2_LIB.BASEBOARD_FAB2(SCH_1):TP_P3E_CPU1_PE1_RSR3_TXP<13>
  DT7  TP_P3E_CPU1_PE1_RSR3_TXP<12>  PE1_TX_DP<12>  @BASEBOARD_FAB2_LIB.BASEBOARD_FAB2(SCH_1):TP_P3E_CPU1_PE1_RSR3_TXP<12>
  DV5  TP_P3E_CPU1_PE1_RSR3_TXP<11>  PE1_TX_DP<11>  @BASEBOARD_FAB2_LIB.BASEBOARD_FAB2(SCH_1):TP_P3E_CPU1_PE1_RSR3_TXP<11>
  DU4  TP_P3E_CPU1_PE1_RSR3_TXP<10>  PE1_TX_DP<10>  @BASEBOARD_FAB2_LIB.BASEBOARD_FAB2(SCH_1):TP_P3E_CPU1_PE1_RSR3_TXP<10>
  DV3  TP_P3E_CPU1_PE1_RSR3_TXN<9>  PE1_TX_DN<9>  @BASEBOARD_FAB2_LIB.BASEBOARD_FAB2(SCH_1):TP_P3E_CPU1_PE1_RSR3_TXN<9>
  DT5  TP_P3E_CPU1_PE1_RSR3_TXN<8>  PE1_TX_DN<8>  @BASEBOARD_FAB2_LIB.BASEBOARD_FAB2(SCH_1):TP_P3E_CPU1_PE1_RSR3_TXN<8>
  ED9  TP_P3E_CPU1_PE1_RSR3_TXN<15>  PE1_TX_DN<15>  @BASEBOARD_FAB2_LIB.BASEBOARD_FAB2(SCH_1):TP_P3E_CPU1_PE1_RSR3_TXN<15>
  EA8  TP_P3E_CPU1_PE1_RSR3_TXN<14>  PE1_TX_DN<14>  @BASEBOARD_FAB2_LIB.BASEBOARD_FAB2(SCH_1):TP_P3E_CPU1_PE1_RSR3_TXN<14>
  DY7  TP_P3E_CPU1_PE1_RSR3_TXN<13>  PE1_TX_DN<13>  @BASEBOARD_FAB2_LIB.BASEBOARD_FAB2(SCH_1):TP_P3E_CPU1_PE1_RSR3_TXN<13>
  DV7  TP_P3E_CPU1_PE1_RSR3_TXN<12>  PE1_TX_DN<12>  @BASEBOARD_FAB2_LIB.BASEBOARD_FAB2(SCH_1):TP_P3E_CPU1_PE1_RSR3_TXN<12>
  DU6  TP_P3E_CPU1_PE1_RSR3_TXN<11>  PE1_TX_DN<11>  @BASEBOARD_FAB2_LIB.BASEBOARD_FAB2(SCH_1):TP_P3E_CPU1_PE1_RSR3_TXN<11>
  DW4  TP_P3E_CPU1_PE1_RSR3_TXN<10>  PE1_TX_DN<10>  @BASEBOARD_FAB2_LIB.BASEBOARD_FAB2(SCH_1):TP_P3E_CPU1_PE1_RSR3_TXN<10>
  DN10  TP_P3E_CPU1_PE1_RSR3_RXP<9>  PE1_RX_DP<9>  @BASEBOARD_FAB2_LIB.BASEBOARD_FAB2(SCH_1):TP_P3E_CPU1_PE1_RSR3_RXP<9>
  DK11  TP_P3E_CPU1_PE1_RSR3_RXP<8>  PE1_RX_DP<8>  @BASEBOARD_FAB2_LIB.BASEBOARD_FAB2(SCH_1):TP_P3E_CPU1_PE1_RSR3_RXP<8>
  DT15  TP_P3E_CPU1_PE1_RSR3_RXP<15>  PE1_RX_DP<15>  @BASEBOARD_FAB2_LIB.BASEBOARD_FAB2(SCH_1):TP_P3E_CPU1_PE1_RSR3_RXP<15>
  DV15  TP_P3E_CPU1_PE1_RSR3_RXP<14>  PE1_RX_DP<14>  @BASEBOARD_FAB2_LIB.BASEBOARD_FAB2(SCH_1):TP_P3E_CPU1_PE1_RSR3_RXP<14>
  DY13  TP_P3E_CPU1_PE1_RSR3_RXP<13>  PE1_RX_DP<13>  @BASEBOARD_FAB2_LIB.BASEBOARD_FAB2(SCH_1):TP_P3E_CPU1_PE1_RSR3_RXP<13>
  DU12  TP_P3E_CPU1_PE1_RSR3_RXP<12>  PE1_RX_DP<12>  @BASEBOARD_FAB2_LIB.BASEBOARD_FAB2(SCH_1):TP_P3E_CPU1_PE1_RSR3_RXP<12>
  DP13  TP_P3E_CPU1_PE1_RSR3_RXP<11>  PE1_RX_DP<11>  @BASEBOARD_FAB2_LIB.BASEBOARD_FAB2(SCH_1):TP_P3E_CPU1_PE1_RSR3_RXP<11>
  DR12  TP_P3E_CPU1_PE1_RSR3_RXP<10>  PE1_RX_DP<10>  @BASEBOARD_FAB2_LIB.BASEBOARD_FAB2(SCH_1):TP_P3E_CPU1_PE1_RSR3_RXP<10>
  DP11  TP_P3E_CPU1_PE1_RSR3_RXN<9>  PE1_RX_DN<9>  @BASEBOARD_FAB2_LIB.BASEBOARD_FAB2(SCH_1):TP_P3E_CPU1_PE1_RSR3_RXN<9>
  DM11  TP_P3E_CPU1_PE1_RSR3_RXN<8>  PE1_RX_DN<8>  @BASEBOARD_FAB2_LIB.BASEBOARD_FAB2(SCH_1):TP_P3E_CPU1_PE1_RSR3_RXN<8>
  DU16  TP_P3E_CPU1_PE1_RSR3_RXN<15>  PE1_RX_DN<15>  @BASEBOARD_FAB2_LIB.BASEBOARD_FAB2(SCH_1):TP_P3E_CPU1_PE1_RSR3_RXN<15>
  DY15  TP_P3E_CPU1_PE1_RSR3_RXN<14>  PE1_RX_DN<14>  @BASEBOARD_FAB2_LIB.BASEBOARD_FAB2(SCH_1):TP_P3E_CPU1_PE1_RSR3_RXN<14>
  DW14  TP_P3E_CPU1_PE1_RSR3_RXN<13>  PE1_RX_DN<13>  @BASEBOARD_FAB2_LIB.BASEBOARD_FAB2(SCH_1):TP_P3E_CPU1_PE1_RSR3_RXN<13>
  DV13  TP_P3E_CPU1_PE1_RSR3_RXN<12>  PE1_RX_DN<12>  @BASEBOARD_FAB2_LIB.BASEBOARD_FAB2(SCH_1):TP_P3E_CPU1_PE1_RSR3_RXN<12>
  DT13  TP_P3E_CPU1_PE1_RSR3_RXN<11>  PE1_RX_DN<11>  @BASEBOARD_FAB2_LIB.BASEBOARD_FAB2(SCH_1):TP_P3E_CPU1_PE1_RSR3_RXN<11>
  DT11  TP_P3E_CPU1_PE1_RSR3_RXN<10>  PE1_RX_DN<10>  @BASEBOARD_FAB2_LIB.BASEBOARD_FAB2(SCH_1):TP_P3E_CPU1_PE1_RSR3_RXN<10>
  DP3  TP_P3E_CPU1_PE1_MP_TXP<7>  PE1_TX_DP<7>  @BASEBOARD_FAB2_LIB.BASEBOARD_FAB2(SCH_1):TP_P3E_CPU1_PE1_MP_TXP<7>
  DL2  TP_P3E_CPU1_PE1_MP_TXP<6>  PE1_TX_DP<6>  @BASEBOARD_FAB2_LIB.BASEBOARD_FAB2(SCH_1):TP_P3E_CPU1_PE1_MP_TXP<6>
  DH3  TP_P3E_CPU1_PE1_MP_TXP<5>  PE1_TX_DP<5>  @BASEBOARD_FAB2_LIB.BASEBOARD_FAB2(SCH_1):TP_P3E_CPU1_PE1_MP_TXP<5>
  DF3  TP_P3E_CPU1_PE1_MP_TXP<4>  PE1_TX_DP<4>  @BASEBOARD_FAB2_LIB.BASEBOARD_FAB2(SCH_1):TP_P3E_CPU1_PE1_MP_TXP<4>
  DC4  TP_P3E_CPU1_PE1_MP_TXP<3>  PE1_TX_DP<3>  @BASEBOARD_FAB2_LIB.BASEBOARD_FAB2(SCH_1):TP_P3E_CPU1_PE1_MP_TXP<3>
  DD3  TP_P3E_CPU1_PE1_MP_TXP<2>  PE1_TX_DP<2>  @BASEBOARD_FAB2_LIB.BASEBOARD_FAB2(SCH_1):TP_P3E_CPU1_PE1_MP_TXP<2>
  DB1  TP_P3E_CPU1_PE1_MP_TXP<1>  PE1_TX_DP<1>  @BASEBOARD_FAB2_LIB.BASEBOARD_FAB2(SCH_1):TP_P3E_CPU1_PE1_MP_TXP<1>
  CW2  TP_P3E_CPU1_PE1_MP_TXP<0>  PE1_TX_DP<0>  @BASEBOARD_FAB2_LIB.BASEBOARD_FAB2(SCH_1):TP_P3E_CPU1_PE1_MP_TXP<0>
  DN4  TP_P3E_CPU1_PE1_MP_TXN<7>  PE1_TX_DN<7>  @BASEBOARD_FAB2_LIB.BASEBOARD_FAB2(SCH_1):TP_P3E_CPU1_PE1_MP_TXN<7>
  DM3  TP_P3E_CPU1_PE1_MP_TXN<6>  PE1_TX_DN<6>  @BASEBOARD_FAB2_LIB.BASEBOARD_FAB2(SCH_1):TP_P3E_CPU1_PE1_MP_TXN<6>
  DK3  TP_P3E_CPU1_PE1_MP_TXN<5>  PE1_TX_DN<5>  @BASEBOARD_FAB2_LIB.BASEBOARD_FAB2(SCH_1):TP_P3E_CPU1_PE1_MP_TXN<5>
  DG4  TP_P3E_CPU1_PE1_MP_TXN<4>  PE1_TX_DN<4>  @BASEBOARD_FAB2_LIB.BASEBOARD_FAB2(SCH_1):TP_P3E_CPU1_PE1_MP_TXN<4>
  DE4  TP_P3E_CPU1_PE1_MP_TXN<3>  PE1_TX_DN<3>  @BASEBOARD_FAB2_LIB.BASEBOARD_FAB2(SCH_1):TP_P3E_CPU1_PE1_MP_TXN<3>
  DE2  TP_P3E_CPU1_PE1_MP_TXN<2>  PE1_TX_DN<2>  @BASEBOARD_FAB2_LIB.BASEBOARD_FAB2(SCH_1):TP_P3E_CPU1_PE1_MP_TXN<2>
  DC2  TP_P3E_CPU1_PE1_MP_TXN<1>  PE1_TX_DN<1>  @BASEBOARD_FAB2_LIB.BASEBOARD_FAB2(SCH_1):TP_P3E_CPU1_PE1_MP_TXN<1>
  DA2  TP_P3E_CPU1_PE1_MP_TXN<0>  PE1_TX_DN<0>  @BASEBOARD_FAB2_LIB.BASEBOARD_FAB2(SCH_1):TP_P3E_CPU1_PE1_MP_TXN<0>
  DL10  TP_P3E_CPU1_PE1_MP_RXP<7>  PE1_RX_DP<7>  @BASEBOARD_FAB2_LIB.BASEBOARD_FAB2(SCH_1):TP_P3E_CPU1_PE1_MP_RXP<7>
  DJ8  TP_P3E_CPU1_PE1_MP_RXP<6>  PE1_RX_DP<6>  @BASEBOARD_FAB2_LIB.BASEBOARD_FAB2(SCH_1):TP_P3E_CPU1_PE1_MP_RXP<6>
  DF9  TP_P3E_CPU1_PE1_MP_RXP<5>  PE1_RX_DP<5>  @BASEBOARD_FAB2_LIB.BASEBOARD_FAB2(SCH_1):TP_P3E_CPU1_PE1_MP_RXP<5>
  DD9  TP_P3E_CPU1_PE1_MP_RXP<4>  PE1_RX_DP<4>  @BASEBOARD_FAB2_LIB.BASEBOARD_FAB2(SCH_1):TP_P3E_CPU1_PE1_MP_RXP<4>
  DA10  TP_P3E_CPU1_PE1_MP_RXP<3>  PE1_RX_DP<3>  @BASEBOARD_FAB2_LIB.BASEBOARD_FAB2(SCH_1):TP_P3E_CPU1_PE1_MP_RXP<3>
  DB9  TP_P3E_CPU1_PE1_MP_RXP<2>  PE1_RX_DP<2>  @BASEBOARD_FAB2_LIB.BASEBOARD_FAB2(SCH_1):TP_P3E_CPU1_PE1_MP_RXP<2>
  CY7  TP_P3E_CPU1_PE1_MP_RXP<1>  PE1_RX_DP<1>  @BASEBOARD_FAB2_LIB.BASEBOARD_FAB2(SCH_1):TP_P3E_CPU1_PE1_MP_RXP<1>
  CU8  TP_P3E_CPU1_PE1_MP_RXP<0>  PE1_RX_DP<0>  @BASEBOARD_FAB2_LIB.BASEBOARD_FAB2(SCH_1):TP_P3E_CPU1_PE1_MP_RXP<0>
  DM9  TP_P3E_CPU1_PE1_MP_RXN<7>  PE1_RX_DN<7>  @BASEBOARD_FAB2_LIB.BASEBOARD_FAB2(SCH_1):TP_P3E_CPU1_PE1_MP_RXN<7>
  DK9  TP_P3E_CPU1_PE1_MP_RXN<6>  PE1_RX_DN<6>  @BASEBOARD_FAB2_LIB.BASEBOARD_FAB2(SCH_1):TP_P3E_CPU1_PE1_MP_RXN<6>
  DH9  TP_P3E_CPU1_PE1_MP_RXN<5>  PE1_RX_DN<5>  @BASEBOARD_FAB2_LIB.BASEBOARD_FAB2(SCH_1):TP_P3E_CPU1_PE1_MP_RXN<5>
  DE10  TP_P3E_CPU1_PE1_MP_RXN<4>  PE1_RX_DN<4>  @BASEBOARD_FAB2_LIB.BASEBOARD_FAB2(SCH_1):TP_P3E_CPU1_PE1_MP_RXN<4>
  DC10  TP_P3E_CPU1_PE1_MP_RXN<3>  PE1_RX_DN<3>  @BASEBOARD_FAB2_LIB.BASEBOARD_FAB2(SCH_1):TP_P3E_CPU1_PE1_MP_RXN<3>
  DC8  TP_P3E_CPU1_PE1_MP_RXN<2>  PE1_RX_DN<2>  @BASEBOARD_FAB2_LIB.BASEBOARD_FAB2(SCH_1):TP_P3E_CPU1_PE1_MP_RXN<2>
  DA8  TP_P3E_CPU1_PE1_MP_RXN<1>  PE1_RX_DN<1>  @BASEBOARD_FAB2_LIB.BASEBOARD_FAB2(SCH_1):TP_P3E_CPU1_PE1_MP_RXN<1>
  CW8  TP_P3E_CPU1_PE1_MP_RXN<0>  PE1_RX_DN<0>  @BASEBOARD_FAB2_LIB.BASEBOARD_FAB2(SCH_1):TP_P3E_CPU1_PE1_MP_RXN<0>

SKX_EXT_B_BGA1  I23  U2D1   [SKX_EXT_B_BGA1-IC,TBD]
  BP23  TP_SMB_CPU1_CD_HFI0_I2CDAT  CD_HFI0_I2CDAT  @BASEBOARD_FAB2_LIB.BASEBOARD_FAB2(SCH_1):TP_SMB_CPU1_CD_HFI0_I2CDAT
  BN22  TP_SMB_CPU1_CD_HFI0_I2CCLK  CD_HFI0_I2CCLK  @BASEBOARD_FAB2_LIB.BASEBOARD_FAB2(SCH_1):TP_SMB_CPU1_CD_HFI0_I2CCLK
  BN24  TP_RST_CPU1_CD_HFI0_N  CD_HFI0_RESET_N  @BASEBOARD_FAB2_LIB.BASEBOARD_FAB2(SCH_1):TP_RST_CPU1_CD_HFI0_N
  BK21  TP_LED_CPU1_CD_HFI0_N  CD_HFI0_LED_N  @BASEBOARD_FAB2_LIB.BASEBOARD_FAB2(SCH_1):TP_LED_CPU1_CD_HFI0_N
  BP19  TP_IRQ_CPU1_CD_HFI0_N  CD_HFI0_INT_N  @BASEBOARD_FAB2_LIB.BASEBOARD_FAB2(SCH_1):TP_IRQ_CPU1_CD_HFI0_N
  BR20  TP_FM_CPU1_CD_HFI0_MODPRST_N  CD_HFI0_MODPRST_N  @BASEBOARD_FAB2_LIB.BASEBOARD_FAB2(SCH_1):TP_FM_CPU1_CD_HFI0_MODPRST_N
  AR62  TP_CPU1_RSVD_190  RSVD<190>  @BASEBOARD_FAB2_LIB.BASEBOARD_FAB2(SCH_1):TP_CPU1_RSVD_190
  AT13  TP_CPU1_RSVD_189  RSVD<189>  @BASEBOARD_FAB2_LIB.BASEBOARD_FAB2(SCH_1):TP_CPU1_RSVD_189
  AV77  TP_CPU1_RSVD_186  RSVD<186>  @BASEBOARD_FAB2_LIB.BASEBOARD_FAB2(SCH_1):TP_CPU1_RSVD_186
  AW64  TP_CPU1_RSVD_184  RSVD<184>  @BASEBOARD_FAB2_LIB.BASEBOARD_FAB2(SCH_1):TP_CPU1_RSVD_184
  AW76  TP_CPU1_RSVD_183  RSVD<183>  @BASEBOARD_FAB2_LIB.BASEBOARD_FAB2(SCH_1):TP_CPU1_RSVD_183
  AY65  TP_CPU1_RSVD_182  RSVD<182>  @BASEBOARD_FAB2_LIB.BASEBOARD_FAB2(SCH_1):TP_CPU1_RSVD_182
  AY67  TP_CPU1_RSVD_181  RSVD<181>  @BASEBOARD_FAB2_LIB.BASEBOARD_FAB2(SCH_1):TP_CPU1_RSVD_181
  AY75  TP_CPU1_RSVD_180  RSVD<180>  @BASEBOARD_FAB2_LIB.BASEBOARD_FAB2(SCH_1):TP_CPU1_RSVD_180
  AY77  TP_CPU1_RSVD_179  RSVD<179>  @BASEBOARD_FAB2_LIB.BASEBOARD_FAB2(SCH_1):TP_CPU1_RSVD_179
  BA14  TP_CPU1_RSVD_178  RSVD<178>  @BASEBOARD_FAB2_LIB.BASEBOARD_FAB2(SCH_1):TP_CPU1_RSVD_178
  BA16  TP_CPU1_RSVD_177  RSVD<177>  @BASEBOARD_FAB2_LIB.BASEBOARD_FAB2(SCH_1):TP_CPU1_RSVD_177
  BA18  TP_CPU1_RSVD_176  RSVD<176>  @BASEBOARD_FAB2_LIB.BASEBOARD_FAB2(SCH_1):TP_CPU1_RSVD_176
  BA22  TP_CPU1_RSVD_175  RSVD<175>  @BASEBOARD_FAB2_LIB.BASEBOARD_FAB2(SCH_1):TP_CPU1_RSVD_175
  BA64  TP_CPU1_RSVD_174  RSVD<174>  @BASEBOARD_FAB2_LIB.BASEBOARD_FAB2(SCH_1):TP_CPU1_RSVD_174
  BA66  TP_CPU1_RSVD_173  RSVD<173>  @BASEBOARD_FAB2_LIB.BASEBOARD_FAB2(SCH_1):TP_CPU1_RSVD_173
  BA76  TP_CPU1_RSVD_172  RSVD<172>  @BASEBOARD_FAB2_LIB.BASEBOARD_FAB2(SCH_1):TP_CPU1_RSVD_172
  CR4  TP_CPU1_DMI_TX_DP3  DMI_TX_DP<3>  @BASEBOARD_FAB2_LIB.BASEBOARD_FAB2(SCH_1):TP_CPU1_DMI_TX_DP3
  CM3  TP_CPU1_DMI_TX_DP2  DMI_TX_DP<2>  @BASEBOARD_FAB2_LIB.BASEBOARD_FAB2(SCH_1):TP_CPU1_DMI_TX_DP2
  CL4  TP_CPU1_DMI_TX_DP1  DMI_TX_DP<1>  @BASEBOARD_FAB2_LIB.BASEBOARD_FAB2(SCH_1):TP_CPU1_DMI_TX_DP1
  CH5  TP_CPU1_DMI_TX_DP0  DMI_TX_DP<0>  @BASEBOARD_FAB2_LIB.BASEBOARD_FAB2(SCH_1):TP_CPU1_DMI_TX_DP0
  CP5  TP_CPU1_DMI_TX_DN3  DMI_TX_DN<3>  @BASEBOARD_FAB2_LIB.BASEBOARD_FAB2(SCH_1):TP_CPU1_DMI_TX_DN3
  CN4  TP_CPU1_DMI_TX_DN2  DMI_TX_DN<2>  @BASEBOARD_FAB2_LIB.BASEBOARD_FAB2(SCH_1):TP_CPU1_DMI_TX_DN2
  CJ4  TP_CPU1_DMI_TX_DN1  DMI_TX_DN<1>  @BASEBOARD_FAB2_LIB.BASEBOARD_FAB2(SCH_1):TP_CPU1_DMI_TX_DN1
  CG4  TP_CPU1_DMI_TX_DN0  DMI_TX_DN<0>  @BASEBOARD_FAB2_LIB.BASEBOARD_FAB2(SCH_1):TP_CPU1_DMI_TX_DN0
  CV11  TP_CPU1_DMI_RX_DP3  DMI_RX_DP<3>  @BASEBOARD_FAB2_LIB.BASEBOARD_FAB2(SCH_1):TP_CPU1_DMI_RX_DP3
  CP11  TP_CPU1_DMI_RX_DP2  DMI_RX_DP<2>  @BASEBOARD_FAB2_LIB.BASEBOARD_FAB2(SCH_1):TP_CPU1_DMI_RX_DP2
  CN10  TP_CPU1_DMI_RX_DP1  DMI_RX_DP<1>  @BASEBOARD_FAB2_LIB.BASEBOARD_FAB2(SCH_1):TP_CPU1_DMI_RX_DP1
  CL10  TP_CPU1_DMI_RX_DP0  DMI_RX_DP<0>  @BASEBOARD_FAB2_LIB.BASEBOARD_FAB2(SCH_1):TP_CPU1_DMI_RX_DP0
  CT11  TP_CPU1_DMI_RX_DN3  DMI_RX_DN<3>  @BASEBOARD_FAB2_LIB.BASEBOARD_FAB2(SCH_1):TP_CPU1_DMI_RX_DN3
  CR12  TP_CPU1_DMI_RX_DN2  DMI_RX_DN<2>  @BASEBOARD_FAB2_LIB.BASEBOARD_FAB2(SCH_1):TP_CPU1_DMI_RX_DN2
  CM11  TP_CPU1_DMI_RX_DN1  DMI_RX_DN<1>  @BASEBOARD_FAB2_LIB.BASEBOARD_FAB2(SCH_1):TP_CPU1_DMI_RX_DN1
  CK9  TP_CPU1_DMI_RX_DN0  DMI_RX_DN<0>  @BASEBOARD_FAB2_LIB.BASEBOARD_FAB2(SCH_1):TP_CPU1_DMI_RX_DN0
  BK23  TP_CD_HFI1_CPU1_RESET_N  CD_HFI1_RESET_N  @BASEBOARD_FAB2_LIB.BASEBOARD_FAB2(SCH_1):TP_CD_HFI1_CPU1_RESET_N
  BT19  TP_CD_HFI1_CPU1_MODPRST_N  CD_HFI1_MODPRST_N  @BASEBOARD_FAB2_LIB.BASEBOARD_FAB2(SCH_1):TP_CD_HFI1_CPU1_MODPRST_N
  BM23  TP_CD_HFI1_CPU1_LED_N  CD_HFI1_LED_N  @BASEBOARD_FAB2_LIB.BASEBOARD_FAB2(SCH_1):TP_CD_HFI1_CPU1_LED_N
  BM21  TP_CD_HFI1_CPU1_INT_N  CD_HFI1_INT_N  @BASEBOARD_FAB2_LIB.BASEBOARD_FAB2(SCH_1):TP_CD_HFI1_CPU1_INT_N
  BJ22  TP_CD_HFI1_CPU1_I2CLK  CD_HFI1_I2CCLK  @BASEBOARD_FAB2_LIB.BASEBOARD_FAB2(SCH_1):TP_CD_HFI1_CPU1_I2CLK
  BH23  TP_CD_HFI1_CPU1_I2CDAT  CD_HFI1_I2CDAT  @BASEBOARD_FAB2_LIB.BASEBOARD_FAB2(SCH_1):TP_CD_HFI1_CPU1_I2CDAT
  CF25  RST_CD_CPU1_POR_N  CD_POR_N  @BASEBOARD_FAB2_LIB.BASEBOARD_FAB2(SCH_1):RST_CD_CPU1_POR_N
  AR20  PVCCMCP_CPU1   RSVD<193>  @BASEBOARD_FAB2_LIB.BASEBOARD_FAB2(SCH_1):PVCCMCP_CPU1
  AR22  PVCCMCP_CPU1   RSVD<192>  @BASEBOARD_FAB2_LIB.BASEBOARD_FAB2(SCH_1):PVCCMCP_CPU1
  AR26  PVCCMCP_CPU1   RSVD<191>  @BASEBOARD_FAB2_LIB.BASEBOARD_FAB2(SCH_1):PVCCMCP_CPU1
  AT23  PVCCMCP_CPU1   RSVD<188>  @BASEBOARD_FAB2_LIB.BASEBOARD_FAB2(SCH_1):PVCCMCP_CPU1
  AT25  PVCCMCP_CPU1   RSVD<187>  @BASEBOARD_FAB2_LIB.BASEBOARD_FAB2(SCH_1):PVCCMCP_CPU1
  CD23  JTAG_MCP_TRST_N  CD_TRST_N  @BASEBOARD_FAB2_LIB.BASEBOARD_FAB2(SCH_1):JTAG_MCP_TRST_N
  CE24  JTAG_MCP_TMS   CD_TMS  @BASEBOARD_FAB2_LIB.BASEBOARD_FAB2(SCH_1):JTAG_MCP_TMS
  CB23  JTAG_MCP_TCK   CD_TCLK  @BASEBOARD_FAB2_LIB.BASEBOARD_FAB2(SCH_1):JTAG_MCP_TCK
  CC22  JTAG_MCP_CPU1_TDO  CD_TDO  @BASEBOARD_FAB2_LIB.BASEBOARD_FAB2(SCH_1):JTAG_MCP_CPU1_TDO
  BY21  JTAG_MCP_CPU1_TDI  CD_TDI  @BASEBOARD_FAB2_LIB.BASEBOARD_FAB2(SCH_1):JTAG_MCP_CPU1_TDI
  BG16  CLK_156M_OSC_CPU1_HFI_DP  CD_HFI_REFCLK_DP  @BASEBOARD_FAB2_LIB.BASEBOARD_FAB2(SCH_1):CLK_156M_OSC_CPU1_HFI_DP
  BE16  CLK_156M_OSC_CPU1_HFI_DN  CD_HFI_REFCLK_DN  @BASEBOARD_FAB2_LIB.BASEBOARD_FAB2(SCH_1):CLK_156M_OSC_CPU1_HFI_DN
  BW24  CLK_100M_CPU1_PE_REFCLK_DP  CD_PE_REFCLK_DP  @BASEBOARD_FAB2_LIB.BASEBOARD_FAB2(SCH_1):CLK_100M_CPU1_PE_REFCLK_DP
  BU24  CLK_100M_CPU1_PE_REFCLK_DN  CD_PE_REFCLK_DN  @BASEBOARD_FAB2_LIB.BASEBOARD_FAB2(SCH_1):CLK_100M_CPU1_PE_REFCLK_DN

SKX_EXT_B_BGA1  I172  U2D1   [SKX_EXT_B_BGA1-IC,TBD]
  DK53  M_M_PAR        DDR5_PAR  @BASEBOARD_FAB2_LIB.BASEBOARD_FAB2(SCH_1):M_M_PAR
  DF47  M_M_ODT<3>     DDR5_ODT<3>  @BASEBOARD_FAB2_LIB.BASEBOARD_FAB2(SCH_1):M_M_ODT<3>
  DK49  M_M_ODT<2>     DDR5_ODT<2>  @BASEBOARD_FAB2_LIB.BASEBOARD_FAB2(SCH_1):M_M_ODT<2>
  DG48  M_M_ODT<1>     DDR5_ODT<1>  @BASEBOARD_FAB2_LIB.BASEBOARD_FAB2(SCH_1):M_M_ODT<1>
  DG50  M_M_ODT<0>     DDR5_ODT<0>  @BASEBOARD_FAB2_LIB.BASEBOARD_FAB2(SCH_1):M_M_ODT<0>
  DA58  M_M_MA<9>      DDR5_MA<9>  @BASEBOARD_FAB2_LIB.BASEBOARD_FAB2(SCH_1):M_M_MA<9>
  DD59  M_M_MA<8>      DDR5_MA<8>  @BASEBOARD_FAB2_LIB.BASEBOARD_FAB2(SCH_1):M_M_MA<8>
  DC60  M_M_MA<7>      DDR5_MA<7>  @BASEBOARD_FAB2_LIB.BASEBOARD_FAB2(SCH_1):M_M_MA<7>
  DK59  M_M_MA<6>      DDR5_MA<6>  @BASEBOARD_FAB2_LIB.BASEBOARD_FAB2(SCH_1):M_M_MA<6>
  DF59  M_M_MA<5>      DDR5_MA<5>  @BASEBOARD_FAB2_LIB.BASEBOARD_FAB2(SCH_1):M_M_MA<5>
  DJ58  M_M_MA<4>      DDR5_MA<4>  @BASEBOARD_FAB2_LIB.BASEBOARD_FAB2(SCH_1):M_M_MA<4>
  DG58  M_M_MA<3>      DDR5_MA<3>  @BASEBOARD_FAB2_LIB.BASEBOARD_FAB2(SCH_1):M_M_MA<3>
  DD57  M_M_MA<2>      DDR5_MA<2>  @BASEBOARD_FAB2_LIB.BASEBOARD_FAB2(SCH_1):M_M_MA<2>
  DC58  M_M_MA<1>      DDR5_MA<1>  @BASEBOARD_FAB2_LIB.BASEBOARD_FAB2(SCH_1):M_M_MA<1>
  DE46  M_M_MA<17>     DDR5_MA<17>  @BASEBOARD_FAB2_LIB.BASEBOARD_FAB2(SCH_1):M_M_MA<17>
  DG52  M_M_MA<16>     DDR5_MA<16>  @BASEBOARD_FAB2_LIB.BASEBOARD_FAB2(SCH_1):M_M_MA<16>
  DC54  M_M_MA<15>     DDR5_MA<15>  @BASEBOARD_FAB2_LIB.BASEBOARD_FAB2(SCH_1):M_M_MA<15>
  DJ50  M_M_MA<14>     DDR5_MA<14>  @BASEBOARD_FAB2_LIB.BASEBOARD_FAB2(SCH_1):M_M_MA<14>
  DD53  M_M_MA<13>     DDR5_MA<13>  @BASEBOARD_FAB2_LIB.BASEBOARD_FAB2(SCH_1):M_M_MA<13>
  DG60  M_M_MA<12>     DDR5_MA<12>  @BASEBOARD_FAB2_LIB.BASEBOARD_FAB2(SCH_1):M_M_MA<12>
  DA60  M_M_MA<11>     DDR5_MA<11>  @BASEBOARD_FAB2_LIB.BASEBOARD_FAB2(SCH_1):M_M_MA<11>
  DD55  M_M_MA<10>     DDR5_MA<10>  @BASEBOARD_FAB2_LIB.BASEBOARD_FAB2(SCH_1):M_M_MA<10>
  DF53  M_M_MA<0>      DDR5_MA<0>  @BASEBOARD_FAB2_LIB.BASEBOARD_FAB2(SCH_1):M_M_MA<0>
  CM69  M_M_ECC<7>     DDR5_ECC<7>  @BASEBOARD_FAB2_LIB.BASEBOARD_FAB2(SCH_1):M_M_ECC<7>
  CH69  M_M_ECC<6>     DDR5_ECC<6>  @BASEBOARD_FAB2_LIB.BASEBOARD_FAB2(SCH_1):M_M_ECC<6>
  CL72  M_M_ECC<5>     DDR5_ECC<5>  @BASEBOARD_FAB2_LIB.BASEBOARD_FAB2(SCH_1):M_M_ECC<5>
  CJ72  M_M_ECC<4>     DDR5_ECC<4>  @BASEBOARD_FAB2_LIB.BASEBOARD_FAB2(SCH_1):M_M_ECC<4>
  CL68  M_M_ECC<3>     DDR5_ECC<3>  @BASEBOARD_FAB2_LIB.BASEBOARD_FAB2(SCH_1):M_M_ECC<3>
  CJ68  M_M_ECC<2>     DDR5_ECC<2>  @BASEBOARD_FAB2_LIB.BASEBOARD_FAB2(SCH_1):M_M_ECC<2>
  CM71  M_M_ECC<1>     DDR5_ECC<1>  @BASEBOARD_FAB2_LIB.BASEBOARD_FAB2(SCH_1):M_M_ECC<1>
  CH71  M_M_ECC<0>     DDR5_ECC<0>  @BASEBOARD_FAB2_LIB.BASEBOARD_FAB2(SCH_1):M_M_ECC<0>
  CU74  M_M_DQS_DP<9>  DDR5_DQS_DP<9>  @BASEBOARD_FAB2_LIB.BASEBOARD_FAB2(SCH_1):M_M_DQS_DP<9>
  CL70  M_M_DQS_DP<8>  DDR5_DQS_DP<8>  @BASEBOARD_FAB2_LIB.BASEBOARD_FAB2(SCH_1):M_M_DQS_DP<8>
  DB29  M_M_DQS_DP<7>  DDR5_DQS_DP<7>  @BASEBOARD_FAB2_LIB.BASEBOARD_FAB2(SCH_1):M_M_DQS_DP<7>
  DB35  M_M_DQS_DP<6>  DDR5_DQS_DP<6>  @BASEBOARD_FAB2_LIB.BASEBOARD_FAB2(SCH_1):M_M_DQS_DP<6>
  DJ32  M_M_DQS_DP<5>  DDR5_DQS_DP<5>  @BASEBOARD_FAB2_LIB.BASEBOARD_FAB2(SCH_1):M_M_DQS_DP<5>
  DJ40  M_M_DQS_DP<4>  DDR5_DQS_DP<4>  @BASEBOARD_FAB2_LIB.BASEBOARD_FAB2(SCH_1):M_M_DQS_DP<4>
  CT65  M_M_DQS_DP<3>  DDR5_DQS_DP<3>  @BASEBOARD_FAB2_LIB.BASEBOARD_FAB2(SCH_1):M_M_DQS_DP<3>
  DK71  M_M_DQS_DP<2>  DDR5_DQS_DP<2>  @BASEBOARD_FAB2_LIB.BASEBOARD_FAB2(SCH_1):M_M_DQS_DP<2>
  DE76  M_M_DQS_DP<1>  DDR5_DQS_DP<1>  @BASEBOARD_FAB2_LIB.BASEBOARD_FAB2(SCH_1):M_M_DQS_DP<1>
  CG70  M_M_DQS_DP<17>  DDR5_DQS_DP<17>  @BASEBOARD_FAB2_LIB.BASEBOARD_FAB2(SCH_1):M_M_DQS_DP<17>
  CV29  M_M_DQS_DP<16>  DDR5_DQS_DP<16>  @BASEBOARD_FAB2_LIB.BASEBOARD_FAB2(SCH_1):M_M_DQS_DP<16>
  CV35  M_M_DQS_DP<15>  DDR5_DQS_DP<15>  @BASEBOARD_FAB2_LIB.BASEBOARD_FAB2(SCH_1):M_M_DQS_DP<15>
  DE32  M_M_DQS_DP<14>  DDR5_DQS_DP<14>  @BASEBOARD_FAB2_LIB.BASEBOARD_FAB2(SCH_1):M_M_DQS_DP<14>
  DC40  M_M_DQS_DP<13>  DDR5_DQS_DP<13>  @BASEBOARD_FAB2_LIB.BASEBOARD_FAB2(SCH_1):M_M_DQS_DP<13>
  CM65  M_M_DQS_DP<12>  DDR5_DQS_DP<12>  @BASEBOARD_FAB2_LIB.BASEBOARD_FAB2(SCH_1):M_M_DQS_DP<12>
  DH69  M_M_DQS_DP<11>  DDR5_DQS_DP<11>  @BASEBOARD_FAB2_LIB.BASEBOARD_FAB2(SCH_1):M_M_DQS_DP<11>
  DG74  M_M_DQS_DP<10>  DDR5_DQS_DP<10>  @BASEBOARD_FAB2_LIB.BASEBOARD_FAB2(SCH_1):M_M_DQS_DP<10>
  CR76  M_M_DQS_DP<0>  DDR5_DQS_DP<0>  @BASEBOARD_FAB2_LIB.BASEBOARD_FAB2(SCH_1):M_M_DQS_DP<0>
  CT75  M_M_DQS_DN<9>  DDR5_DQS_DN<9>  @BASEBOARD_FAB2_LIB.BASEBOARD_FAB2(SCH_1):M_M_DQS_DN<9>
  CN70  M_M_DQS_DN<8>  DDR5_DQS_DN<8>  @BASEBOARD_FAB2_LIB.BASEBOARD_FAB2(SCH_1):M_M_DQS_DN<8>
  DD29  M_M_DQS_DN<7>  DDR5_DQS_DN<7>  @BASEBOARD_FAB2_LIB.BASEBOARD_FAB2(SCH_1):M_M_DQS_DN<7>
  DD35  M_M_DQS_DN<6>  DDR5_DQS_DN<6>  @BASEBOARD_FAB2_LIB.BASEBOARD_FAB2(SCH_1):M_M_DQS_DN<6>
  DL32  M_M_DQS_DN<5>  DDR5_DQS_DN<5>  @BASEBOARD_FAB2_LIB.BASEBOARD_FAB2(SCH_1):M_M_DQS_DN<5>
  DG40  M_M_DQS_DN<4>  DDR5_DQS_DN<4>  @BASEBOARD_FAB2_LIB.BASEBOARD_FAB2(SCH_1):M_M_DQS_DN<4>
  CV65  M_M_DQS_DN<3>  DDR5_DQS_DN<3>  @BASEBOARD_FAB2_LIB.BASEBOARD_FAB2(SCH_1):M_M_DQS_DN<3>
  DL72  M_M_DQS_DN<2>  DDR5_DQS_DN<2>  @BASEBOARD_FAB2_LIB.BASEBOARD_FAB2(SCH_1):M_M_DQS_DN<2>
  DD77  M_M_DQS_DN<1>  DDR5_DQS_DN<1>  @BASEBOARD_FAB2_LIB.BASEBOARD_FAB2(SCH_1):M_M_DQS_DN<1>
  CJ70  M_M_DQS_DN<17>  DDR5_DQS_DN<17>  @BASEBOARD_FAB2_LIB.BASEBOARD_FAB2(SCH_1):M_M_DQS_DN<17>
  CY29  M_M_DQS_DN<16>  DDR5_DQS_DN<16>  @BASEBOARD_FAB2_LIB.BASEBOARD_FAB2(SCH_1):M_M_DQS_DN<16>
  CY35  M_M_DQS_DN<15>  DDR5_DQS_DN<15>  @BASEBOARD_FAB2_LIB.BASEBOARD_FAB2(SCH_1):M_M_DQS_DN<15>
  DG32  M_M_DQS_DN<14>  DDR5_DQS_DN<14>  @BASEBOARD_FAB2_LIB.BASEBOARD_FAB2(SCH_1):M_M_DQS_DN<14>
  DE40  M_M_DQS_DN<13>  DDR5_DQS_DN<13>  @BASEBOARD_FAB2_LIB.BASEBOARD_FAB2(SCH_1):M_M_DQS_DN<13>
  CP65  M_M_DQS_DN<12>  DDR5_DQS_DN<12>  @BASEBOARD_FAB2_LIB.BASEBOARD_FAB2(SCH_1):M_M_DQS_DN<12>
  DJ70  M_M_DQS_DN<11>  DDR5_DQS_DN<11>  @BASEBOARD_FAB2_LIB.BASEBOARD_FAB2(SCH_1):M_M_DQS_DN<11>
  DF75  M_M_DQS_DN<10>  DDR5_DQS_DN<10>  @BASEBOARD_FAB2_LIB.BASEBOARD_FAB2(SCH_1):M_M_DQS_DN<10>
  CP77  M_M_DQS_DN<0>  DDR5_DQS_DN<0>  @BASEBOARD_FAB2_LIB.BASEBOARD_FAB2(SCH_1):M_M_DQS_DN<0>
  DC76  M_M_DQ<9>      DDR5_DQ<9>  @BASEBOARD_FAB2_LIB.BASEBOARD_FAB2(SCH_1):M_M_DQ<9>
  DE74  M_M_DQ<8>      DDR5_DQ<8>  @BASEBOARD_FAB2_LIB.BASEBOARD_FAB2(SCH_1):M_M_DQ<8>
  CT77  M_M_DQ<7>      DDR5_DQ<7>  @BASEBOARD_FAB2_LIB.BASEBOARD_FAB2(SCH_1):M_M_DQ<7>
  CV75  M_M_DQ<6>      DDR5_DQ<6>  @BASEBOARD_FAB2_LIB.BASEBOARD_FAB2(SCH_1):M_M_DQ<6>
  DC28  M_M_DQ<63>     DDR5_DQ<63>  @BASEBOARD_FAB2_LIB.BASEBOARD_FAB2(SCH_1):M_M_DQ<63>
  CW28  M_M_DQ<62>     DDR5_DQ<62>  @BASEBOARD_FAB2_LIB.BASEBOARD_FAB2(SCH_1):M_M_DQ<62>
  DB31  M_M_DQ<61>     DDR5_DQ<61>  @BASEBOARD_FAB2_LIB.BASEBOARD_FAB2(SCH_1):M_M_DQ<61>
  CY31  M_M_DQ<60>     DDR5_DQ<60>  @BASEBOARD_FAB2_LIB.BASEBOARD_FAB2(SCH_1):M_M_DQ<60>
  CM75  M_M_DQ<5>      DDR5_DQ<5>  @BASEBOARD_FAB2_LIB.BASEBOARD_FAB2(SCH_1):M_M_DQ<5>
  DB27  M_M_DQ<59>     DDR5_DQ<59>  @BASEBOARD_FAB2_LIB.BASEBOARD_FAB2(SCH_1):M_M_DQ<59>
  CY27  M_M_DQ<58>     DDR5_DQ<58>  @BASEBOARD_FAB2_LIB.BASEBOARD_FAB2(SCH_1):M_M_DQ<58>
  DC30  M_M_DQ<57>     DDR5_DQ<57>  @BASEBOARD_FAB2_LIB.BASEBOARD_FAB2(SCH_1):M_M_DQ<57>
  CW30  M_M_DQ<56>     DDR5_DQ<56>  @BASEBOARD_FAB2_LIB.BASEBOARD_FAB2(SCH_1):M_M_DQ<56>
  DC34  M_M_DQ<55>     DDR5_DQ<55>  @BASEBOARD_FAB2_LIB.BASEBOARD_FAB2(SCH_1):M_M_DQ<55>
  CW34  M_M_DQ<54>     DDR5_DQ<54>  @BASEBOARD_FAB2_LIB.BASEBOARD_FAB2(SCH_1):M_M_DQ<54>
  DB37  M_M_DQ<53>     DDR5_DQ<53>  @BASEBOARD_FAB2_LIB.BASEBOARD_FAB2(SCH_1):M_M_DQ<53>
  CY37  M_M_DQ<52>     DDR5_DQ<52>  @BASEBOARD_FAB2_LIB.BASEBOARD_FAB2(SCH_1):M_M_DQ<52>
  DB33  M_M_DQ<51>     DDR5_DQ<51>  @BASEBOARD_FAB2_LIB.BASEBOARD_FAB2(SCH_1):M_M_DQ<51>
  CY33  M_M_DQ<50>     DDR5_DQ<50>  @BASEBOARD_FAB2_LIB.BASEBOARD_FAB2(SCH_1):M_M_DQ<50>
  CN74  M_M_DQ<4>      DDR5_DQ<4>  @BASEBOARD_FAB2_LIB.BASEBOARD_FAB2(SCH_1):M_M_DQ<4>
  DC36  M_M_DQ<49>     DDR5_DQ<49>  @BASEBOARD_FAB2_LIB.BASEBOARD_FAB2(SCH_1):M_M_DQ<49>
  CW36  M_M_DQ<48>     DDR5_DQ<48>  @BASEBOARD_FAB2_LIB.BASEBOARD_FAB2(SCH_1):M_M_DQ<48>
  DK31  M_M_DQ<47>     DDR5_DQ<47>  @BASEBOARD_FAB2_LIB.BASEBOARD_FAB2(SCH_1):M_M_DQ<47>
  DF31  M_M_DQ<46>     DDR5_DQ<46>  @BASEBOARD_FAB2_LIB.BASEBOARD_FAB2(SCH_1):M_M_DQ<46>
  DJ34  M_M_DQ<45>     DDR5_DQ<45>  @BASEBOARD_FAB2_LIB.BASEBOARD_FAB2(SCH_1):M_M_DQ<45>
  DG34  M_M_DQ<44>     DDR5_DQ<44>  @BASEBOARD_FAB2_LIB.BASEBOARD_FAB2(SCH_1):M_M_DQ<44>
  DJ30  M_M_DQ<43>     DDR5_DQ<43>  @BASEBOARD_FAB2_LIB.BASEBOARD_FAB2(SCH_1):M_M_DQ<43>
  DG30  M_M_DQ<42>     DDR5_DQ<42>  @BASEBOARD_FAB2_LIB.BASEBOARD_FAB2(SCH_1):M_M_DQ<42>
  DK33  M_M_DQ<41>     DDR5_DQ<41>  @BASEBOARD_FAB2_LIB.BASEBOARD_FAB2(SCH_1):M_M_DQ<41>
  DF33  M_M_DQ<40>     DDR5_DQ<40>  @BASEBOARD_FAB2_LIB.BASEBOARD_FAB2(SCH_1):M_M_DQ<40>
  CV77  M_M_DQ<3>      DDR5_DQ<3>  @BASEBOARD_FAB2_LIB.BASEBOARD_FAB2(SCH_1):M_M_DQ<3>
  DH39  M_M_DQ<39>     DDR5_DQ<39>  @BASEBOARD_FAB2_LIB.BASEBOARD_FAB2(SCH_1):M_M_DQ<39>
  DD39  M_M_DQ<38>     DDR5_DQ<38>  @BASEBOARD_FAB2_LIB.BASEBOARD_FAB2(SCH_1):M_M_DQ<38>
  DE42  M_M_DQ<37>     DDR5_DQ<37>  @BASEBOARD_FAB2_LIB.BASEBOARD_FAB2(SCH_1):M_M_DQ<37>
  DA42  M_M_DQ<36>     DDR5_DQ<36>  @BASEBOARD_FAB2_LIB.BASEBOARD_FAB2(SCH_1):M_M_DQ<36>
  DG38  M_M_DQ<35>     DDR5_DQ<35>  @BASEBOARD_FAB2_LIB.BASEBOARD_FAB2(SCH_1):M_M_DQ<35>
  DE38  M_M_DQ<34>     DDR5_DQ<34>  @BASEBOARD_FAB2_LIB.BASEBOARD_FAB2(SCH_1):M_M_DQ<34>
  DG42  M_M_DQ<33>     DDR5_DQ<33>  @BASEBOARD_FAB2_LIB.BASEBOARD_FAB2(SCH_1):M_M_DQ<33>
  DD41  M_M_DQ<32>     DDR5_DQ<32>  @BASEBOARD_FAB2_LIB.BASEBOARD_FAB2(SCH_1):M_M_DQ<32>
  CU64  M_M_DQ<31>     DDR5_DQ<31>  @BASEBOARD_FAB2_LIB.BASEBOARD_FAB2(SCH_1):M_M_DQ<31>
  CN64  M_M_DQ<30>     DDR5_DQ<30>  @BASEBOARD_FAB2_LIB.BASEBOARD_FAB2(SCH_1):M_M_DQ<30>
  CW76  M_M_DQ<2>      DDR5_DQ<2>  @BASEBOARD_FAB2_LIB.BASEBOARD_FAB2(SCH_1):M_M_DQ<2>
  CT67  M_M_DQ<29>     DDR5_DQ<29>  @BASEBOARD_FAB2_LIB.BASEBOARD_FAB2(SCH_1):M_M_DQ<29>
  CP67  M_M_DQ<28>     DDR5_DQ<28>  @BASEBOARD_FAB2_LIB.BASEBOARD_FAB2(SCH_1):M_M_DQ<28>
  CT63  M_M_DQ<27>     DDR5_DQ<27>  @BASEBOARD_FAB2_LIB.BASEBOARD_FAB2(SCH_1):M_M_DQ<27>
  CP63  M_M_DQ<26>     DDR5_DQ<26>  @BASEBOARD_FAB2_LIB.BASEBOARD_FAB2(SCH_1):M_M_DQ<26>
  CU66  M_M_DQ<25>     DDR5_DQ<25>  @BASEBOARD_FAB2_LIB.BASEBOARD_FAB2(SCH_1):M_M_DQ<25>
  CN66  M_M_DQ<24>     DDR5_DQ<24>  @BASEBOARD_FAB2_LIB.BASEBOARD_FAB2(SCH_1):M_M_DQ<24>
  DM71  M_M_DQ<23>     DDR5_DQ<23>  @BASEBOARD_FAB2_LIB.BASEBOARD_FAB2(SCH_1):M_M_DQ<23>
  DK69  M_M_DQ<22>     DDR5_DQ<22>  @BASEBOARD_FAB2_LIB.BASEBOARD_FAB2(SCH_1):M_M_DQ<22>
  DG72  M_M_DQ<21>     DDR5_DQ<21>  @BASEBOARD_FAB2_LIB.BASEBOARD_FAB2(SCH_1):M_M_DQ<21>
  DF71  M_M_DQ<20>     DDR5_DQ<20>  @BASEBOARD_FAB2_LIB.BASEBOARD_FAB2(SCH_1):M_M_DQ<20>
  CN76  M_M_DQ<1>      DDR5_DQ<1>  @BASEBOARD_FAB2_LIB.BASEBOARD_FAB2(SCH_1):M_M_DQ<1>
  DN70  M_M_DQ<19>     DDR5_DQ<19>  @BASEBOARD_FAB2_LIB.BASEBOARD_FAB2(SCH_1):M_M_DQ<19>
  DM69  M_M_DQ<18>     DDR5_DQ<18>  @BASEBOARD_FAB2_LIB.BASEBOARD_FAB2(SCH_1):M_M_DQ<18>
  DJ72  M_M_DQ<17>     DDR5_DQ<17>  @BASEBOARD_FAB2_LIB.BASEBOARD_FAB2(SCH_1):M_M_DQ<17>
  DG70  M_M_DQ<16>     DDR5_DQ<16>  @BASEBOARD_FAB2_LIB.BASEBOARD_FAB2(SCH_1):M_M_DQ<16>
  DH77  M_M_DQ<15>     DDR5_DQ<15>  @BASEBOARD_FAB2_LIB.BASEBOARD_FAB2(SCH_1):M_M_DQ<15>
  DF77  M_M_DQ<14>     DDR5_DQ<14>  @BASEBOARD_FAB2_LIB.BASEBOARD_FAB2(SCH_1):M_M_DQ<14>
  DB75  M_M_DQ<13>     DDR5_DQ<13>  @BASEBOARD_FAB2_LIB.BASEBOARD_FAB2(SCH_1):M_M_DQ<13>
  DC74  M_M_DQ<12>     DDR5_DQ<12>  @BASEBOARD_FAB2_LIB.BASEBOARD_FAB2(SCH_1):M_M_DQ<12>
  DJ76  M_M_DQ<11>     DDR5_DQ<11>  @BASEBOARD_FAB2_LIB.BASEBOARD_FAB2(SCH_1):M_M_DQ<11>
  DH75  M_M_DQ<10>     DDR5_DQ<10>  @BASEBOARD_FAB2_LIB.BASEBOARD_FAB2(SCH_1):M_M_DQ<10>
  CR74  M_M_DQ<0>      DDR5_DQ<0>  @BASEBOARD_FAB2_LIB.BASEBOARD_FAB2(SCH_1):M_M_DQ<0>
  DK45  M_M_CS_N<7>    DDR5_CS_N<7>  @BASEBOARD_FAB2_LIB.BASEBOARD_FAB2(SCH_1):M_M_CS_N<7>
  DM45  M_M_CS_N<6>    DDR5_CS_N<6>  @BASEBOARD_FAB2_LIB.BASEBOARD_FAB2(SCH_1):M_M_CS_N<6>
  DJ48  M_M_CS_N<5>    DDR5_CS_N<5>  @BASEBOARD_FAB2_LIB.BASEBOARD_FAB2(SCH_1):M_M_CS_N<5>
  DF51  M_M_CS_N<4>    DDR5_CS_N<4>  @BASEBOARD_FAB2_LIB.BASEBOARD_FAB2(SCH_1):M_M_CS_N<4>
  DG46  M_M_CS_N<3>    DDR5_CS_N<3>  @BASEBOARD_FAB2_LIB.BASEBOARD_FAB2(SCH_1):M_M_CS_N<3>
  DJ46  M_M_CS_N<2>    DDR5_CS_N<2>  @BASEBOARD_FAB2_LIB.BASEBOARD_FAB2(SCH_1):M_M_CS_N<2>
  DF49  M_M_CS_N<1>    DDR5_CS_N<1>  @BASEBOARD_FAB2_LIB.BASEBOARD_FAB2(SCH_1):M_M_CS_N<1>
  DK51  M_M_CS_N<0>    DDR5_CS_N<0>  @BASEBOARD_FAB2_LIB.BASEBOARD_FAB2(SCH_1):M_M_CS_N<0>
  DG56  M_M_CLK_DP<3>  DDR5_CLK_DP<3>  @BASEBOARD_FAB2_LIB.BASEBOARD_FAB2(SCH_1):M_M_CLK_DP<3>
  DJ56  M_M_CLK_DP<2>  DDR5_CLK_DP<2>  @BASEBOARD_FAB2_LIB.BASEBOARD_FAB2(SCH_1):M_M_CLK_DP<2>
  DG54  M_M_CLK_DP<1>  DDR5_CLK_DP<1>  @BASEBOARD_FAB2_LIB.BASEBOARD_FAB2(SCH_1):M_M_CLK_DP<1>
  DJ54  M_M_CLK_DP<0>  DDR5_CLK_DP<0>  @BASEBOARD_FAB2_LIB.BASEBOARD_FAB2(SCH_1):M_M_CLK_DP<0>
  DF57  M_M_CLK_DN<3>  DDR5_CLK_DN<3>  @BASEBOARD_FAB2_LIB.BASEBOARD_FAB2(SCH_1):M_M_CLK_DN<3>
  DK57  M_M_CLK_DN<2>  DDR5_CLK_DN<2>  @BASEBOARD_FAB2_LIB.BASEBOARD_FAB2(SCH_1):M_M_CLK_DN<2>
  DF55  M_M_CLK_DN<1>  DDR5_CLK_DN<1>  @BASEBOARD_FAB2_LIB.BASEBOARD_FAB2(SCH_1):M_M_CLK_DN<1>
  DK55  M_M_CLK_DN<0>  DDR5_CLK_DN<0>  @BASEBOARD_FAB2_LIB.BASEBOARD_FAB2(SCH_1):M_M_CLK_DN<0>
  DF63  M_M_CKE<3>     DDR5_CKE<3>  @BASEBOARD_FAB2_LIB.BASEBOARD_FAB2(SCH_1):M_M_CKE<3>
  DK63  M_M_CKE<2>     DDR5_CKE<2>  @BASEBOARD_FAB2_LIB.BASEBOARD_FAB2(SCH_1):M_M_CKE<2>
  DD63  M_M_CKE<1>     DDR5_CKE<1>  @BASEBOARD_FAB2_LIB.BASEBOARD_FAB2(SCH_1):M_M_CKE<1>
  DG62  M_M_CKE<0>     DDR5_CKE<0>  @BASEBOARD_FAB2_LIB.BASEBOARD_FAB2(SCH_1):M_M_CKE<0>
  DF45  M_M_C<2>       DDR5_CID<2>  @BASEBOARD_FAB2_LIB.BASEBOARD_FAB2(SCH_1):M_M_C<2>
  DF61  M_M_BG<1>      DDR5_BG<1>  @BASEBOARD_FAB2_LIB.BASEBOARD_FAB2(SCH_1):M_M_BG<1>
  DA62  M_M_BG<0>      DDR5_BG<0>  @BASEBOARD_FAB2_LIB.BASEBOARD_FAB2(SCH_1):M_M_BG<0>
  DC56  M_M_BA<1>      DDR5_BA<1>  @BASEBOARD_FAB2_LIB.BASEBOARD_FAB2(SCH_1):M_M_BA<1>
  DJ52  M_M_BA<0>      DDR5_BA<0>  @BASEBOARD_FAB2_LIB.BASEBOARD_FAB2(SCH_1):M_M_BA<0>
  DD61  M_M_ALERT_N    DDR5_ALERT_N  @BASEBOARD_FAB2_LIB.BASEBOARD_FAB2(SCH_1):M_M_ALERT_N
  DC62  M_M_ACT_N      DDR5_ACT_N  @BASEBOARD_FAB2_LIB.BASEBOARD_FAB2(SCH_1):M_M_ACT_N

SKX_EXT_B_BGA1  I172  U2D1   [SKX_EXT_B_BGA1-IC,TBD]
  DV53  M_L_PAR        DDR4_PAR  @BASEBOARD_FAB2_LIB.BASEBOARD_FAB2(SCH_1):M_L_PAR
  DM47  M_L_ODT<3>     DDR4_ODT<3>  @BASEBOARD_FAB2_LIB.BASEBOARD_FAB2(SCH_1):M_L_ODT<3>
  DT49  M_L_ODT<2>     DDR4_ODT<2>  @BASEBOARD_FAB2_LIB.BASEBOARD_FAB2(SCH_1):M_L_ODT<2>
  DN48  M_L_ODT<1>     DDR4_ODT<1>  @BASEBOARD_FAB2_LIB.BASEBOARD_FAB2(SCH_1):M_L_ODT<1>
  DR50  M_L_ODT<0>     DDR4_ODT<0>  @BASEBOARD_FAB2_LIB.BASEBOARD_FAB2(SCH_1):M_L_ODT<0>
  DV59  M_L_MA<9>      DDR4_MA<9>  @BASEBOARD_FAB2_LIB.BASEBOARD_FAB2(SCH_1):M_L_MA<9>
  DJ60  M_L_MA<8>      DDR4_MA<8>  @BASEBOARD_FAB2_LIB.BASEBOARD_FAB2(SCH_1):M_L_MA<8>
  DK61  M_L_MA<7>      DDR4_MA<7>  @BASEBOARD_FAB2_LIB.BASEBOARD_FAB2(SCH_1):M_L_MA<7>
  DM59  M_L_MA<6>      DDR4_MA<6>  @BASEBOARD_FAB2_LIB.BASEBOARD_FAB2(SCH_1):M_L_MA<6>
  DN58  M_L_MA<5>      DDR4_MA<5>  @BASEBOARD_FAB2_LIB.BASEBOARD_FAB2(SCH_1):M_L_MA<5>
  DT59  M_L_MA<4>      DDR4_MA<4>  @BASEBOARD_FAB2_LIB.BASEBOARD_FAB2(SCH_1):M_L_MA<4>
  DR58  M_L_MA<3>      DDR4_MA<3>  @BASEBOARD_FAB2_LIB.BASEBOARD_FAB2(SCH_1):M_L_MA<3>
  DV57  M_L_MA<2>      DDR4_MA<2>  @BASEBOARD_FAB2_LIB.BASEBOARD_FAB2(SCH_1):M_L_MA<2>
  DW58  M_L_MA<1>      DDR4_MA<1>  @BASEBOARD_FAB2_LIB.BASEBOARD_FAB2(SCH_1):M_L_MA<1>
  DR48  M_L_MA<17>     DDR4_MA<17>  @BASEBOARD_FAB2_LIB.BASEBOARD_FAB2(SCH_1):M_L_MA<17>
  DN52  M_L_MA<16>     DDR4_MA<16>  @BASEBOARD_FAB2_LIB.BASEBOARD_FAB2(SCH_1):M_L_MA<16>
  DR52  M_L_MA<15>     DDR4_MA<15>  @BASEBOARD_FAB2_LIB.BASEBOARD_FAB2(SCH_1):M_L_MA<15>
  DM51  M_L_MA<14>     DDR4_MA<14>  @BASEBOARD_FAB2_LIB.BASEBOARD_FAB2(SCH_1):M_L_MA<14>
  DT51  M_L_MA<13>     DDR4_MA<13>  @BASEBOARD_FAB2_LIB.BASEBOARD_FAB2(SCH_1):M_L_MA<13>
  DN60  M_L_MA<12>     DDR4_MA<12>  @BASEBOARD_FAB2_LIB.BASEBOARD_FAB2(SCH_1):M_L_MA<12>
  DR60  M_L_MA<11>     DDR4_MA<11>  @BASEBOARD_FAB2_LIB.BASEBOARD_FAB2(SCH_1):M_L_MA<11>
  DT55  M_L_MA<10>     DDR4_MA<10>  @BASEBOARD_FAB2_LIB.BASEBOARD_FAB2(SCH_1):M_L_MA<10>
  DW52  M_L_MA<0>      DDR4_MA<0>  @BASEBOARD_FAB2_LIB.BASEBOARD_FAB2(SCH_1):M_L_MA<0>
  EA66  M_L_ECC<7>     DDR4_ECC<7>  @BASEBOARD_FAB2_LIB.BASEBOARD_FAB2(SCH_1):M_L_ECC<7>
  DU66  M_L_ECC<6>     DDR4_ECC<6>  @BASEBOARD_FAB2_LIB.BASEBOARD_FAB2(SCH_1):M_L_ECC<6>
  DV69  M_L_ECC<5>     DDR4_ECC<5>  @BASEBOARD_FAB2_LIB.BASEBOARD_FAB2(SCH_1):M_L_ECC<5>
  DU68  M_L_ECC<4>     DDR4_ECC<4>  @BASEBOARD_FAB2_LIB.BASEBOARD_FAB2(SCH_1):M_L_ECC<4>
  DY65  M_L_ECC<3>     DDR4_ECC<3>  @BASEBOARD_FAB2_LIB.BASEBOARD_FAB2(SCH_1):M_L_ECC<3>
  DV65  M_L_ECC<2>     DDR4_ECC<2>  @BASEBOARD_FAB2_LIB.BASEBOARD_FAB2(SCH_1):M_L_ECC<2>
  EA68  M_L_ECC<1>     DDR4_ECC<1>  @BASEBOARD_FAB2_LIB.BASEBOARD_FAB2(SCH_1):M_L_ECC<1>
  DY69  M_L_ECC<0>     DDR4_ECC<0>  @BASEBOARD_FAB2_LIB.BASEBOARD_FAB2(SCH_1):M_L_ECC<0>
  CP79  M_L_DQS_DP<9>  DDR4_DQS_DP<9>  @BASEBOARD_FAB2_LIB.BASEBOARD_FAB2(SCH_1):M_L_DQS_DP<9>
  DY67  M_L_DQS_DP<8>  DDR4_DQS_DP<8>  @BASEBOARD_FAB2_LIB.BASEBOARD_FAB2(SCH_1):M_L_DQS_DP<8>
  DJ26  M_L_DQS_DP<7>  DDR4_DQS_DP<7>  @BASEBOARD_FAB2_LIB.BASEBOARD_FAB2(SCH_1):M_L_DQS_DP<7>
  EC26  M_L_DQS_DP<6>  DDR4_DQS_DP<6>  @BASEBOARD_FAB2_LIB.BASEBOARD_FAB2(SCH_1):M_L_DQS_DP<6>
  EC32  M_L_DQS_DP<5>  DDR4_DQS_DP<5>  @BASEBOARD_FAB2_LIB.BASEBOARD_FAB2(SCH_1):M_L_DQS_DP<5>
  DT41  M_L_DQS_DP<4>  DDR4_DQS_DP<4>  @BASEBOARD_FAB2_LIB.BASEBOARD_FAB2(SCH_1):M_L_DQS_DP<4>
  ED73  M_L_DQS_DP<3>  DDR4_DQS_DP<3>  @BASEBOARD_FAB2_LIB.BASEBOARD_FAB2(SCH_1):M_L_DQS_DP<3>
  EB79  M_L_DQS_DP<2>  DDR4_DQS_DP<2>  @BASEBOARD_FAB2_LIB.BASEBOARD_FAB2(SCH_1):M_L_DQS_DP<2>
  DB81  M_L_DQS_DP<1>  DDR4_DQS_DP<1>  @BASEBOARD_FAB2_LIB.BASEBOARD_FAB2(SCH_1):M_L_DQS_DP<1>
  DT67  M_L_DQS_DP<17>  DDR4_DQS_DP<17>  @BASEBOARD_FAB2_LIB.BASEBOARD_FAB2(SCH_1):M_L_DQS_DP<17>
  DE26  M_L_DQS_DP<16>  DDR4_DQS_DP<16>  @BASEBOARD_FAB2_LIB.BASEBOARD_FAB2(SCH_1):M_L_DQS_DP<16>
  DW26  M_L_DQS_DP<15>  DDR4_DQS_DP<15>  @BASEBOARD_FAB2_LIB.BASEBOARD_FAB2(SCH_1):M_L_DQS_DP<15>
  DW32  M_L_DQS_DP<14>  DDR4_DQS_DP<14>  @BASEBOARD_FAB2_LIB.BASEBOARD_FAB2(SCH_1):M_L_DQS_DP<14>
  DM41  M_L_DQS_DP<13>  DDR4_DQS_DP<13>  @BASEBOARD_FAB2_LIB.BASEBOARD_FAB2(SCH_1):M_L_DQS_DP<13>
  DY73  M_L_DQS_DP<12>  DDR4_DQS_DP<12>  @BASEBOARD_FAB2_LIB.BASEBOARD_FAB2(SCH_1):M_L_DQS_DP<12>
  DV79  M_L_DQS_DP<11>  DDR4_DQS_DP<11>  @BASEBOARD_FAB2_LIB.BASEBOARD_FAB2(SCH_1):M_L_DQS_DP<11>
  DD79  M_L_DQS_DP<10>  DDR4_DQS_DP<10>  @BASEBOARD_FAB2_LIB.BASEBOARD_FAB2(SCH_1):M_L_DQS_DP<10>
  CM81  M_L_DQS_DP<0>  DDR4_DQS_DP<0>  @BASEBOARD_FAB2_LIB.BASEBOARD_FAB2(SCH_1):M_L_DQS_DP<0>
  CN80  M_L_DQS_DN<9>  DDR4_DQS_DN<9>  @BASEBOARD_FAB2_LIB.BASEBOARD_FAB2(SCH_1):M_L_DQS_DN<9>
  EB67  M_L_DQS_DN<8>  DDR4_DQS_DN<8>  @BASEBOARD_FAB2_LIB.BASEBOARD_FAB2(SCH_1):M_L_DQS_DN<8>
  DL26  M_L_DQS_DN<7>  DDR4_DQS_DN<7>  @BASEBOARD_FAB2_LIB.BASEBOARD_FAB2(SCH_1):M_L_DQS_DN<7>
  EE26  M_L_DQS_DN<6>  DDR4_DQS_DN<6>  @BASEBOARD_FAB2_LIB.BASEBOARD_FAB2(SCH_1):M_L_DQS_DN<6>
  EE32  M_L_DQS_DN<5>  DDR4_DQS_DN<5>  @BASEBOARD_FAB2_LIB.BASEBOARD_FAB2(SCH_1):M_L_DQS_DN<5>
  DV41  M_L_DQS_DN<4>  DDR4_DQS_DN<4>  @BASEBOARD_FAB2_LIB.BASEBOARD_FAB2(SCH_1):M_L_DQS_DN<4>
  EF73  M_L_DQS_DN<3>  DDR4_DQS_DN<3>  @BASEBOARD_FAB2_LIB.BASEBOARD_FAB2(SCH_1):M_L_DQS_DN<3>
  ED79  M_L_DQS_DN<2>  DDR4_DQS_DN<2>  @BASEBOARD_FAB2_LIB.BASEBOARD_FAB2(SCH_1):M_L_DQS_DN<2>
  DA82  M_L_DQS_DN<1>  DDR4_DQS_DN<1>  @BASEBOARD_FAB2_LIB.BASEBOARD_FAB2(SCH_1):M_L_DQS_DN<1>
  DV67  M_L_DQS_DN<17>  DDR4_DQS_DN<17>  @BASEBOARD_FAB2_LIB.BASEBOARD_FAB2(SCH_1):M_L_DQS_DN<17>
  DG26  M_L_DQS_DN<16>  DDR4_DQS_DN<16>  @BASEBOARD_FAB2_LIB.BASEBOARD_FAB2(SCH_1):M_L_DQS_DN<16>
  EA26  M_L_DQS_DN<15>  DDR4_DQS_DN<15>  @BASEBOARD_FAB2_LIB.BASEBOARD_FAB2(SCH_1):M_L_DQS_DN<15>
  EA32  M_L_DQS_DN<14>  DDR4_DQS_DN<14>  @BASEBOARD_FAB2_LIB.BASEBOARD_FAB2(SCH_1):M_L_DQS_DN<14>
  DP41  M_L_DQS_DN<13>  DDR4_DQS_DN<13>  @BASEBOARD_FAB2_LIB.BASEBOARD_FAB2(SCH_1):M_L_DQS_DN<13>
  EB73  M_L_DQS_DN<12>  DDR4_DQS_DN<12>  @BASEBOARD_FAB2_LIB.BASEBOARD_FAB2(SCH_1):M_L_DQS_DN<12>
  DY79  M_L_DQS_DN<11>  DDR4_DQS_DN<11>  @BASEBOARD_FAB2_LIB.BASEBOARD_FAB2(SCH_1):M_L_DQS_DN<11>
  DC80  M_L_DQS_DN<10>  DDR4_DQS_DN<10>  @BASEBOARD_FAB2_LIB.BASEBOARD_FAB2(SCH_1):M_L_DQS_DN<10>
  CL82  M_L_DQS_DN<0>  DDR4_DQS_DN<0>  @BASEBOARD_FAB2_LIB.BASEBOARD_FAB2(SCH_1):M_L_DQS_DN<0>
  CY81  M_L_DQ<9>      DDR4_DQ<9>  @BASEBOARD_FAB2_LIB.BASEBOARD_FAB2(SCH_1):M_L_DQ<9>
  DB79  M_L_DQ<8>      DDR4_DQ<8>  @BASEBOARD_FAB2_LIB.BASEBOARD_FAB2(SCH_1):M_L_DQ<8>
  CN82  M_L_DQ<7>      DDR4_DQ<7>  @BASEBOARD_FAB2_LIB.BASEBOARD_FAB2(SCH_1):M_L_DQ<7>
  CR80  M_L_DQ<6>      DDR4_DQ<6>  @BASEBOARD_FAB2_LIB.BASEBOARD_FAB2(SCH_1):M_L_DQ<6>
  DK25  M_L_DQ<63>     DDR4_DQ<63>  @BASEBOARD_FAB2_LIB.BASEBOARD_FAB2(SCH_1):M_L_DQ<63>
  DF25  M_L_DQ<62>     DDR4_DQ<62>  @BASEBOARD_FAB2_LIB.BASEBOARD_FAB2(SCH_1):M_L_DQ<62>
  DJ28  M_L_DQ<61>     DDR4_DQ<61>  @BASEBOARD_FAB2_LIB.BASEBOARD_FAB2(SCH_1):M_L_DQ<61>
  DG28  M_L_DQ<60>     DDR4_DQ<60>  @BASEBOARD_FAB2_LIB.BASEBOARD_FAB2(SCH_1):M_L_DQ<60>
  CJ80  M_L_DQ<5>      DDR4_DQ<5>  @BASEBOARD_FAB2_LIB.BASEBOARD_FAB2(SCH_1):M_L_DQ<5>
  DJ24  M_L_DQ<59>     DDR4_DQ<59>  @BASEBOARD_FAB2_LIB.BASEBOARD_FAB2(SCH_1):M_L_DQ<59>
  DD25  M_L_DQ<58>     DDR4_DQ<58>  @BASEBOARD_FAB2_LIB.BASEBOARD_FAB2(SCH_1):M_L_DQ<58>
  DK27  M_L_DQ<57>     DDR4_DQ<57>  @BASEBOARD_FAB2_LIB.BASEBOARD_FAB2(SCH_1):M_L_DQ<57>
  DF27  M_L_DQ<56>     DDR4_DQ<56>  @BASEBOARD_FAB2_LIB.BASEBOARD_FAB2(SCH_1):M_L_DQ<56>
  ED25  M_L_DQ<55>     DDR4_DQ<55>  @BASEBOARD_FAB2_LIB.BASEBOARD_FAB2(SCH_1):M_L_DQ<55>
  DY25  M_L_DQ<54>     DDR4_DQ<54>  @BASEBOARD_FAB2_LIB.BASEBOARD_FAB2(SCH_1):M_L_DQ<54>
  EA28  M_L_DQ<53>     DDR4_DQ<53>  @BASEBOARD_FAB2_LIB.BASEBOARD_FAB2(SCH_1):M_L_DQ<53>
  DY27  M_L_DQ<52>     DDR4_DQ<52>  @BASEBOARD_FAB2_LIB.BASEBOARD_FAB2(SCH_1):M_L_DQ<52>
  EC24  M_L_DQ<51>     DDR4_DQ<51>  @BASEBOARD_FAB2_LIB.BASEBOARD_FAB2(SCH_1):M_L_DQ<51>
  EA24  M_L_DQ<50>     DDR4_DQ<50>  @BASEBOARD_FAB2_LIB.BASEBOARD_FAB2(SCH_1):M_L_DQ<50>
  CK79  M_L_DQ<4>      DDR4_DQ<4>  @BASEBOARD_FAB2_LIB.BASEBOARD_FAB2(SCH_1):M_L_DQ<4>
  ED27  M_L_DQ<49>     DDR4_DQ<49>  @BASEBOARD_FAB2_LIB.BASEBOARD_FAB2(SCH_1):M_L_DQ<49>
  EC28  M_L_DQ<48>     DDR4_DQ<48>  @BASEBOARD_FAB2_LIB.BASEBOARD_FAB2(SCH_1):M_L_DQ<48>
  ED31  M_L_DQ<47>     DDR4_DQ<47>  @BASEBOARD_FAB2_LIB.BASEBOARD_FAB2(SCH_1):M_L_DQ<47>
  DY31  M_L_DQ<46>     DDR4_DQ<46>  @BASEBOARD_FAB2_LIB.BASEBOARD_FAB2(SCH_1):M_L_DQ<46>
  EA34  M_L_DQ<45>     DDR4_DQ<45>  @BASEBOARD_FAB2_LIB.BASEBOARD_FAB2(SCH_1):M_L_DQ<45>
  DY33  M_L_DQ<44>     DDR4_DQ<44>  @BASEBOARD_FAB2_LIB.BASEBOARD_FAB2(SCH_1):M_L_DQ<44>
  EC30  M_L_DQ<43>     DDR4_DQ<43>  @BASEBOARD_FAB2_LIB.BASEBOARD_FAB2(SCH_1):M_L_DQ<43>
  EA30  M_L_DQ<42>     DDR4_DQ<42>  @BASEBOARD_FAB2_LIB.BASEBOARD_FAB2(SCH_1):M_L_DQ<42>
  ED33  M_L_DQ<41>     DDR4_DQ<41>  @BASEBOARD_FAB2_LIB.BASEBOARD_FAB2(SCH_1):M_L_DQ<41>
  EC34  M_L_DQ<40>     DDR4_DQ<40>  @BASEBOARD_FAB2_LIB.BASEBOARD_FAB2(SCH_1):M_L_DQ<40>
  CR82  M_L_DQ<3>      DDR4_DQ<3>  @BASEBOARD_FAB2_LIB.BASEBOARD_FAB2(SCH_1):M_L_DQ<3>
  DU40  M_L_DQ<39>     DDR4_DQ<39>  @BASEBOARD_FAB2_LIB.BASEBOARD_FAB2(SCH_1):M_L_DQ<39>
  DN40  M_L_DQ<38>     DDR4_DQ<38>  @BASEBOARD_FAB2_LIB.BASEBOARD_FAB2(SCH_1):M_L_DQ<38>
  DN42  M_L_DQ<37>     DDR4_DQ<37>  @BASEBOARD_FAB2_LIB.BASEBOARD_FAB2(SCH_1):M_L_DQ<37>
  DL42  M_L_DQ<36>     DDR4_DQ<36>  @BASEBOARD_FAB2_LIB.BASEBOARD_FAB2(SCH_1):M_L_DQ<36>
  DT39  M_L_DQ<35>     DDR4_DQ<35>  @BASEBOARD_FAB2_LIB.BASEBOARD_FAB2(SCH_1):M_L_DQ<35>
  DP39  M_L_DQ<34>     DDR4_DQ<34>  @BASEBOARD_FAB2_LIB.BASEBOARD_FAB2(SCH_1):M_L_DQ<34>
  DW42  M_L_DQ<33>     DDR4_DQ<33>  @BASEBOARD_FAB2_LIB.BASEBOARD_FAB2(SCH_1):M_L_DQ<33>
  DU42  M_L_DQ<32>     DDR4_DQ<32>  @BASEBOARD_FAB2_LIB.BASEBOARD_FAB2(SCH_1):M_L_DQ<32>
  EE72  M_L_DQ<31>     DDR4_DQ<31>  @BASEBOARD_FAB2_LIB.BASEBOARD_FAB2(SCH_1):M_L_DQ<31>
  EA72  M_L_DQ<30>     DDR4_DQ<30>  @BASEBOARD_FAB2_LIB.BASEBOARD_FAB2(SCH_1):M_L_DQ<30>
  CT81  M_L_DQ<2>      DDR4_DQ<2>  @BASEBOARD_FAB2_LIB.BASEBOARD_FAB2(SCH_1):M_L_DQ<2>
  EB75  M_L_DQ<29>     DDR4_DQ<29>  @BASEBOARD_FAB2_LIB.BASEBOARD_FAB2(SCH_1):M_L_DQ<29>
  EA74  M_L_DQ<28>     DDR4_DQ<28>  @BASEBOARD_FAB2_LIB.BASEBOARD_FAB2(SCH_1):M_L_DQ<28>
  ED71  M_L_DQ<27>     DDR4_DQ<27>  @BASEBOARD_FAB2_LIB.BASEBOARD_FAB2(SCH_1):M_L_DQ<27>
  EB71  M_L_DQ<26>     DDR4_DQ<26>  @BASEBOARD_FAB2_LIB.BASEBOARD_FAB2(SCH_1):M_L_DQ<26>
  EE74  M_L_DQ<25>     DDR4_DQ<25>  @BASEBOARD_FAB2_LIB.BASEBOARD_FAB2(SCH_1):M_L_DQ<25>
  ED75  M_L_DQ<24>     DDR4_DQ<24>  @BASEBOARD_FAB2_LIB.BASEBOARD_FAB2(SCH_1):M_L_DQ<24>
  EC78  M_L_DQ<23>     DDR4_DQ<23>  @BASEBOARD_FAB2_LIB.BASEBOARD_FAB2(SCH_1):M_L_DQ<23>
  DW78  M_L_DQ<22>     DDR4_DQ<22>  @BASEBOARD_FAB2_LIB.BASEBOARD_FAB2(SCH_1):M_L_DQ<22>
  EB81  M_L_DQ<21>     DDR4_DQ<21>  @BASEBOARD_FAB2_LIB.BASEBOARD_FAB2(SCH_1):M_L_DQ<21>
  DY81  M_L_DQ<20>     DDR4_DQ<20>  @BASEBOARD_FAB2_LIB.BASEBOARD_FAB2(SCH_1):M_L_DQ<20>
  CK81  M_L_DQ<1>      DDR4_DQ<1>  @BASEBOARD_FAB2_LIB.BASEBOARD_FAB2(SCH_1):M_L_DQ<1>
  EB77  M_L_DQ<19>     DDR4_DQ<19>  @BASEBOARD_FAB2_LIB.BASEBOARD_FAB2(SCH_1):M_L_DQ<19>
  DY77  M_L_DQ<18>     DDR4_DQ<18>  @BASEBOARD_FAB2_LIB.BASEBOARD_FAB2(SCH_1):M_L_DQ<18>
  EC80  M_L_DQ<17>     DDR4_DQ<17>  @BASEBOARD_FAB2_LIB.BASEBOARD_FAB2(SCH_1):M_L_DQ<17>
  DW80  M_L_DQ<16>     DDR4_DQ<16>  @BASEBOARD_FAB2_LIB.BASEBOARD_FAB2(SCH_1):M_L_DQ<16>
  DE82  M_L_DQ<15>     DDR4_DQ<15>  @BASEBOARD_FAB2_LIB.BASEBOARD_FAB2(SCH_1):M_L_DQ<15>
  DC82  M_L_DQ<14>     DDR4_DQ<14>  @BASEBOARD_FAB2_LIB.BASEBOARD_FAB2(SCH_1):M_L_DQ<14>
  CW80  M_L_DQ<13>     DDR4_DQ<13>  @BASEBOARD_FAB2_LIB.BASEBOARD_FAB2(SCH_1):M_L_DQ<13>
  CY79  M_L_DQ<12>     DDR4_DQ<12>  @BASEBOARD_FAB2_LIB.BASEBOARD_FAB2(SCH_1):M_L_DQ<12>
  DF81  M_L_DQ<11>     DDR4_DQ<11>  @BASEBOARD_FAB2_LIB.BASEBOARD_FAB2(SCH_1):M_L_DQ<11>
  DE80  M_L_DQ<10>     DDR4_DQ<10>  @BASEBOARD_FAB2_LIB.BASEBOARD_FAB2(SCH_1):M_L_DQ<10>
  CM79  M_L_DQ<0>      DDR4_DQ<0>  @BASEBOARD_FAB2_LIB.BASEBOARD_FAB2(SCH_1):M_L_DQ<0>
  DN46  M_L_CS_N<7>    DDR4_CS_N<7>  @BASEBOARD_FAB2_LIB.BASEBOARD_FAB2(SCH_1):M_L_CS_N<7>
  DT45  M_L_CS_N<6>    DDR4_CS_N<6>  @BASEBOARD_FAB2_LIB.BASEBOARD_FAB2(SCH_1):M_L_CS_N<6>
  DM49  M_L_CS_N<5>    DDR4_CS_N<5>  @BASEBOARD_FAB2_LIB.BASEBOARD_FAB2(SCH_1):M_L_CS_N<5>
  DW50  M_L_CS_N<4>    DDR4_CS_N<4>  @BASEBOARD_FAB2_LIB.BASEBOARD_FAB2(SCH_1):M_L_CS_N<4>
  DK47  M_L_CS_N<3>    DDR4_CS_N<3>  @BASEBOARD_FAB2_LIB.BASEBOARD_FAB2(SCH_1):M_L_CS_N<3>
  DR46  M_L_CS_N<2>    DDR4_CS_N<2>  @BASEBOARD_FAB2_LIB.BASEBOARD_FAB2(SCH_1):M_L_CS_N<2>
  DN50  M_L_CS_N<1>    DDR4_CS_N<1>  @BASEBOARD_FAB2_LIB.BASEBOARD_FAB2(SCH_1):M_L_CS_N<1>
  DV51  M_L_CS_N<0>    DDR4_CS_N<0>  @BASEBOARD_FAB2_LIB.BASEBOARD_FAB2(SCH_1):M_L_CS_N<0>
  DR56  M_L_CLK_DP<3>  DDR4_CLK_DP<3>  @BASEBOARD_FAB2_LIB.BASEBOARD_FAB2(SCH_1):M_L_CLK_DP<3>
  DN56  M_L_CLK_DP<2>  DDR4_CLK_DP<2>  @BASEBOARD_FAB2_LIB.BASEBOARD_FAB2(SCH_1):M_L_CLK_DP<2>
  DT53  M_L_CLK_DP<1>  DDR4_CLK_DP<1>  @BASEBOARD_FAB2_LIB.BASEBOARD_FAB2(SCH_1):M_L_CLK_DP<1>
  DN54  M_L_CLK_DP<0>  DDR4_CLK_DP<0>  @BASEBOARD_FAB2_LIB.BASEBOARD_FAB2(SCH_1):M_L_CLK_DP<0>
  DT57  M_L_CLK_DN<3>  DDR4_CLK_DN<3>  @BASEBOARD_FAB2_LIB.BASEBOARD_FAB2(SCH_1):M_L_CLK_DN<3>
  DM57  M_L_CLK_DN<2>  DDR4_CLK_DN<2>  @BASEBOARD_FAB2_LIB.BASEBOARD_FAB2(SCH_1):M_L_CLK_DN<2>
  DR54  M_L_CLK_DN<1>  DDR4_CLK_DN<1>  @BASEBOARD_FAB2_LIB.BASEBOARD_FAB2(SCH_1):M_L_CLK_DN<1>
  DM55  M_L_CLK_DN<0>  DDR4_CLK_DN<0>  @BASEBOARD_FAB2_LIB.BASEBOARD_FAB2(SCH_1):M_L_CLK_DN<0>
  DR64  M_L_CKE<3>     DDR4_CKE<3>  @BASEBOARD_FAB2_LIB.BASEBOARD_FAB2(SCH_1):M_L_CKE<3>
  DL64  M_L_CKE<2>     DDR4_CKE<2>  @BASEBOARD_FAB2_LIB.BASEBOARD_FAB2(SCH_1):M_L_CKE<2>
  DN64  M_L_CKE<1>     DDR4_CKE<1>  @BASEBOARD_FAB2_LIB.BASEBOARD_FAB2(SCH_1):M_L_CKE<1>
  DM63  M_L_CKE<0>     DDR4_CKE<0>  @BASEBOARD_FAB2_LIB.BASEBOARD_FAB2(SCH_1):M_L_CKE<0>
  DT47  M_L_C<2>       DDR4_CID<2>  @BASEBOARD_FAB2_LIB.BASEBOARD_FAB2(SCH_1):M_L_C<2>
  DM61  M_L_BG<1>      DDR4_BG<1>  @BASEBOARD_FAB2_LIB.BASEBOARD_FAB2(SCH_1):M_L_BG<1>
  DJ62  M_L_BG<0>      DDR4_BG<0>  @BASEBOARD_FAB2_LIB.BASEBOARD_FAB2(SCH_1):M_L_BG<0>
  DV55  M_L_BA<1>      DDR4_BA<1>  @BASEBOARD_FAB2_LIB.BASEBOARD_FAB2(SCH_1):M_L_BA<1>
  DM53  M_L_BA<0>      DDR4_BA<0>  @BASEBOARD_FAB2_LIB.BASEBOARD_FAB2(SCH_1):M_L_BA<0>
  DT61  M_L_ALERT_N    DDR4_ALERT_N  @BASEBOARD_FAB2_LIB.BASEBOARD_FAB2(SCH_1):M_L_ALERT_N
  DR62  M_L_ACT_N      DDR4_ACT_N  @BASEBOARD_FAB2_LIB.BASEBOARD_FAB2(SCH_1):M_L_ACT_N

SKX_EXT_B_BGA1  I172  U2D1   [SKX_EXT_B_BGA1-IC,TBD]
  ED53  M_K_PAR        DDR3_PAR  @BASEBOARD_FAB2_LIB.BASEBOARD_FAB2(SCH_1):M_K_PAR
  EA48  M_K_ODT<3>     DDR3_ODT<3>  @BASEBOARD_FAB2_LIB.BASEBOARD_FAB2(SCH_1):M_K_ODT<3>
  EA50  M_K_ODT<2>     DDR3_ODT<2>  @BASEBOARD_FAB2_LIB.BASEBOARD_FAB2(SCH_1):M_K_ODT<2>
  EE48  M_K_ODT<1>     DDR3_ODT<1>  @BASEBOARD_FAB2_LIB.BASEBOARD_FAB2(SCH_1):M_K_ODT<1>
  EE50  M_K_ODT<0>     DDR3_ODT<0>  @BASEBOARD_FAB2_LIB.BASEBOARD_FAB2(SCH_1):M_K_ODT<0>
  EF61  M_K_MA<9>      DDR3_MA<9>  @BASEBOARD_FAB2_LIB.BASEBOARD_FAB2(SCH_1):M_K_MA<9>
  EB59  M_K_MA<8>      DDR3_MA<8>  @BASEBOARD_FAB2_LIB.BASEBOARD_FAB2(SCH_1):M_K_MA<8>
  EA60  M_K_MA<7>      DDR3_MA<7>  @BASEBOARD_FAB2_LIB.BASEBOARD_FAB2(SCH_1):M_K_MA<7>
  EE60  M_K_MA<6>      DDR3_MA<6>  @BASEBOARD_FAB2_LIB.BASEBOARD_FAB2(SCH_1):M_K_MA<6>
  EA58  M_K_MA<5>      DDR3_MA<5>  @BASEBOARD_FAB2_LIB.BASEBOARD_FAB2(SCH_1):M_K_MA<5>
  ED59  M_K_MA<4>      DDR3_MA<4>  @BASEBOARD_FAB2_LIB.BASEBOARD_FAB2(SCH_1):M_K_MA<4>
  EB57  M_K_MA<3>      DDR3_MA<3>  @BASEBOARD_FAB2_LIB.BASEBOARD_FAB2(SCH_1):M_K_MA<3>
  EE58  M_K_MA<2>      DDR3_MA<2>  @BASEBOARD_FAB2_LIB.BASEBOARD_FAB2(SCH_1):M_K_MA<2>
  ED57  M_K_MA<1>      DDR3_MA<1>  @BASEBOARD_FAB2_LIB.BASEBOARD_FAB2(SCH_1):M_K_MA<1>
  EA46  M_K_MA<17>     DDR3_MA<17>  @BASEBOARD_FAB2_LIB.BASEBOARD_FAB2(SCH_1):M_K_MA<17>
  EA52  M_K_MA<16>     DDR3_MA<16>  @BASEBOARD_FAB2_LIB.BASEBOARD_FAB2(SCH_1):M_K_MA<16>
  DV49  M_K_MA<15>     DDR3_MA<15>  @BASEBOARD_FAB2_LIB.BASEBOARD_FAB2(SCH_1):M_K_MA<15>
  ED51  M_K_MA<14>     DDR3_MA<14>  @BASEBOARD_FAB2_LIB.BASEBOARD_FAB2(SCH_1):M_K_MA<14>
  DW48  M_K_MA<13>     DDR3_MA<13>  @BASEBOARD_FAB2_LIB.BASEBOARD_FAB2(SCH_1):M_K_MA<13>
  DT63  M_K_MA<12>     DDR3_MA<12>  @BASEBOARD_FAB2_LIB.BASEBOARD_FAB2(SCH_1):M_K_MA<12>
  EB61  M_K_MA<11>     DDR3_MA<11>  @BASEBOARD_FAB2_LIB.BASEBOARD_FAB2(SCH_1):M_K_MA<11>
  DW54  M_K_MA<10>     DDR3_MA<10>  @BASEBOARD_FAB2_LIB.BASEBOARD_FAB2(SCH_1):M_K_MA<10>
  EB53  M_K_MA<0>      DDR3_MA<0>  @BASEBOARD_FAB2_LIB.BASEBOARD_FAB2(SCH_1):M_K_MA<0>
  DE66  M_K_ECC<7>     DDR3_ECC<7>  @BASEBOARD_FAB2_LIB.BASEBOARD_FAB2(SCH_1):M_K_ECC<7>
  DA66  M_K_ECC<6>     DDR3_ECC<6>  @BASEBOARD_FAB2_LIB.BASEBOARD_FAB2(SCH_1):M_K_ECC<6>
  DD69  M_K_ECC<5>     DDR3_ECC<5>  @BASEBOARD_FAB2_LIB.BASEBOARD_FAB2(SCH_1):M_K_ECC<5>
  DB69  M_K_ECC<4>     DDR3_ECC<4>  @BASEBOARD_FAB2_LIB.BASEBOARD_FAB2(SCH_1):M_K_ECC<4>
  DD65  M_K_ECC<3>     DDR3_ECC<3>  @BASEBOARD_FAB2_LIB.BASEBOARD_FAB2(SCH_1):M_K_ECC<3>
  DB65  M_K_ECC<2>     DDR3_ECC<2>  @BASEBOARD_FAB2_LIB.BASEBOARD_FAB2(SCH_1):M_K_ECC<2>
  DE68  M_K_ECC<1>     DDR3_ECC<1>  @BASEBOARD_FAB2_LIB.BASEBOARD_FAB2(SCH_1):M_K_ECC<1>
  DA68  M_K_ECC<0>     DDR3_ECC<0>  @BASEBOARD_FAB2_LIB.BASEBOARD_FAB2(SCH_1):M_K_ECC<0>
  CP85  M_K_DQS_DP<9>  DDR3_DQS_DP<9>  @BASEBOARD_FAB2_LIB.BASEBOARD_FAB2(SCH_1):M_K_DQS_DP<9>
  DD67  M_K_DQS_DP<8>  DDR3_DQS_DP<8>  @BASEBOARD_FAB2_LIB.BASEBOARD_FAB2(SCH_1):M_K_DQS_DP<8>
  DT23  M_K_DQS_DP<7>  DDR3_DQS_DP<7>  @BASEBOARD_FAB2_LIB.BASEBOARD_FAB2(SCH_1):M_K_DQS_DP<7>
  DT29  M_K_DQS_DP<6>  DDR3_DQS_DP<6>  @BASEBOARD_FAB2_LIB.BASEBOARD_FAB2(SCH_1):M_K_DQS_DP<6>
  DT35  M_K_DQS_DP<5>  DDR3_DQS_DP<5>  @BASEBOARD_FAB2_LIB.BASEBOARD_FAB2(SCH_1):M_K_DQS_DP<5>
  EC38  M_K_DQS_DP<4>  DDR3_DQS_DP<4>  @BASEBOARD_FAB2_LIB.BASEBOARD_FAB2(SCH_1):M_K_DQS_DP<4>
  DT75  M_K_DQS_DP<3>  DDR3_DQS_DP<3>  @BASEBOARD_FAB2_LIB.BASEBOARD_FAB2(SCH_1):M_K_DQS_DP<3>
  DM81  M_K_DQS_DP<2>  DDR3_DQS_DP<2>  @BASEBOARD_FAB2_LIB.BASEBOARD_FAB2(SCH_1):M_K_DQS_DP<2>
  DP85  M_K_DQS_DP<1>  DDR3_DQS_DP<1>  @BASEBOARD_FAB2_LIB.BASEBOARD_FAB2(SCH_1):M_K_DQS_DP<1>
  CY67  M_K_DQS_DP<17>  DDR3_DQS_DP<17>  @BASEBOARD_FAB2_LIB.BASEBOARD_FAB2(SCH_1):M_K_DQS_DP<17>
  DP23  M_K_DQS_DP<16>  DDR3_DQS_DP<16>  @BASEBOARD_FAB2_LIB.BASEBOARD_FAB2(SCH_1):M_K_DQS_DP<16>
  DP29  M_K_DQS_DP<15>  DDR3_DQS_DP<15>  @BASEBOARD_FAB2_LIB.BASEBOARD_FAB2(SCH_1):M_K_DQS_DP<15>
  DM35  M_K_DQS_DP<14>  DDR3_DQS_DP<14>  @BASEBOARD_FAB2_LIB.BASEBOARD_FAB2(SCH_1):M_K_DQS_DP<14>
  DW38  M_K_DQS_DP<13>  DDR3_DQS_DP<13>  @BASEBOARD_FAB2_LIB.BASEBOARD_FAB2(SCH_1):M_K_DQS_DP<13>
  DM75  M_K_DQS_DP<12>  DDR3_DQS_DP<12>  @BASEBOARD_FAB2_LIB.BASEBOARD_FAB2(SCH_1):M_K_DQS_DP<12>
  DP79  M_K_DQS_DP<11>  DDR3_DQS_DP<11>  @BASEBOARD_FAB2_LIB.BASEBOARD_FAB2(SCH_1):M_K_DQS_DP<11>
  DL84  M_K_DQS_DP<10>  DDR3_DQS_DP<10>  @BASEBOARD_FAB2_LIB.BASEBOARD_FAB2(SCH_1):M_K_DQS_DP<10>
  CV85  M_K_DQS_DP<0>  DDR3_DQS_DP<0>  @BASEBOARD_FAB2_LIB.BASEBOARD_FAB2(SCH_1):M_K_DQS_DP<0>
  CR84  M_K_DQS_DN<9>  DDR3_DQS_DN<9>  @BASEBOARD_FAB2_LIB.BASEBOARD_FAB2(SCH_1):M_K_DQS_DN<9>
  DF67  M_K_DQS_DN<8>  DDR3_DQS_DN<8>  @BASEBOARD_FAB2_LIB.BASEBOARD_FAB2(SCH_1):M_K_DQS_DN<8>
  DV23  M_K_DQS_DN<7>  DDR3_DQS_DN<7>  @BASEBOARD_FAB2_LIB.BASEBOARD_FAB2(SCH_1):M_K_DQS_DN<7>
  DV29  M_K_DQS_DN<6>  DDR3_DQS_DN<6>  @BASEBOARD_FAB2_LIB.BASEBOARD_FAB2(SCH_1):M_K_DQS_DN<6>
  DV35  M_K_DQS_DN<5>  DDR3_DQS_DN<5>  @BASEBOARD_FAB2_LIB.BASEBOARD_FAB2(SCH_1):M_K_DQS_DN<5>
  EE38  M_K_DQS_DN<4>  DDR3_DQS_DN<4>  @BASEBOARD_FAB2_LIB.BASEBOARD_FAB2(SCH_1):M_K_DQS_DN<4>
  DV75  M_K_DQS_DN<3>  DDR3_DQS_DN<3>  @BASEBOARD_FAB2_LIB.BASEBOARD_FAB2(SCH_1):M_K_DQS_DN<3>
  DL82  M_K_DQS_DN<2>  DDR3_DQS_DN<2>  @BASEBOARD_FAB2_LIB.BASEBOARD_FAB2(SCH_1):M_K_DQS_DN<2>
  DN84  M_K_DQS_DN<1>  DDR3_DQS_DN<1>  @BASEBOARD_FAB2_LIB.BASEBOARD_FAB2(SCH_1):M_K_DQS_DN<1>
  DB67  M_K_DQS_DN<17>  DDR3_DQS_DN<17>  @BASEBOARD_FAB2_LIB.BASEBOARD_FAB2(SCH_1):M_K_DQS_DN<17>
  DM23  M_K_DQS_DN<16>  DDR3_DQS_DN<16>  @BASEBOARD_FAB2_LIB.BASEBOARD_FAB2(SCH_1):M_K_DQS_DN<16>
  DM29  M_K_DQS_DN<15>  DDR3_DQS_DN<15>  @BASEBOARD_FAB2_LIB.BASEBOARD_FAB2(SCH_1):M_K_DQS_DN<15>
  DP35  M_K_DQS_DN<14>  DDR3_DQS_DN<14>  @BASEBOARD_FAB2_LIB.BASEBOARD_FAB2(SCH_1):M_K_DQS_DN<14>
  EA38  M_K_DQS_DN<13>  DDR3_DQS_DN<13>  @BASEBOARD_FAB2_LIB.BASEBOARD_FAB2(SCH_1):M_K_DQS_DN<13>
  DP75  M_K_DQS_DN<12>  DDR3_DQS_DN<12>  @BASEBOARD_FAB2_LIB.BASEBOARD_FAB2(SCH_1):M_K_DQS_DN<12>
  DN80  M_K_DQS_DN<11>  DDR3_DQS_DN<11>  @BASEBOARD_FAB2_LIB.BASEBOARD_FAB2(SCH_1):M_K_DQS_DN<11>
  DM85  M_K_DQS_DN<10>  DDR3_DQS_DN<10>  @BASEBOARD_FAB2_LIB.BASEBOARD_FAB2(SCH_1):M_K_DQS_DN<10>
  CU84  M_K_DQS_DN<0>  DDR3_DQS_DN<0>  @BASEBOARD_FAB2_LIB.BASEBOARD_FAB2(SCH_1):M_K_DQS_DN<0>
  DH85  M_K_DQ<9>      DDR3_DQ<9>  @BASEBOARD_FAB2_LIB.BASEBOARD_FAB2(SCH_1):M_K_DQ<9>
  DG84  M_K_DQ<8>      DDR3_DQ<8>  @BASEBOARD_FAB2_LIB.BASEBOARD_FAB2(SCH_1):M_K_DQ<8>
  CW84  M_K_DQ<7>      DDR3_DQ<7>  @BASEBOARD_FAB2_LIB.BASEBOARD_FAB2(SCH_1):M_K_DQ<7>
  CW86  M_K_DQ<6>      DDR3_DQ<6>  @BASEBOARD_FAB2_LIB.BASEBOARD_FAB2(SCH_1):M_K_DQ<6>
  DW22  M_K_DQ<63>     DDR3_DQ<63>  @BASEBOARD_FAB2_LIB.BASEBOARD_FAB2(SCH_1):M_K_DQ<63>
  EC22  M_K_DQ<62>     DDR3_DQ<62>  @BASEBOARD_FAB2_LIB.BASEBOARD_FAB2(SCH_1):M_K_DQ<62>
  DT25  M_K_DQ<61>     DDR3_DQ<61>  @BASEBOARD_FAB2_LIB.BASEBOARD_FAB2(SCH_1):M_K_DQ<61>
  DP25  M_K_DQ<60>     DDR3_DQ<60>  @BASEBOARD_FAB2_LIB.BASEBOARD_FAB2(SCH_1):M_K_DQ<60>
  CL86  M_K_DQ<5>      DDR3_DQ<5>  @BASEBOARD_FAB2_LIB.BASEBOARD_FAB2(SCH_1):M_K_DQ<5>
  EB21  M_K_DQ<59>     DDR3_DQ<59>  @BASEBOARD_FAB2_LIB.BASEBOARD_FAB2(SCH_1):M_K_DQ<59>
  DY21  M_K_DQ<58>     DDR3_DQ<58>  @BASEBOARD_FAB2_LIB.BASEBOARD_FAB2(SCH_1):M_K_DQ<58>
  DU24  M_K_DQ<57>     DDR3_DQ<57>  @BASEBOARD_FAB2_LIB.BASEBOARD_FAB2(SCH_1):M_K_DQ<57>
  DN24  M_K_DQ<56>     DDR3_DQ<56>  @BASEBOARD_FAB2_LIB.BASEBOARD_FAB2(SCH_1):M_K_DQ<56>
  DU28  M_K_DQ<55>     DDR3_DQ<55>  @BASEBOARD_FAB2_LIB.BASEBOARD_FAB2(SCH_1):M_K_DQ<55>
  DN28  M_K_DQ<54>     DDR3_DQ<54>  @BASEBOARD_FAB2_LIB.BASEBOARD_FAB2(SCH_1):M_K_DQ<54>
  DT31  M_K_DQ<53>     DDR3_DQ<53>  @BASEBOARD_FAB2_LIB.BASEBOARD_FAB2(SCH_1):M_K_DQ<53>
  DP31  M_K_DQ<52>     DDR3_DQ<52>  @BASEBOARD_FAB2_LIB.BASEBOARD_FAB2(SCH_1):M_K_DQ<52>
  DT27  M_K_DQ<51>     DDR3_DQ<51>  @BASEBOARD_FAB2_LIB.BASEBOARD_FAB2(SCH_1):M_K_DQ<51>
  DP27  M_K_DQ<50>     DDR3_DQ<50>  @BASEBOARD_FAB2_LIB.BASEBOARD_FAB2(SCH_1):M_K_DQ<50>
  CL84  M_K_DQ<4>      DDR3_DQ<4>  @BASEBOARD_FAB2_LIB.BASEBOARD_FAB2(SCH_1):M_K_DQ<4>
  DU30  M_K_DQ<49>     DDR3_DQ<49>  @BASEBOARD_FAB2_LIB.BASEBOARD_FAB2(SCH_1):M_K_DQ<49>
  DN30  M_K_DQ<48>     DDR3_DQ<48>  @BASEBOARD_FAB2_LIB.BASEBOARD_FAB2(SCH_1):M_K_DQ<48>
  DU34  M_K_DQ<47>     DDR3_DQ<47>  @BASEBOARD_FAB2_LIB.BASEBOARD_FAB2(SCH_1):M_K_DQ<47>
  DN34  M_K_DQ<46>     DDR3_DQ<46>  @BASEBOARD_FAB2_LIB.BASEBOARD_FAB2(SCH_1):M_K_DQ<46>
  DT37  M_K_DQ<45>     DDR3_DQ<45>  @BASEBOARD_FAB2_LIB.BASEBOARD_FAB2(SCH_1):M_K_DQ<45>
  DP37  M_K_DQ<44>     DDR3_DQ<44>  @BASEBOARD_FAB2_LIB.BASEBOARD_FAB2(SCH_1):M_K_DQ<44>
  DT33  M_K_DQ<43>     DDR3_DQ<43>  @BASEBOARD_FAB2_LIB.BASEBOARD_FAB2(SCH_1):M_K_DQ<43>
  DP33  M_K_DQ<42>     DDR3_DQ<42>  @BASEBOARD_FAB2_LIB.BASEBOARD_FAB2(SCH_1):M_K_DQ<42>
  DU36  M_K_DQ<41>     DDR3_DQ<41>  @BASEBOARD_FAB2_LIB.BASEBOARD_FAB2(SCH_1):M_K_DQ<41>
  DN36  M_K_DQ<40>     DDR3_DQ<40>  @BASEBOARD_FAB2_LIB.BASEBOARD_FAB2(SCH_1):M_K_DQ<40>
  DA84  M_K_DQ<3>      DDR3_DQ<3>  @BASEBOARD_FAB2_LIB.BASEBOARD_FAB2(SCH_1):M_K_DQ<3>
  ED37  M_K_DQ<39>     DDR3_DQ<39>  @BASEBOARD_FAB2_LIB.BASEBOARD_FAB2(SCH_1):M_K_DQ<39>
  DY37  M_K_DQ<38>     DDR3_DQ<38>  @BASEBOARD_FAB2_LIB.BASEBOARD_FAB2(SCH_1):M_K_DQ<38>
  EA40  M_K_DQ<37>     DDR3_DQ<37>  @BASEBOARD_FAB2_LIB.BASEBOARD_FAB2(SCH_1):M_K_DQ<37>
  DY39  M_K_DQ<36>     DDR3_DQ<36>  @BASEBOARD_FAB2_LIB.BASEBOARD_FAB2(SCH_1):M_K_DQ<36>
  EC36  M_K_DQ<35>     DDR3_DQ<35>  @BASEBOARD_FAB2_LIB.BASEBOARD_FAB2(SCH_1):M_K_DQ<35>
  EA36  M_K_DQ<34>     DDR3_DQ<34>  @BASEBOARD_FAB2_LIB.BASEBOARD_FAB2(SCH_1):M_K_DQ<34>
  ED39  M_K_DQ<33>     DDR3_DQ<33>  @BASEBOARD_FAB2_LIB.BASEBOARD_FAB2(SCH_1):M_K_DQ<33>
  EC40  M_K_DQ<32>     DDR3_DQ<32>  @BASEBOARD_FAB2_LIB.BASEBOARD_FAB2(SCH_1):M_K_DQ<32>
  DU74  M_K_DQ<31>     DDR3_DQ<31>  @BASEBOARD_FAB2_LIB.BASEBOARD_FAB2(SCH_1):M_K_DQ<31>
  DN74  M_K_DQ<30>     DDR3_DQ<30>  @BASEBOARD_FAB2_LIB.BASEBOARD_FAB2(SCH_1):M_K_DQ<30>
  DA86  M_K_DQ<2>      DDR3_DQ<2>  @BASEBOARD_FAB2_LIB.BASEBOARD_FAB2(SCH_1):M_K_DQ<2>
  DT77  M_K_DQ<29>     DDR3_DQ<29>  @BASEBOARD_FAB2_LIB.BASEBOARD_FAB2(SCH_1):M_K_DQ<29>
  DP77  M_K_DQ<28>     DDR3_DQ<28>  @BASEBOARD_FAB2_LIB.BASEBOARD_FAB2(SCH_1):M_K_DQ<28>
  DT73  M_K_DQ<27>     DDR3_DQ<27>  @BASEBOARD_FAB2_LIB.BASEBOARD_FAB2(SCH_1):M_K_DQ<27>
  DP73  M_K_DQ<26>     DDR3_DQ<26>  @BASEBOARD_FAB2_LIB.BASEBOARD_FAB2(SCH_1):M_K_DQ<26>
  DU76  M_K_DQ<25>     DDR3_DQ<25>  @BASEBOARD_FAB2_LIB.BASEBOARD_FAB2(SCH_1):M_K_DQ<25>
  DN76  M_K_DQ<24>     DDR3_DQ<24>  @BASEBOARD_FAB2_LIB.BASEBOARD_FAB2(SCH_1):M_K_DQ<24>
  DN82  M_K_DQ<23>     DDR3_DQ<23>  @BASEBOARD_FAB2_LIB.BASEBOARD_FAB2(SCH_1):M_K_DQ<23>
  DR80  M_K_DQ<22>     DDR3_DQ<22>  @BASEBOARD_FAB2_LIB.BASEBOARD_FAB2(SCH_1):M_K_DQ<22>
  DJ80  M_K_DQ<21>     DDR3_DQ<21>  @BASEBOARD_FAB2_LIB.BASEBOARD_FAB2(SCH_1):M_K_DQ<21>
  DK79  M_K_DQ<20>     DDR3_DQ<20>  @BASEBOARD_FAB2_LIB.BASEBOARD_FAB2(SCH_1):M_K_DQ<20>
  CN86  M_K_DQ<1>      DDR3_DQ<1>  @BASEBOARD_FAB2_LIB.BASEBOARD_FAB2(SCH_1):M_K_DQ<1>
  DR82  M_K_DQ<19>     DDR3_DQ<19>  @BASEBOARD_FAB2_LIB.BASEBOARD_FAB2(SCH_1):M_K_DQ<19>
  DT81  M_K_DQ<18>     DDR3_DQ<18>  @BASEBOARD_FAB2_LIB.BASEBOARD_FAB2(SCH_1):M_K_DQ<18>
  DK81  M_K_DQ<17>     DDR3_DQ<17>  @BASEBOARD_FAB2_LIB.BASEBOARD_FAB2(SCH_1):M_K_DQ<17>
  DM79  M_K_DQ<16>     DDR3_DQ<16>  @BASEBOARD_FAB2_LIB.BASEBOARD_FAB2(SCH_1):M_K_DQ<16>
  DV85  M_K_DQ<15>     DDR3_DQ<15>  @BASEBOARD_FAB2_LIB.BASEBOARD_FAB2(SCH_1):M_K_DQ<15>
  DR84  M_K_DQ<14>     DDR3_DQ<14>  @BASEBOARD_FAB2_LIB.BASEBOARD_FAB2(SCH_1):M_K_DQ<14>
  DE84  M_K_DQ<13>     DDR3_DQ<13>  @BASEBOARD_FAB2_LIB.BASEBOARD_FAB2(SCH_1):M_K_DQ<13>
  DD85  M_K_DQ<12>     DDR3_DQ<12>  @BASEBOARD_FAB2_LIB.BASEBOARD_FAB2(SCH_1):M_K_DQ<12>
  DY83  M_K_DQ<11>     DDR3_DQ<11>  @BASEBOARD_FAB2_LIB.BASEBOARD_FAB2(SCH_1):M_K_DQ<11>
  DV83  M_K_DQ<10>     DDR3_DQ<10>  @BASEBOARD_FAB2_LIB.BASEBOARD_FAB2(SCH_1):M_K_DQ<10>
  CN84  M_K_DQ<0>      DDR3_DQ<0>  @BASEBOARD_FAB2_LIB.BASEBOARD_FAB2(SCH_1):M_K_DQ<0>
  EB45  M_K_CS_N<7>    DDR3_CS_N<7>  @BASEBOARD_FAB2_LIB.BASEBOARD_FAB2(SCH_1):M_K_CS_N<7>
  DV45  M_K_CS_N<6>    DDR3_CS_N<6>  @BASEBOARD_FAB2_LIB.BASEBOARD_FAB2(SCH_1):M_K_CS_N<6>
  EB49  M_K_CS_N<5>    DDR3_CS_N<5>  @BASEBOARD_FAB2_LIB.BASEBOARD_FAB2(SCH_1):M_K_CS_N<5>
  EB51  M_K_CS_N<4>    DDR3_CS_N<4>  @BASEBOARD_FAB2_LIB.BASEBOARD_FAB2(SCH_1):M_K_CS_N<4>
  EB47  M_K_CS_N<3>    DDR3_CS_N<3>  @BASEBOARD_FAB2_LIB.BASEBOARD_FAB2(SCH_1):M_K_CS_N<3>
  ED47  M_K_CS_N<2>    DDR3_CS_N<2>  @BASEBOARD_FAB2_LIB.BASEBOARD_FAB2(SCH_1):M_K_CS_N<2>
  ED49  M_K_CS_N<1>    DDR3_CS_N<1>  @BASEBOARD_FAB2_LIB.BASEBOARD_FAB2(SCH_1):M_K_CS_N<1>
  EF51  M_K_CS_N<0>    DDR3_CS_N<0>  @BASEBOARD_FAB2_LIB.BASEBOARD_FAB2(SCH_1):M_K_CS_N<0>
  EE56  M_K_CLK_DP<3>  DDR3_CLK_DP<3>  @BASEBOARD_FAB2_LIB.BASEBOARD_FAB2(SCH_1):M_K_CLK_DP<3>
  EA56  M_K_CLK_DP<2>  DDR3_CLK_DP<2>  @BASEBOARD_FAB2_LIB.BASEBOARD_FAB2(SCH_1):M_K_CLK_DP<2>
  EE54  M_K_CLK_DP<1>  DDR3_CLK_DP<1>  @BASEBOARD_FAB2_LIB.BASEBOARD_FAB2(SCH_1):M_K_CLK_DP<1>
  EB55  M_K_CLK_DP<0>  DDR3_CLK_DP<0>  @BASEBOARD_FAB2_LIB.BASEBOARD_FAB2(SCH_1):M_K_CLK_DP<0>
  EF57  M_K_CLK_DN<3>  DDR3_CLK_DN<3>  @BASEBOARD_FAB2_LIB.BASEBOARD_FAB2(SCH_1):M_K_CLK_DN<3>
  DW56  M_K_CLK_DN<2>  DDR3_CLK_DN<2>  @BASEBOARD_FAB2_LIB.BASEBOARD_FAB2(SCH_1):M_K_CLK_DN<2>
  EF55  M_K_CLK_DN<1>  DDR3_CLK_DN<1>  @BASEBOARD_FAB2_LIB.BASEBOARD_FAB2(SCH_1):M_K_CLK_DN<1>
  ED55  M_K_CLK_DN<0>  DDR3_CLK_DN<0>  @BASEBOARD_FAB2_LIB.BASEBOARD_FAB2(SCH_1):M_K_CLK_DN<0>
  EB63  M_K_CKE<3>     DDR3_CKE<3>  @BASEBOARD_FAB2_LIB.BASEBOARD_FAB2(SCH_1):M_K_CKE<3>
  EA62  M_K_CKE<2>     DDR3_CKE<2>  @BASEBOARD_FAB2_LIB.BASEBOARD_FAB2(SCH_1):M_K_CKE<2>
  EF63  M_K_CKE<1>     DDR3_CKE<1>  @BASEBOARD_FAB2_LIB.BASEBOARD_FAB2(SCH_1):M_K_CKE<1>
  EE62  M_K_CKE<0>     DDR3_CKE<0>  @BASEBOARD_FAB2_LIB.BASEBOARD_FAB2(SCH_1):M_K_CKE<0>
  DV47  M_K_C<2>       DDR3_CID<2>  @BASEBOARD_FAB2_LIB.BASEBOARD_FAB2(SCH_1):M_K_C<2>
  DW62  M_K_BG<1>      DDR3_BG<1>  @BASEBOARD_FAB2_LIB.BASEBOARD_FAB2(SCH_1):M_K_BG<1>
  ED61  M_K_BG<0>      DDR3_BG<0>  @BASEBOARD_FAB2_LIB.BASEBOARD_FAB2(SCH_1):M_K_BG<0>
  EA54  M_K_BA<1>      DDR3_BA<1>  @BASEBOARD_FAB2_LIB.BASEBOARD_FAB2(SCH_1):M_K_BA<1>
  EE52  M_K_BA<0>      DDR3_BA<0>  @BASEBOARD_FAB2_LIB.BASEBOARD_FAB2(SCH_1):M_K_BA<0>
  ED63  M_K_ALERT_N    DDR3_ALERT_N  @BASEBOARD_FAB2_LIB.BASEBOARD_FAB2(SCH_1):M_K_ALERT_N
  DW60  M_K_ACT_N      DDR3_ACT_N  @BASEBOARD_FAB2_LIB.BASEBOARD_FAB2(SCH_1):M_K_ACT_N

SKX_EXT_B_BGA1  I172  U2D1   [SKX_EXT_B_BGA1-IC,TBD]
  V53  M_J_PAR        DDR2_PAR  @BASEBOARD_FAB2_LIB.BASEBOARD_FAB2(SCH_1):M_J_PAR
  AB47  M_J_ODT<3>     DDR2_ODT<3>  @BASEBOARD_FAB2_LIB.BASEBOARD_FAB2(SCH_1):M_J_ODT<3>
  V49  M_J_ODT<2>     DDR2_ODT<2>  @BASEBOARD_FAB2_LIB.BASEBOARD_FAB2(SCH_1):M_J_ODT<2>
  AA48  M_J_ODT<1>     DDR2_ODT<1>  @BASEBOARD_FAB2_LIB.BASEBOARD_FAB2(SCH_1):M_J_ODT<1>
  AA50  M_J_ODT<0>     DDR2_ODT<0>  @BASEBOARD_FAB2_LIB.BASEBOARD_FAB2(SCH_1):M_J_ODT<0>
  AG58  M_J_MA<9>      DDR2_MA<9>  @BASEBOARD_FAB2_LIB.BASEBOARD_FAB2(SCH_1):M_J_MA<9>
  AD59  M_J_MA<8>      DDR2_MA<8>  @BASEBOARD_FAB2_LIB.BASEBOARD_FAB2(SCH_1):M_J_MA<8>
  AE60  M_J_MA<7>      DDR2_MA<7>  @BASEBOARD_FAB2_LIB.BASEBOARD_FAB2(SCH_1):M_J_MA<7>
  AB59  M_J_MA<6>      DDR2_MA<6>  @BASEBOARD_FAB2_LIB.BASEBOARD_FAB2(SCH_1):M_J_MA<6>
  V59  M_J_MA<5>      DDR2_MA<5>  @BASEBOARD_FAB2_LIB.BASEBOARD_FAB2(SCH_1):M_J_MA<5>
  AA58  M_J_MA<4>      DDR2_MA<4>  @BASEBOARD_FAB2_LIB.BASEBOARD_FAB2(SCH_1):M_J_MA<4>
  W58  M_J_MA<3>      DDR2_MA<3>  @BASEBOARD_FAB2_LIB.BASEBOARD_FAB2(SCH_1):M_J_MA<3>
  AD57  M_J_MA<2>      DDR2_MA<2>  @BASEBOARD_FAB2_LIB.BASEBOARD_FAB2(SCH_1):M_J_MA<2>
  AE58  M_J_MA<1>      DDR2_MA<1>  @BASEBOARD_FAB2_LIB.BASEBOARD_FAB2(SCH_1):M_J_MA<1>
  AC46  M_J_MA<17>     DDR2_MA<17>  @BASEBOARD_FAB2_LIB.BASEBOARD_FAB2(SCH_1):M_J_MA<17>
  AA52  M_J_MA<16>     DDR2_MA<16>  @BASEBOARD_FAB2_LIB.BASEBOARD_FAB2(SCH_1):M_J_MA<16>
  AE54  M_J_MA<15>     DDR2_MA<15>  @BASEBOARD_FAB2_LIB.BASEBOARD_FAB2(SCH_1):M_J_MA<15>
  W50  M_J_MA<14>     DDR2_MA<14>  @BASEBOARD_FAB2_LIB.BASEBOARD_FAB2(SCH_1):M_J_MA<14>
  AD53  M_J_MA<13>     DDR2_MA<13>  @BASEBOARD_FAB2_LIB.BASEBOARD_FAB2(SCH_1):M_J_MA<13>
  AG62  M_J_MA<12>     DDR2_MA<12>  @BASEBOARD_FAB2_LIB.BASEBOARD_FAB2(SCH_1):M_J_MA<12>
  AG60  M_J_MA<11>     DDR2_MA<11>  @BASEBOARD_FAB2_LIB.BASEBOARD_FAB2(SCH_1):M_J_MA<11>
  AD55  M_J_MA<10>     DDR2_MA<10>  @BASEBOARD_FAB2_LIB.BASEBOARD_FAB2(SCH_1):M_J_MA<10>
  AB53  M_J_MA<0>      DDR2_MA<0>  @BASEBOARD_FAB2_LIB.BASEBOARD_FAB2(SCH_1):M_J_MA<0>
  BA70  M_J_ECC<7>     DDR2_ECC<7>  @BASEBOARD_FAB2_LIB.BASEBOARD_FAB2(SCH_1):M_J_ECC<7>
  AU70  M_J_ECC<6>     DDR2_ECC<6>  @BASEBOARD_FAB2_LIB.BASEBOARD_FAB2(SCH_1):M_J_ECC<6>
  AY73  M_J_ECC<5>     DDR2_ECC<5>  @BASEBOARD_FAB2_LIB.BASEBOARD_FAB2(SCH_1):M_J_ECC<5>
  AV73  M_J_ECC<4>     DDR2_ECC<4>  @BASEBOARD_FAB2_LIB.BASEBOARD_FAB2(SCH_1):M_J_ECC<4>
  AY69  M_J_ECC<3>     DDR2_ECC<3>  @BASEBOARD_FAB2_LIB.BASEBOARD_FAB2(SCH_1):M_J_ECC<3>
  AV69  M_J_ECC<2>     DDR2_ECC<2>  @BASEBOARD_FAB2_LIB.BASEBOARD_FAB2(SCH_1):M_J_ECC<2>
  BA72  M_J_ECC<1>     DDR2_ECC<1>  @BASEBOARD_FAB2_LIB.BASEBOARD_FAB2(SCH_1):M_J_ECC<1>
  AU72  M_J_ECC<0>     DDR2_ECC<0>  @BASEBOARD_FAB2_LIB.BASEBOARD_FAB2(SCH_1):M_J_ECC<0>
  AN76  M_J_DQS_DP<9>  DDR2_DQS_DP<9>  @BASEBOARD_FAB2_LIB.BASEBOARD_FAB2(SCH_1):M_J_DQS_DP<9>
  AY71  M_J_DQS_DP<8>  DDR2_DQS_DP<8>  @BASEBOARD_FAB2_LIB.BASEBOARD_FAB2(SCH_1):M_J_DQS_DP<8>
  AG24  M_J_DQS_DP<7>  DDR2_DQS_DP<7>  @BASEBOARD_FAB2_LIB.BASEBOARD_FAB2(SCH_1):M_J_DQS_DP<7>
  AG30  M_J_DQS_DP<6>  DDR2_DQS_DP<6>  @BASEBOARD_FAB2_LIB.BASEBOARD_FAB2(SCH_1):M_J_DQS_DP<6>
  Y33  M_J_DQS_DP<5>  DDR2_DQS_DP<5>  @BASEBOARD_FAB2_LIB.BASEBOARD_FAB2(SCH_1):M_J_DQS_DP<5>
  Y39  M_J_DQS_DP<4>  DDR2_DQS_DP<4>  @BASEBOARD_FAB2_LIB.BASEBOARD_FAB2(SCH_1):M_J_DQS_DP<4>
  AR66  M_J_DQS_DP<3>  DDR2_DQS_DP<3>  @BASEBOARD_FAB2_LIB.BASEBOARD_FAB2(SCH_1):M_J_DQS_DP<3>
  W70  M_J_DQS_DP<2>  DDR2_DQS_DP<2>  @BASEBOARD_FAB2_LIB.BASEBOARD_FAB2(SCH_1):M_J_DQS_DP<2>
  AB75  M_J_DQS_DP<1>  DDR2_DQS_DP<1>  @BASEBOARD_FAB2_LIB.BASEBOARD_FAB2(SCH_1):M_J_DQS_DP<1>
  AV71  M_J_DQS_DP<17>  DDR2_DQS_DP<17>  @BASEBOARD_FAB2_LIB.BASEBOARD_FAB2(SCH_1):M_J_DQS_DP<17>
  AE24  M_J_DQS_DP<16>  DDR2_DQS_DP<16>  @BASEBOARD_FAB2_LIB.BASEBOARD_FAB2(SCH_1):M_J_DQS_DP<16>
  AE30  M_J_DQS_DP<15>  DDR2_DQS_DP<15>  @BASEBOARD_FAB2_LIB.BASEBOARD_FAB2(SCH_1):M_J_DQS_DP<15>
  V33  M_J_DQS_DP<14>  DDR2_DQS_DP<14>  @BASEBOARD_FAB2_LIB.BASEBOARD_FAB2(SCH_1):M_J_DQS_DP<14>
  V39  M_J_DQS_DP<13>  DDR2_DQS_DP<13>  @BASEBOARD_FAB2_LIB.BASEBOARD_FAB2(SCH_1):M_J_DQS_DP<13>
  AN66  M_J_DQS_DP<12>  DDR2_DQS_DP<12>  @BASEBOARD_FAB2_LIB.BASEBOARD_FAB2(SCH_1):M_J_DQS_DP<12>
  V71  M_J_DQS_DP<11>  DDR2_DQS_DP<11>  @BASEBOARD_FAB2_LIB.BASEBOARD_FAB2(SCH_1):M_J_DQS_DP<11>
  AC76  M_J_DQS_DP<10>  DDR2_DQS_DP<10>  @BASEBOARD_FAB2_LIB.BASEBOARD_FAB2(SCH_1):M_J_DQS_DP<10>
  AM75  M_J_DQS_DP<0>  DDR2_DQS_DP<0>  @BASEBOARD_FAB2_LIB.BASEBOARD_FAB2(SCH_1):M_J_DQS_DP<0>
  AP77  M_J_DQS_DN<9>  DDR2_DQS_DN<9>  @BASEBOARD_FAB2_LIB.BASEBOARD_FAB2(SCH_1):M_J_DQS_DN<9>
  BB71  M_J_DQS_DN<8>  DDR2_DQS_DN<8>  @BASEBOARD_FAB2_LIB.BASEBOARD_FAB2(SCH_1):M_J_DQS_DN<8>
  AJ24  M_J_DQS_DN<7>  DDR2_DQS_DN<7>  @BASEBOARD_FAB2_LIB.BASEBOARD_FAB2(SCH_1):M_J_DQS_DN<7>
  AJ30  M_J_DQS_DN<6>  DDR2_DQS_DN<6>  @BASEBOARD_FAB2_LIB.BASEBOARD_FAB2(SCH_1):M_J_DQS_DN<6>
  AB33  M_J_DQS_DN<5>  DDR2_DQS_DN<5>  @BASEBOARD_FAB2_LIB.BASEBOARD_FAB2(SCH_1):M_J_DQS_DN<5>
  AB39  M_J_DQS_DN<4>  DDR2_DQS_DN<4>  @BASEBOARD_FAB2_LIB.BASEBOARD_FAB2(SCH_1):M_J_DQS_DN<4>
  AU66  M_J_DQS_DN<3>  DDR2_DQS_DN<3>  @BASEBOARD_FAB2_LIB.BASEBOARD_FAB2(SCH_1):M_J_DQS_DN<3>
  Y69  M_J_DQS_DN<2>  DDR2_DQS_DN<2>  @BASEBOARD_FAB2_LIB.BASEBOARD_FAB2(SCH_1):M_J_DQS_DN<2>
  AA74  M_J_DQS_DN<1>  DDR2_DQS_DN<1>  @BASEBOARD_FAB2_LIB.BASEBOARD_FAB2(SCH_1):M_J_DQS_DN<1>
  AT71  M_J_DQS_DN<17>  DDR2_DQS_DN<17>  @BASEBOARD_FAB2_LIB.BASEBOARD_FAB2(SCH_1):M_J_DQS_DN<17>
  AC24  M_J_DQS_DN<16>  DDR2_DQS_DN<16>  @BASEBOARD_FAB2_LIB.BASEBOARD_FAB2(SCH_1):M_J_DQS_DN<16>
  AC30  M_J_DQS_DN<15>  DDR2_DQS_DN<15>  @BASEBOARD_FAB2_LIB.BASEBOARD_FAB2(SCH_1):M_J_DQS_DN<15>
  T33  M_J_DQS_DN<14>  DDR2_DQS_DN<14>  @BASEBOARD_FAB2_LIB.BASEBOARD_FAB2(SCH_1):M_J_DQS_DN<14>
  T39  M_J_DQS_DN<13>  DDR2_DQS_DN<13>  @BASEBOARD_FAB2_LIB.BASEBOARD_FAB2(SCH_1):M_J_DQS_DN<13>
  AL66  M_J_DQS_DN<12>  DDR2_DQS_DN<12>  @BASEBOARD_FAB2_LIB.BASEBOARD_FAB2(SCH_1):M_J_DQS_DN<12>
  U72  M_J_DQS_DN<11>  DDR2_DQS_DN<11>  @BASEBOARD_FAB2_LIB.BASEBOARD_FAB2(SCH_1):M_J_DQS_DN<11>
  AD77  M_J_DQS_DN<10>  DDR2_DQS_DN<10>  @BASEBOARD_FAB2_LIB.BASEBOARD_FAB2(SCH_1):M_J_DQS_DN<10>
  AL74  M_J_DQS_DN<0>  DDR2_DQS_DN<0>  @BASEBOARD_FAB2_LIB.BASEBOARD_FAB2(SCH_1):M_J_DQS_DN<0>
  AC74  M_J_DQ<9>      DDR2_DQ<9>  @BASEBOARD_FAB2_LIB.BASEBOARD_FAB2(SCH_1):M_J_DQ<9>
  AE76  M_J_DQ<8>      DDR2_DQ<8>  @BASEBOARD_FAB2_LIB.BASEBOARD_FAB2(SCH_1):M_J_DQ<8>
  AK75  M_J_DQ<7>      DDR2_DQ<7>  @BASEBOARD_FAB2_LIB.BASEBOARD_FAB2(SCH_1):M_J_DQ<7>
  AM77  M_J_DQ<6>      DDR2_DQ<6>  @BASEBOARD_FAB2_LIB.BASEBOARD_FAB2(SCH_1):M_J_DQ<6>
  AH23  M_J_DQ<63>     DDR2_DQ<63>  @BASEBOARD_FAB2_LIB.BASEBOARD_FAB2(SCH_1):M_J_DQ<63>
  AD23  M_J_DQ<62>     DDR2_DQ<62>  @BASEBOARD_FAB2_LIB.BASEBOARD_FAB2(SCH_1):M_J_DQ<62>
  AG26  M_J_DQ<61>     DDR2_DQ<61>  @BASEBOARD_FAB2_LIB.BASEBOARD_FAB2(SCH_1):M_J_DQ<61>
  AE26  M_J_DQ<60>     DDR2_DQ<60>  @BASEBOARD_FAB2_LIB.BASEBOARD_FAB2(SCH_1):M_J_DQ<60>
  AR74  M_J_DQ<5>      DDR2_DQ<5>  @BASEBOARD_FAB2_LIB.BASEBOARD_FAB2(SCH_1):M_J_DQ<5>
  AG22  M_J_DQ<59>     DDR2_DQ<59>  @BASEBOARD_FAB2_LIB.BASEBOARD_FAB2(SCH_1):M_J_DQ<59>
  AE22  M_J_DQ<58>     DDR2_DQ<58>  @BASEBOARD_FAB2_LIB.BASEBOARD_FAB2(SCH_1):M_J_DQ<58>
  AH25  M_J_DQ<57>     DDR2_DQ<57>  @BASEBOARD_FAB2_LIB.BASEBOARD_FAB2(SCH_1):M_J_DQ<57>
  AD25  M_J_DQ<56>     DDR2_DQ<56>  @BASEBOARD_FAB2_LIB.BASEBOARD_FAB2(SCH_1):M_J_DQ<56>
  AH29  M_J_DQ<55>     DDR2_DQ<55>  @BASEBOARD_FAB2_LIB.BASEBOARD_FAB2(SCH_1):M_J_DQ<55>
  AD29  M_J_DQ<54>     DDR2_DQ<54>  @BASEBOARD_FAB2_LIB.BASEBOARD_FAB2(SCH_1):M_J_DQ<54>
  AG32  M_J_DQ<53>     DDR2_DQ<53>  @BASEBOARD_FAB2_LIB.BASEBOARD_FAB2(SCH_1):M_J_DQ<53>
  AE32  M_J_DQ<52>     DDR2_DQ<52>  @BASEBOARD_FAB2_LIB.BASEBOARD_FAB2(SCH_1):M_J_DQ<52>
  AG28  M_J_DQ<51>     DDR2_DQ<51>  @BASEBOARD_FAB2_LIB.BASEBOARD_FAB2(SCH_1):M_J_DQ<51>
  AE28  M_J_DQ<50>     DDR2_DQ<50>  @BASEBOARD_FAB2_LIB.BASEBOARD_FAB2(SCH_1):M_J_DQ<50>
  AT75  M_J_DQ<4>      DDR2_DQ<4>  @BASEBOARD_FAB2_LIB.BASEBOARD_FAB2(SCH_1):M_J_DQ<4>
  AH31  M_J_DQ<49>     DDR2_DQ<49>  @BASEBOARD_FAB2_LIB.BASEBOARD_FAB2(SCH_1):M_J_DQ<49>
  AD31  M_J_DQ<48>     DDR2_DQ<48>  @BASEBOARD_FAB2_LIB.BASEBOARD_FAB2(SCH_1):M_J_DQ<48>
  AA32  M_J_DQ<47>     DDR2_DQ<47>  @BASEBOARD_FAB2_LIB.BASEBOARD_FAB2(SCH_1):M_J_DQ<47>
  U32  M_J_DQ<46>     DDR2_DQ<46>  @BASEBOARD_FAB2_LIB.BASEBOARD_FAB2(SCH_1):M_J_DQ<46>
  Y35  M_J_DQ<45>     DDR2_DQ<45>  @BASEBOARD_FAB2_LIB.BASEBOARD_FAB2(SCH_1):M_J_DQ<45>
  V35  M_J_DQ<44>     DDR2_DQ<44>  @BASEBOARD_FAB2_LIB.BASEBOARD_FAB2(SCH_1):M_J_DQ<44>
  Y31  M_J_DQ<43>     DDR2_DQ<43>  @BASEBOARD_FAB2_LIB.BASEBOARD_FAB2(SCH_1):M_J_DQ<43>
  V31  M_J_DQ<42>     DDR2_DQ<42>  @BASEBOARD_FAB2_LIB.BASEBOARD_FAB2(SCH_1):M_J_DQ<42>
  AA34  M_J_DQ<41>     DDR2_DQ<41>  @BASEBOARD_FAB2_LIB.BASEBOARD_FAB2(SCH_1):M_J_DQ<41>
  U34  M_J_DQ<40>     DDR2_DQ<40>  @BASEBOARD_FAB2_LIB.BASEBOARD_FAB2(SCH_1):M_J_DQ<40>
  AJ76  M_J_DQ<3>      DDR2_DQ<3>  @BASEBOARD_FAB2_LIB.BASEBOARD_FAB2(SCH_1):M_J_DQ<3>
  AA38  M_J_DQ<39>     DDR2_DQ<39>  @BASEBOARD_FAB2_LIB.BASEBOARD_FAB2(SCH_1):M_J_DQ<39>
  U38  M_J_DQ<38>     DDR2_DQ<38>  @BASEBOARD_FAB2_LIB.BASEBOARD_FAB2(SCH_1):M_J_DQ<38>
  Y41  M_J_DQ<37>     DDR2_DQ<37>  @BASEBOARD_FAB2_LIB.BASEBOARD_FAB2(SCH_1):M_J_DQ<37>
  V41  M_J_DQ<36>     DDR2_DQ<36>  @BASEBOARD_FAB2_LIB.BASEBOARD_FAB2(SCH_1):M_J_DQ<36>
  Y37  M_J_DQ<35>     DDR2_DQ<35>  @BASEBOARD_FAB2_LIB.BASEBOARD_FAB2(SCH_1):M_J_DQ<35>
  V37  M_J_DQ<34>     DDR2_DQ<34>  @BASEBOARD_FAB2_LIB.BASEBOARD_FAB2(SCH_1):M_J_DQ<34>
  AA40  M_J_DQ<33>     DDR2_DQ<33>  @BASEBOARD_FAB2_LIB.BASEBOARD_FAB2(SCH_1):M_J_DQ<33>
  U40  M_J_DQ<32>     DDR2_DQ<32>  @BASEBOARD_FAB2_LIB.BASEBOARD_FAB2(SCH_1):M_J_DQ<32>
  AT65  M_J_DQ<31>     DDR2_DQ<31>  @BASEBOARD_FAB2_LIB.BASEBOARD_FAB2(SCH_1):M_J_DQ<31>
  AM65  M_J_DQ<30>     DDR2_DQ<30>  @BASEBOARD_FAB2_LIB.BASEBOARD_FAB2(SCH_1):M_J_DQ<30>
  AK77  M_J_DQ<2>      DDR2_DQ<2>  @BASEBOARD_FAB2_LIB.BASEBOARD_FAB2(SCH_1):M_J_DQ<2>
  AR68  M_J_DQ<29>     DDR2_DQ<29>  @BASEBOARD_FAB2_LIB.BASEBOARD_FAB2(SCH_1):M_J_DQ<29>
  AN68  M_J_DQ<28>     DDR2_DQ<28>  @BASEBOARD_FAB2_LIB.BASEBOARD_FAB2(SCH_1):M_J_DQ<28>
  AR64  M_J_DQ<27>     DDR2_DQ<27>  @BASEBOARD_FAB2_LIB.BASEBOARD_FAB2(SCH_1):M_J_DQ<27>
  AN64  M_J_DQ<26>     DDR2_DQ<26>  @BASEBOARD_FAB2_LIB.BASEBOARD_FAB2(SCH_1):M_J_DQ<26>
  AT67  M_J_DQ<25>     DDR2_DQ<25>  @BASEBOARD_FAB2_LIB.BASEBOARD_FAB2(SCH_1):M_J_DQ<25>
  AM67  M_J_DQ<24>     DDR2_DQ<24>  @BASEBOARD_FAB2_LIB.BASEBOARD_FAB2(SCH_1):M_J_DQ<24>
  V69  M_J_DQ<23>     DDR2_DQ<23>  @BASEBOARD_FAB2_LIB.BASEBOARD_FAB2(SCH_1):M_J_DQ<23>
  T71  M_J_DQ<22>     DDR2_DQ<22>  @BASEBOARD_FAB2_LIB.BASEBOARD_FAB2(SCH_1):M_J_DQ<22>
  AB71  M_J_DQ<21>     DDR2_DQ<21>  @BASEBOARD_FAB2_LIB.BASEBOARD_FAB2(SCH_1):M_J_DQ<21>
  AA72  M_J_DQ<20>     DDR2_DQ<20>  @BASEBOARD_FAB2_LIB.BASEBOARD_FAB2(SCH_1):M_J_DQ<20>
  AN74  M_J_DQ<1>      DDR2_DQ<1>  @BASEBOARD_FAB2_LIB.BASEBOARD_FAB2(SCH_1):M_J_DQ<1>
  T69  M_J_DQ<19>     DDR2_DQ<19>  @BASEBOARD_FAB2_LIB.BASEBOARD_FAB2(SCH_1):M_J_DQ<19>
  R70  M_J_DQ<18>     DDR2_DQ<18>  @BASEBOARD_FAB2_LIB.BASEBOARD_FAB2(SCH_1):M_J_DQ<18>
  AA70  M_J_DQ<17>     DDR2_DQ<17>  @BASEBOARD_FAB2_LIB.BASEBOARD_FAB2(SCH_1):M_J_DQ<17>
  W72  M_J_DQ<16>     DDR2_DQ<16>  @BASEBOARD_FAB2_LIB.BASEBOARD_FAB2(SCH_1):M_J_DQ<16>
  Y75  M_J_DQ<15>     DDR2_DQ<15>  @BASEBOARD_FAB2_LIB.BASEBOARD_FAB2(SCH_1):M_J_DQ<15>
  AB77  M_J_DQ<14>     DDR2_DQ<14>  @BASEBOARD_FAB2_LIB.BASEBOARD_FAB2(SCH_1):M_J_DQ<14>
  AE74  M_J_DQ<13>     DDR2_DQ<13>  @BASEBOARD_FAB2_LIB.BASEBOARD_FAB2(SCH_1):M_J_DQ<13>
  AF75  M_J_DQ<12>     DDR2_DQ<12>  @BASEBOARD_FAB2_LIB.BASEBOARD_FAB2(SCH_1):M_J_DQ<12>
  W76  M_J_DQ<11>     DDR2_DQ<11>  @BASEBOARD_FAB2_LIB.BASEBOARD_FAB2(SCH_1):M_J_DQ<11>
  Y77  M_J_DQ<10>     DDR2_DQ<10>  @BASEBOARD_FAB2_LIB.BASEBOARD_FAB2(SCH_1):M_J_DQ<10>
  AR76  M_J_DQ<0>      DDR2_DQ<0>  @BASEBOARD_FAB2_LIB.BASEBOARD_FAB2(SCH_1):M_J_DQ<0>
  V45  M_J_CS_N<7>    DDR2_CS_N<7>  @BASEBOARD_FAB2_LIB.BASEBOARD_FAB2(SCH_1):M_J_CS_N<7>
  T45  M_J_CS_N<6>    DDR2_CS_N<6>  @BASEBOARD_FAB2_LIB.BASEBOARD_FAB2(SCH_1):M_J_CS_N<6>
  W48  M_J_CS_N<5>    DDR2_CS_N<5>  @BASEBOARD_FAB2_LIB.BASEBOARD_FAB2(SCH_1):M_J_CS_N<5>
  AB51  M_J_CS_N<4>    DDR2_CS_N<4>  @BASEBOARD_FAB2_LIB.BASEBOARD_FAB2(SCH_1):M_J_CS_N<4>
  AA46  M_J_CS_N<3>    DDR2_CS_N<3>  @BASEBOARD_FAB2_LIB.BASEBOARD_FAB2(SCH_1):M_J_CS_N<3>
  W46  M_J_CS_N<2>    DDR2_CS_N<2>  @BASEBOARD_FAB2_LIB.BASEBOARD_FAB2(SCH_1):M_J_CS_N<2>
  AB49  M_J_CS_N<1>    DDR2_CS_N<1>  @BASEBOARD_FAB2_LIB.BASEBOARD_FAB2(SCH_1):M_J_CS_N<1>
  V51  M_J_CS_N<0>    DDR2_CS_N<0>  @BASEBOARD_FAB2_LIB.BASEBOARD_FAB2(SCH_1):M_J_CS_N<0>
  V57  M_J_CLK_DP<3>  DDR2_CLK_DP<3>  @BASEBOARD_FAB2_LIB.BASEBOARD_FAB2(SCH_1):M_J_CLK_DP<3>
  AB57  M_J_CLK_DP<2>  DDR2_CLK_DP<2>  @BASEBOARD_FAB2_LIB.BASEBOARD_FAB2(SCH_1):M_J_CLK_DP<2>
  V55  M_J_CLK_DP<1>  DDR2_CLK_DP<1>  @BASEBOARD_FAB2_LIB.BASEBOARD_FAB2(SCH_1):M_J_CLK_DP<1>
  AB55  M_J_CLK_DP<0>  DDR2_CLK_DP<0>  @BASEBOARD_FAB2_LIB.BASEBOARD_FAB2(SCH_1):M_J_CLK_DP<0>
  W56  M_J_CLK_DN<3>  DDR2_CLK_DN<3>  @BASEBOARD_FAB2_LIB.BASEBOARD_FAB2(SCH_1):M_J_CLK_DN<3>
  AA56  M_J_CLK_DN<2>  DDR2_CLK_DN<2>  @BASEBOARD_FAB2_LIB.BASEBOARD_FAB2(SCH_1):M_J_CLK_DN<2>
  W54  M_J_CLK_DN<1>  DDR2_CLK_DN<1>  @BASEBOARD_FAB2_LIB.BASEBOARD_FAB2(SCH_1):M_J_CLK_DN<1>
  AA54  M_J_CLK_DN<0>  DDR2_CLK_DN<0>  @BASEBOARD_FAB2_LIB.BASEBOARD_FAB2(SCH_1):M_J_CLK_DN<0>
  AB63  M_J_CKE<3>     DDR2_CKE<3>  @BASEBOARD_FAB2_LIB.BASEBOARD_FAB2(SCH_1):M_J_CKE<3>
  V63  M_J_CKE<2>     DDR2_CKE<2>  @BASEBOARD_FAB2_LIB.BASEBOARD_FAB2(SCH_1):M_J_CKE<2>
  AD63  M_J_CKE<1>     DDR2_CKE<1>  @BASEBOARD_FAB2_LIB.BASEBOARD_FAB2(SCH_1):M_J_CKE<1>
  AA62  M_J_CKE<0>     DDR2_CKE<0>  @BASEBOARD_FAB2_LIB.BASEBOARD_FAB2(SCH_1):M_J_CKE<0>
  AB45  M_J_C<2>       DDR2_CID<2>  @BASEBOARD_FAB2_LIB.BASEBOARD_FAB2(SCH_1):M_J_C<2>
  AE62  M_J_BG<1>      DDR2_BG<1>  @BASEBOARD_FAB2_LIB.BASEBOARD_FAB2(SCH_1):M_J_BG<1>
  AA60  M_J_BG<0>      DDR2_BG<0>  @BASEBOARD_FAB2_LIB.BASEBOARD_FAB2(SCH_1):M_J_BG<0>
  AE56  M_J_BA<1>      DDR2_BA<1>  @BASEBOARD_FAB2_LIB.BASEBOARD_FAB2(SCH_1):M_J_BA<1>
  W52  M_J_BA<0>      DDR2_BA<0>  @BASEBOARD_FAB2_LIB.BASEBOARD_FAB2(SCH_1):M_J_BA<0>
  AD61  M_J_ALERT_N    DDR2_ALERT_N  @BASEBOARD_FAB2_LIB.BASEBOARD_FAB2(SCH_1):M_J_ALERT_N
  AB61  M_J_ACT_N      DDR2_ACT_N  @BASEBOARD_FAB2_LIB.BASEBOARD_FAB2(SCH_1):M_J_ACT_N

SKX_EXT_B_BGA1  I172  U2D1   [SKX_EXT_B_BGA1-IC,TBD]
  K53  M_H_PAR        DDR1_PAR  @BASEBOARD_FAB2_LIB.BASEBOARD_FAB2(SCH_1):M_H_PAR
  T47  M_H_ODT<3>     DDR1_ODT<3>  @BASEBOARD_FAB2_LIB.BASEBOARD_FAB2(SCH_1):M_H_ODT<3>
  M49  M_H_ODT<2>     DDR1_ODT<2>  @BASEBOARD_FAB2_LIB.BASEBOARD_FAB2(SCH_1):M_H_ODT<2>
  R48  M_H_ODT<1>     DDR1_ODT<1>  @BASEBOARD_FAB2_LIB.BASEBOARD_FAB2(SCH_1):M_H_ODT<1>
  N50  M_H_ODT<0>     DDR1_ODT<0>  @BASEBOARD_FAB2_LIB.BASEBOARD_FAB2(SCH_1):M_H_ODT<0>
  K59  M_H_MA<9>      DDR1_MA<9>  @BASEBOARD_FAB2_LIB.BASEBOARD_FAB2(SCH_1):M_H_MA<9>
  W60  M_H_MA<8>      DDR1_MA<8>  @BASEBOARD_FAB2_LIB.BASEBOARD_FAB2(SCH_1):M_H_MA<8>
  V61  M_H_MA<7>      DDR1_MA<7>  @BASEBOARD_FAB2_LIB.BASEBOARD_FAB2(SCH_1):M_H_MA<7>
  T59  M_H_MA<6>      DDR1_MA<6>  @BASEBOARD_FAB2_LIB.BASEBOARD_FAB2(SCH_1):M_H_MA<6>
  R58  M_H_MA<5>      DDR1_MA<5>  @BASEBOARD_FAB2_LIB.BASEBOARD_FAB2(SCH_1):M_H_MA<5>
  M59  M_H_MA<4>      DDR1_MA<4>  @BASEBOARD_FAB2_LIB.BASEBOARD_FAB2(SCH_1):M_H_MA<4>
  N58  M_H_MA<3>      DDR1_MA<3>  @BASEBOARD_FAB2_LIB.BASEBOARD_FAB2(SCH_1):M_H_MA<3>
  K57  M_H_MA<2>      DDR1_MA<2>  @BASEBOARD_FAB2_LIB.BASEBOARD_FAB2(SCH_1):M_H_MA<2>
  J58  M_H_MA<1>      DDR1_MA<1>  @BASEBOARD_FAB2_LIB.BASEBOARD_FAB2(SCH_1):M_H_MA<1>
  N48  M_H_MA<17>     DDR1_MA<17>  @BASEBOARD_FAB2_LIB.BASEBOARD_FAB2(SCH_1):M_H_MA<17>
  R52  M_H_MA<16>     DDR1_MA<16>  @BASEBOARD_FAB2_LIB.BASEBOARD_FAB2(SCH_1):M_H_MA<16>
  N52  M_H_MA<15>     DDR1_MA<15>  @BASEBOARD_FAB2_LIB.BASEBOARD_FAB2(SCH_1):M_H_MA<15>
  T51  M_H_MA<14>     DDR1_MA<14>  @BASEBOARD_FAB2_LIB.BASEBOARD_FAB2(SCH_1):M_H_MA<14>
  M51  M_H_MA<13>     DDR1_MA<13>  @BASEBOARD_FAB2_LIB.BASEBOARD_FAB2(SCH_1):M_H_MA<13>
  T61  M_H_MA<12>     DDR1_MA<12>  @BASEBOARD_FAB2_LIB.BASEBOARD_FAB2(SCH_1):M_H_MA<12>
  R60  M_H_MA<11>     DDR1_MA<11>  @BASEBOARD_FAB2_LIB.BASEBOARD_FAB2(SCH_1):M_H_MA<11>
  M55  M_H_MA<10>     DDR1_MA<10>  @BASEBOARD_FAB2_LIB.BASEBOARD_FAB2(SCH_1):M_H_MA<10>
  J52  M_H_MA<0>      DDR1_MA<0>  @BASEBOARD_FAB2_LIB.BASEBOARD_FAB2(SCH_1):M_H_MA<0>
  M67  M_H_ECC<7>     DDR1_ECC<7>  @BASEBOARD_FAB2_LIB.BASEBOARD_FAB2(SCH_1):M_H_ECC<7>
  H67  M_H_ECC<6>     DDR1_ECC<6>  @BASEBOARD_FAB2_LIB.BASEBOARD_FAB2(SCH_1):M_H_ECC<6>
  M69  M_H_ECC<5>     DDR1_ECC<5>  @BASEBOARD_FAB2_LIB.BASEBOARD_FAB2(SCH_1):M_H_ECC<5>
  L70  M_H_ECC<4>     DDR1_ECC<4>  @BASEBOARD_FAB2_LIB.BASEBOARD_FAB2(SCH_1):M_H_ECC<4>
  L66  M_H_ECC<3>     DDR1_ECC<3>  @BASEBOARD_FAB2_LIB.BASEBOARD_FAB2(SCH_1):M_H_ECC<3>
  J66  M_H_ECC<2>     DDR1_ECC<2>  @BASEBOARD_FAB2_LIB.BASEBOARD_FAB2(SCH_1):M_H_ECC<2>
  H69  M_H_ECC<1>     DDR1_ECC<1>  @BASEBOARD_FAB2_LIB.BASEBOARD_FAB2(SCH_1):M_H_ECC<1>
  J70  M_H_ECC<0>     DDR1_ECC<0>  @BASEBOARD_FAB2_LIB.BASEBOARD_FAB2(SCH_1):M_H_ECC<0>
  AT81  M_H_DQS_DP<9>  DDR1_DQS_DP<9>  @BASEBOARD_FAB2_LIB.BASEBOARD_FAB2(SCH_1):M_H_DQS_DP<9>
  L68  M_H_DQS_DP<8>  DDR1_DQS_DP<8>  @BASEBOARD_FAB2_LIB.BASEBOARD_FAB2(SCH_1):M_H_DQS_DP<8>
  Y27  M_H_DQS_DP<7>  DDR1_DQS_DP<7>  @BASEBOARD_FAB2_LIB.BASEBOARD_FAB2(SCH_1):M_H_DQS_DP<7>
  E28  M_H_DQS_DP<6>  DDR1_DQS_DP<6>  @BASEBOARD_FAB2_LIB.BASEBOARD_FAB2(SCH_1):M_H_DQS_DP<6>
  E34  M_H_DQS_DP<5>  DDR1_DQS_DP<5>  @BASEBOARD_FAB2_LIB.BASEBOARD_FAB2(SCH_1):M_H_DQS_DP<5>
  R42  M_H_DQS_DP<4>  DDR1_DQS_DP<4>  @BASEBOARD_FAB2_LIB.BASEBOARD_FAB2(SCH_1):M_H_DQS_DP<4>
  F73  M_H_DQS_DP<3>  DDR1_DQS_DP<3>  @BASEBOARD_FAB2_LIB.BASEBOARD_FAB2(SCH_1):M_H_DQS_DP<3>
  H79  M_H_DQS_DP<2>  DDR1_DQS_DP<2>  @BASEBOARD_FAB2_LIB.BASEBOARD_FAB2(SCH_1):M_H_DQS_DP<2>
  AE80  M_H_DQS_DP<1>  DDR1_DQS_DP<1>  @BASEBOARD_FAB2_LIB.BASEBOARD_FAB2(SCH_1):M_H_DQS_DP<1>
  J68  M_H_DQS_DP<17>  DDR1_DQS_DP<17>  @BASEBOARD_FAB2_LIB.BASEBOARD_FAB2(SCH_1):M_H_DQS_DP<17>
  V27  M_H_DQS_DP<16>  DDR1_DQS_DP<16>  @BASEBOARD_FAB2_LIB.BASEBOARD_FAB2(SCH_1):M_H_DQS_DP<16>
  C28  M_H_DQS_DP<15>  DDR1_DQS_DP<15>  @BASEBOARD_FAB2_LIB.BASEBOARD_FAB2(SCH_1):M_H_DQS_DP<15>
  C34  M_H_DQS_DP<14>  DDR1_DQS_DP<14>  @BASEBOARD_FAB2_LIB.BASEBOARD_FAB2(SCH_1):M_H_DQS_DP<14>
  L42  M_H_DQS_DP<13>  DDR1_DQS_DP<13>  @BASEBOARD_FAB2_LIB.BASEBOARD_FAB2(SCH_1):M_H_DQS_DP<13>
  D73  M_H_DQS_DP<12>  DDR1_DQS_DP<12>  @BASEBOARD_FAB2_LIB.BASEBOARD_FAB2(SCH_1):M_H_DQS_DP<12>
  F79  M_H_DQS_DP<11>  DDR1_DQS_DP<11>  @BASEBOARD_FAB2_LIB.BASEBOARD_FAB2(SCH_1):M_H_DQS_DP<11>
  AF81  M_H_DQS_DP<10>  DDR1_DQS_DP<10>  @BASEBOARD_FAB2_LIB.BASEBOARD_FAB2(SCH_1):M_H_DQS_DP<10>
  AR80  M_H_DQS_DP<0>  DDR1_DQS_DP<0>  @BASEBOARD_FAB2_LIB.BASEBOARD_FAB2(SCH_1):M_H_DQS_DP<0>
  AU82  M_H_DQS_DN<9>  DDR1_DQS_DN<9>  @BASEBOARD_FAB2_LIB.BASEBOARD_FAB2(SCH_1):M_H_DQS_DN<9>
  N68  M_H_DQS_DN<8>  DDR1_DQS_DN<8>  @BASEBOARD_FAB2_LIB.BASEBOARD_FAB2(SCH_1):M_H_DQS_DN<8>
  AB27  M_H_DQS_DN<7>  DDR1_DQS_DN<7>  @BASEBOARD_FAB2_LIB.BASEBOARD_FAB2(SCH_1):M_H_DQS_DN<7>
  G28  M_H_DQS_DN<6>  DDR1_DQS_DN<6>  @BASEBOARD_FAB2_LIB.BASEBOARD_FAB2(SCH_1):M_H_DQS_DN<6>
  G34  M_H_DQS_DN<5>  DDR1_DQS_DN<5>  @BASEBOARD_FAB2_LIB.BASEBOARD_FAB2(SCH_1):M_H_DQS_DN<5>
  N42  M_H_DQS_DN<4>  DDR1_DQS_DN<4>  @BASEBOARD_FAB2_LIB.BASEBOARD_FAB2(SCH_1):M_H_DQS_DN<4>
  H73  M_H_DQS_DN<3>  DDR1_DQS_DN<3>  @BASEBOARD_FAB2_LIB.BASEBOARD_FAB2(SCH_1):M_H_DQS_DN<3>
  K79  M_H_DQS_DN<2>  DDR1_DQS_DN<2>  @BASEBOARD_FAB2_LIB.BASEBOARD_FAB2(SCH_1):M_H_DQS_DN<2>
  AD79  M_H_DQS_DN<1>  DDR1_DQS_DN<1>  @BASEBOARD_FAB2_LIB.BASEBOARD_FAB2(SCH_1):M_H_DQS_DN<1>
  G68  M_H_DQS_DN<17>  DDR1_DQS_DN<17>  @BASEBOARD_FAB2_LIB.BASEBOARD_FAB2(SCH_1):M_H_DQS_DN<17>
  T27  M_H_DQS_DN<16>  DDR1_DQS_DN<16>  @BASEBOARD_FAB2_LIB.BASEBOARD_FAB2(SCH_1):M_H_DQS_DN<16>
  A28  M_H_DQS_DN<15>  DDR1_DQS_DN<15>  @BASEBOARD_FAB2_LIB.BASEBOARD_FAB2(SCH_1):M_H_DQS_DN<15>
  A34  M_H_DQS_DN<14>  DDR1_DQS_DN<14>  @BASEBOARD_FAB2_LIB.BASEBOARD_FAB2(SCH_1):M_H_DQS_DN<14>
  J42  M_H_DQS_DN<13>  DDR1_DQS_DN<13>  @BASEBOARD_FAB2_LIB.BASEBOARD_FAB2(SCH_1):M_H_DQS_DN<13>
  B73  M_H_DQS_DN<12>  DDR1_DQS_DN<12>  @BASEBOARD_FAB2_LIB.BASEBOARD_FAB2(SCH_1):M_H_DQS_DN<12>
  D79  M_H_DQS_DN<11>  DDR1_DQS_DN<11>  @BASEBOARD_FAB2_LIB.BASEBOARD_FAB2(SCH_1):M_H_DQS_DN<11>
  AG82  M_H_DQS_DN<10>  DDR1_DQS_DN<10>  @BASEBOARD_FAB2_LIB.BASEBOARD_FAB2(SCH_1):M_H_DQS_DN<10>
  AP79  M_H_DQS_DN<0>  DDR1_DQS_DN<0>  @BASEBOARD_FAB2_LIB.BASEBOARD_FAB2(SCH_1):M_H_DQS_DN<0>
  AF79  M_H_DQ<9>      DDR1_DQ<9>  @BASEBOARD_FAB2_LIB.BASEBOARD_FAB2(SCH_1):M_H_DQ<9>
  AH81  M_H_DQ<8>      DDR1_DQ<8>  @BASEBOARD_FAB2_LIB.BASEBOARD_FAB2(SCH_1):M_H_DQ<8>
  AN80  M_H_DQ<7>      DDR1_DQ<7>  @BASEBOARD_FAB2_LIB.BASEBOARD_FAB2(SCH_1):M_H_DQ<7>
  AR82  M_H_DQ<6>      DDR1_DQ<6>  @BASEBOARD_FAB2_LIB.BASEBOARD_FAB2(SCH_1):M_H_DQ<6>
  AA26  M_H_DQ<63>     DDR1_DQ<63>  @BASEBOARD_FAB2_LIB.BASEBOARD_FAB2(SCH_1):M_H_DQ<63>
  U26  M_H_DQ<62>     DDR1_DQ<62>  @BASEBOARD_FAB2_LIB.BASEBOARD_FAB2(SCH_1):M_H_DQ<62>
  Y29  M_H_DQ<61>     DDR1_DQ<61>  @BASEBOARD_FAB2_LIB.BASEBOARD_FAB2(SCH_1):M_H_DQ<61>
  V29  M_H_DQ<60>     DDR1_DQ<60>  @BASEBOARD_FAB2_LIB.BASEBOARD_FAB2(SCH_1):M_H_DQ<60>
  AV79  M_H_DQ<5>      DDR1_DQ<5>  @BASEBOARD_FAB2_LIB.BASEBOARD_FAB2(SCH_1):M_H_DQ<5>
  Y25  M_H_DQ<59>     DDR1_DQ<59>  @BASEBOARD_FAB2_LIB.BASEBOARD_FAB2(SCH_1):M_H_DQ<59>
  V25  M_H_DQ<58>     DDR1_DQ<58>  @BASEBOARD_FAB2_LIB.BASEBOARD_FAB2(SCH_1):M_H_DQ<58>
  AA28  M_H_DQ<57>     DDR1_DQ<57>  @BASEBOARD_FAB2_LIB.BASEBOARD_FAB2(SCH_1):M_H_DQ<57>
  U28  M_H_DQ<56>     DDR1_DQ<56>  @BASEBOARD_FAB2_LIB.BASEBOARD_FAB2(SCH_1):M_H_DQ<56>
  F27  M_H_DQ<55>     DDR1_DQ<55>  @BASEBOARD_FAB2_LIB.BASEBOARD_FAB2(SCH_1):M_H_DQ<55>
  B27  M_H_DQ<54>     DDR1_DQ<54>  @BASEBOARD_FAB2_LIB.BASEBOARD_FAB2(SCH_1):M_H_DQ<54>
  F29  M_H_DQ<53>     DDR1_DQ<53>  @BASEBOARD_FAB2_LIB.BASEBOARD_FAB2(SCH_1):M_H_DQ<53>
  E30  M_H_DQ<52>     DDR1_DQ<52>  @BASEBOARD_FAB2_LIB.BASEBOARD_FAB2(SCH_1):M_H_DQ<52>
  E26  M_H_DQ<51>     DDR1_DQ<51>  @BASEBOARD_FAB2_LIB.BASEBOARD_FAB2(SCH_1):M_H_DQ<51>
  C26  M_H_DQ<50>     DDR1_DQ<50>  @BASEBOARD_FAB2_LIB.BASEBOARD_FAB2(SCH_1):M_H_DQ<50>
  AW80  M_H_DQ<4>      DDR1_DQ<4>  @BASEBOARD_FAB2_LIB.BASEBOARD_FAB2(SCH_1):M_H_DQ<4>
  B29  M_H_DQ<49>     DDR1_DQ<49>  @BASEBOARD_FAB2_LIB.BASEBOARD_FAB2(SCH_1):M_H_DQ<49>
  C30  M_H_DQ<48>     DDR1_DQ<48>  @BASEBOARD_FAB2_LIB.BASEBOARD_FAB2(SCH_1):M_H_DQ<48>
  F33  M_H_DQ<47>     DDR1_DQ<47>  @BASEBOARD_FAB2_LIB.BASEBOARD_FAB2(SCH_1):M_H_DQ<47>
  B33  M_H_DQ<46>     DDR1_DQ<46>  @BASEBOARD_FAB2_LIB.BASEBOARD_FAB2(SCH_1):M_H_DQ<46>
  F35  M_H_DQ<45>     DDR1_DQ<45>  @BASEBOARD_FAB2_LIB.BASEBOARD_FAB2(SCH_1):M_H_DQ<45>
  E36  M_H_DQ<44>     DDR1_DQ<44>  @BASEBOARD_FAB2_LIB.BASEBOARD_FAB2(SCH_1):M_H_DQ<44>
  E32  M_H_DQ<43>     DDR1_DQ<43>  @BASEBOARD_FAB2_LIB.BASEBOARD_FAB2(SCH_1):M_H_DQ<43>
  C32  M_H_DQ<42>     DDR1_DQ<42>  @BASEBOARD_FAB2_LIB.BASEBOARD_FAB2(SCH_1):M_H_DQ<42>
  B35  M_H_DQ<41>     DDR1_DQ<41>  @BASEBOARD_FAB2_LIB.BASEBOARD_FAB2(SCH_1):M_H_DQ<41>
  C36  M_H_DQ<40>     DDR1_DQ<40>  @BASEBOARD_FAB2_LIB.BASEBOARD_FAB2(SCH_1):M_H_DQ<40>
  AM81  M_H_DQ<3>      DDR1_DQ<3>  @BASEBOARD_FAB2_LIB.BASEBOARD_FAB2(SCH_1):M_H_DQ<3>
  P41  M_H_DQ<39>     DDR1_DQ<39>  @BASEBOARD_FAB2_LIB.BASEBOARD_FAB2(SCH_1):M_H_DQ<39>
  K41  M_H_DQ<38>     DDR1_DQ<38>  @BASEBOARD_FAB2_LIB.BASEBOARD_FAB2(SCH_1):M_H_DQ<38>
  T43  M_H_DQ<37>     DDR1_DQ<37>  @BASEBOARD_FAB2_LIB.BASEBOARD_FAB2(SCH_1):M_H_DQ<37>
  P43  M_H_DQ<36>     DDR1_DQ<36>  @BASEBOARD_FAB2_LIB.BASEBOARD_FAB2(SCH_1):M_H_DQ<36>
  N40  M_H_DQ<35>     DDR1_DQ<35>  @BASEBOARD_FAB2_LIB.BASEBOARD_FAB2(SCH_1):M_H_DQ<35>
  L40  M_H_DQ<34>     DDR1_DQ<34>  @BASEBOARD_FAB2_LIB.BASEBOARD_FAB2(SCH_1):M_H_DQ<34>
  H43  M_H_DQ<33>     DDR1_DQ<33>  @BASEBOARD_FAB2_LIB.BASEBOARD_FAB2(SCH_1):M_H_DQ<33>
  K43  M_H_DQ<32>     DDR1_DQ<32>  @BASEBOARD_FAB2_LIB.BASEBOARD_FAB2(SCH_1):M_H_DQ<32>
  G72  M_H_DQ<31>     DDR1_DQ<31>  @BASEBOARD_FAB2_LIB.BASEBOARD_FAB2(SCH_1):M_H_DQ<31>
  C72  M_H_DQ<30>     DDR1_DQ<30>  @BASEBOARD_FAB2_LIB.BASEBOARD_FAB2(SCH_1):M_H_DQ<30>
  AN82  M_H_DQ<2>      DDR1_DQ<2>  @BASEBOARD_FAB2_LIB.BASEBOARD_FAB2(SCH_1):M_H_DQ<2>
  G74  M_H_DQ<29>     DDR1_DQ<29>  @BASEBOARD_FAB2_LIB.BASEBOARD_FAB2(SCH_1):M_H_DQ<29>
  F75  M_H_DQ<28>     DDR1_DQ<28>  @BASEBOARD_FAB2_LIB.BASEBOARD_FAB2(SCH_1):M_H_DQ<28>
  F71  M_H_DQ<27>     DDR1_DQ<27>  @BASEBOARD_FAB2_LIB.BASEBOARD_FAB2(SCH_1):M_H_DQ<27>
  D71  M_H_DQ<26>     DDR1_DQ<26>  @BASEBOARD_FAB2_LIB.BASEBOARD_FAB2(SCH_1):M_H_DQ<26>
  C74  M_H_DQ<25>     DDR1_DQ<25>  @BASEBOARD_FAB2_LIB.BASEBOARD_FAB2(SCH_1):M_H_DQ<25>
  D75  M_H_DQ<24>     DDR1_DQ<24>  @BASEBOARD_FAB2_LIB.BASEBOARD_FAB2(SCH_1):M_H_DQ<24>
  J78  M_H_DQ<23>     DDR1_DQ<23>  @BASEBOARD_FAB2_LIB.BASEBOARD_FAB2(SCH_1):M_H_DQ<23>
  E78  M_H_DQ<22>     DDR1_DQ<22>  @BASEBOARD_FAB2_LIB.BASEBOARD_FAB2(SCH_1):M_H_DQ<22>
  H81  M_H_DQ<21>     DDR1_DQ<21>  @BASEBOARD_FAB2_LIB.BASEBOARD_FAB2(SCH_1):M_H_DQ<21>
  F81  M_H_DQ<20>     DDR1_DQ<20>  @BASEBOARD_FAB2_LIB.BASEBOARD_FAB2(SCH_1):M_H_DQ<20>
  AT79  M_H_DQ<1>      DDR1_DQ<1>  @BASEBOARD_FAB2_LIB.BASEBOARD_FAB2(SCH_1):M_H_DQ<1>
  H77  M_H_DQ<19>     DDR1_DQ<19>  @BASEBOARD_FAB2_LIB.BASEBOARD_FAB2(SCH_1):M_H_DQ<19>
  F77  M_H_DQ<18>     DDR1_DQ<18>  @BASEBOARD_FAB2_LIB.BASEBOARD_FAB2(SCH_1):M_H_DQ<18>
  J80  M_H_DQ<17>     DDR1_DQ<17>  @BASEBOARD_FAB2_LIB.BASEBOARD_FAB2(SCH_1):M_H_DQ<17>
  E80  M_H_DQ<16>     DDR1_DQ<16>  @BASEBOARD_FAB2_LIB.BASEBOARD_FAB2(SCH_1):M_H_DQ<16>
  AC80  M_H_DQ<15>     DDR1_DQ<15>  @BASEBOARD_FAB2_LIB.BASEBOARD_FAB2(SCH_1):M_H_DQ<15>
  AE82  M_H_DQ<14>     DDR1_DQ<14>  @BASEBOARD_FAB2_LIB.BASEBOARD_FAB2(SCH_1):M_H_DQ<14>
  AH79  M_H_DQ<13>     DDR1_DQ<13>  @BASEBOARD_FAB2_LIB.BASEBOARD_FAB2(SCH_1):M_H_DQ<13>
  AJ80  M_H_DQ<12>     DDR1_DQ<12>  @BASEBOARD_FAB2_LIB.BASEBOARD_FAB2(SCH_1):M_H_DQ<12>
  AB81  M_H_DQ<11>     DDR1_DQ<11>  @BASEBOARD_FAB2_LIB.BASEBOARD_FAB2(SCH_1):M_H_DQ<11>
  AC82  M_H_DQ<10>     DDR1_DQ<10>  @BASEBOARD_FAB2_LIB.BASEBOARD_FAB2(SCH_1):M_H_DQ<10>
  AV81  M_H_DQ<0>      DDR1_DQ<0>  @BASEBOARD_FAB2_LIB.BASEBOARD_FAB2(SCH_1):M_H_DQ<0>
  R46  M_H_CS_N<7>    DDR1_CS_N<7>  @BASEBOARD_FAB2_LIB.BASEBOARD_FAB2(SCH_1):M_H_CS_N<7>
  M45  M_H_CS_N<6>    DDR1_CS_N<6>  @BASEBOARD_FAB2_LIB.BASEBOARD_FAB2(SCH_1):M_H_CS_N<6>
  T49  M_H_CS_N<5>    DDR1_CS_N<5>  @BASEBOARD_FAB2_LIB.BASEBOARD_FAB2(SCH_1):M_H_CS_N<5>
  J50  M_H_CS_N<4>    DDR1_CS_N<4>  @BASEBOARD_FAB2_LIB.BASEBOARD_FAB2(SCH_1):M_H_CS_N<4>
  V47  M_H_CS_N<3>    DDR1_CS_N<3>  @BASEBOARD_FAB2_LIB.BASEBOARD_FAB2(SCH_1):M_H_CS_N<3>
  N46  M_H_CS_N<2>    DDR1_CS_N<2>  @BASEBOARD_FAB2_LIB.BASEBOARD_FAB2(SCH_1):M_H_CS_N<2>
  R50  M_H_CS_N<1>    DDR1_CS_N<1>  @BASEBOARD_FAB2_LIB.BASEBOARD_FAB2(SCH_1):M_H_CS_N<1>
  K51  M_H_CS_N<0>    DDR1_CS_N<0>  @BASEBOARD_FAB2_LIB.BASEBOARD_FAB2(SCH_1):M_H_CS_N<0>
  T57  M_H_CLK_DP<3>  DDR1_CLK_DP<3>  @BASEBOARD_FAB2_LIB.BASEBOARD_FAB2(SCH_1):M_H_CLK_DP<3>
  M57  M_H_CLK_DP<2>  DDR1_CLK_DP<2>  @BASEBOARD_FAB2_LIB.BASEBOARD_FAB2(SCH_1):M_H_CLK_DP<2>
  T55  M_H_CLK_DP<1>  DDR1_CLK_DP<1>  @BASEBOARD_FAB2_LIB.BASEBOARD_FAB2(SCH_1):M_H_CLK_DP<1>
  N54  M_H_CLK_DP<0>  DDR1_CLK_DP<0>  @BASEBOARD_FAB2_LIB.BASEBOARD_FAB2(SCH_1):M_H_CLK_DP<0>
  R56  M_H_CLK_DN<3>  DDR1_CLK_DN<3>  @BASEBOARD_FAB2_LIB.BASEBOARD_FAB2(SCH_1):M_H_CLK_DN<3>
  N56  M_H_CLK_DN<2>  DDR1_CLK_DN<2>  @BASEBOARD_FAB2_LIB.BASEBOARD_FAB2(SCH_1):M_H_CLK_DN<2>
  R54  M_H_CLK_DN<1>  DDR1_CLK_DN<1>  @BASEBOARD_FAB2_LIB.BASEBOARD_FAB2(SCH_1):M_H_CLK_DN<1>
  M53  M_H_CLK_DN<0>  DDR1_CLK_DN<0>  @BASEBOARD_FAB2_LIB.BASEBOARD_FAB2(SCH_1):M_H_CLK_DN<0>
  L64  M_H_CKE<3>     DDR1_CKE<3>  @BASEBOARD_FAB2_LIB.BASEBOARD_FAB2(SCH_1):M_H_CKE<3>
  K63  M_H_CKE<2>     DDR1_CKE<2>  @BASEBOARD_FAB2_LIB.BASEBOARD_FAB2(SCH_1):M_H_CKE<2>
  R64  M_H_CKE<1>     DDR1_CKE<1>  @BASEBOARD_FAB2_LIB.BASEBOARD_FAB2(SCH_1):M_H_CKE<1>
  N62  M_H_CKE<0>     DDR1_CKE<0>  @BASEBOARD_FAB2_LIB.BASEBOARD_FAB2(SCH_1):M_H_CKE<0>
  M47  M_H_C<2>       DDR1_CID<2>  @BASEBOARD_FAB2_LIB.BASEBOARD_FAB2(SCH_1):M_H_C<2>
  N60  M_H_BG<1>      DDR1_BG<1>  @BASEBOARD_FAB2_LIB.BASEBOARD_FAB2(SCH_1):M_H_BG<1>
  M61  M_H_BG<0>      DDR1_BG<0>  @BASEBOARD_FAB2_LIB.BASEBOARD_FAB2(SCH_1):M_H_BG<0>
  K55  M_H_BA<1>      DDR1_BA<1>  @BASEBOARD_FAB2_LIB.BASEBOARD_FAB2(SCH_1):M_H_BA<1>
  T53  M_H_BA<0>      DDR1_BA<0>  @BASEBOARD_FAB2_LIB.BASEBOARD_FAB2(SCH_1):M_H_BA<0>
  W62  M_H_ALERT_N    DDR1_ALERT_N  @BASEBOARD_FAB2_LIB.BASEBOARD_FAB2(SCH_1):M_H_ALERT_N
  T63  M_H_ACT_N      DDR1_ACT_N  @BASEBOARD_FAB2_LIB.BASEBOARD_FAB2(SCH_1):M_H_ACT_N

SKX_EXT_B_BGA1  I172  U2D1   [SKX_EXT_B_BGA1-IC,TBD]
  D53  M_G_PAR        DDR0_PAR  @BASEBOARD_FAB2_LIB.BASEBOARD_FAB2(SCH_1):M_G_PAR
  G48  M_G_ODT<3>     DDR0_ODT<3>  @BASEBOARD_FAB2_LIB.BASEBOARD_FAB2(SCH_1):M_G_ODT<3>
  G50  M_G_ODT<2>     DDR0_ODT<2>  @BASEBOARD_FAB2_LIB.BASEBOARD_FAB2(SCH_1):M_G_ODT<2>
  C48  M_G_ODT<1>     DDR0_ODT<1>  @BASEBOARD_FAB2_LIB.BASEBOARD_FAB2(SCH_1):M_G_ODT<1>
  C50  M_G_ODT<0>     DDR0_ODT<0>  @BASEBOARD_FAB2_LIB.BASEBOARD_FAB2(SCH_1):M_G_ODT<0>
  F61  M_G_MA<9>      DDR0_MA<9>  @BASEBOARD_FAB2_LIB.BASEBOARD_FAB2(SCH_1):M_G_MA<9>
  C60  M_G_MA<8>      DDR0_MA<8>  @BASEBOARD_FAB2_LIB.BASEBOARD_FAB2(SCH_1):M_G_MA<8>
  G60  M_G_MA<7>      DDR0_MA<7>  @BASEBOARD_FAB2_LIB.BASEBOARD_FAB2(SCH_1):M_G_MA<7>
  D59  M_G_MA<6>      DDR0_MA<6>  @BASEBOARD_FAB2_LIB.BASEBOARD_FAB2(SCH_1):M_G_MA<6>
  F59  M_G_MA<5>      DDR0_MA<5>  @BASEBOARD_FAB2_LIB.BASEBOARD_FAB2(SCH_1):M_G_MA<5>
  G58  M_G_MA<4>      DDR0_MA<4>  @BASEBOARD_FAB2_LIB.BASEBOARD_FAB2(SCH_1):M_G_MA<4>
  C58  M_G_MA<3>      DDR0_MA<3>  @BASEBOARD_FAB2_LIB.BASEBOARD_FAB2(SCH_1):M_G_MA<3>
  D57  M_G_MA<2>      DDR0_MA<2>  @BASEBOARD_FAB2_LIB.BASEBOARD_FAB2(SCH_1):M_G_MA<2>
  F57  M_G_MA<1>      DDR0_MA<1>  @BASEBOARD_FAB2_LIB.BASEBOARD_FAB2(SCH_1):M_G_MA<1>
  K47  M_G_MA<17>     DDR0_MA<17>  @BASEBOARD_FAB2_LIB.BASEBOARD_FAB2(SCH_1):M_G_MA<17>
  D51  M_G_MA<16>     DDR0_MA<16>  @BASEBOARD_FAB2_LIB.BASEBOARD_FAB2(SCH_1):M_G_MA<16>
  K49  M_G_MA<15>     DDR0_MA<15>  @BASEBOARD_FAB2_LIB.BASEBOARD_FAB2(SCH_1):M_G_MA<15>
  F51  M_G_MA<14>     DDR0_MA<14>  @BASEBOARD_FAB2_LIB.BASEBOARD_FAB2(SCH_1):M_G_MA<14>
  J48  M_G_MA<13>     DDR0_MA<13>  @BASEBOARD_FAB2_LIB.BASEBOARD_FAB2(SCH_1):M_G_MA<13>
  J64  M_G_MA<12>     DDR0_MA<12>  @BASEBOARD_FAB2_LIB.BASEBOARD_FAB2(SCH_1):M_G_MA<12>
  G62  M_G_MA<11>     DDR0_MA<11>  @BASEBOARD_FAB2_LIB.BASEBOARD_FAB2(SCH_1):M_G_MA<11>
  J54  M_G_MA<10>     DDR0_MA<10>  @BASEBOARD_FAB2_LIB.BASEBOARD_FAB2(SCH_1):M_G_MA<10>
  F53  M_G_MA<0>      DDR0_MA<0>  @BASEBOARD_FAB2_LIB.BASEBOARD_FAB2(SCH_1):M_G_MA<0>
  AG66  M_G_ECC<7>     DDR0_ECC<7>  @BASEBOARD_FAB2_LIB.BASEBOARD_FAB2(SCH_1):M_G_ECC<7>
  AC66  M_G_ECC<6>     DDR0_ECC<6>  @BASEBOARD_FAB2_LIB.BASEBOARD_FAB2(SCH_1):M_G_ECC<6>
  AF69  M_G_ECC<5>     DDR0_ECC<5>  @BASEBOARD_FAB2_LIB.BASEBOARD_FAB2(SCH_1):M_G_ECC<5>
  AD69  M_G_ECC<4>     DDR0_ECC<4>  @BASEBOARD_FAB2_LIB.BASEBOARD_FAB2(SCH_1):M_G_ECC<4>
  AF65  M_G_ECC<3>     DDR0_ECC<3>  @BASEBOARD_FAB2_LIB.BASEBOARD_FAB2(SCH_1):M_G_ECC<3>
  AD65  M_G_ECC<2>     DDR0_ECC<2>  @BASEBOARD_FAB2_LIB.BASEBOARD_FAB2(SCH_1):M_G_ECC<2>
  AG68  M_G_ECC<1>     DDR0_ECC<1>  @BASEBOARD_FAB2_LIB.BASEBOARD_FAB2(SCH_1):M_G_ECC<1>
  AC68  M_G_ECC<0>     DDR0_ECC<0>  @BASEBOARD_FAB2_LIB.BASEBOARD_FAB2(SCH_1):M_G_ECC<0>
  AM85  M_G_DQS_DP<9>  DDR0_DQS_DP<9>  @BASEBOARD_FAB2_LIB.BASEBOARD_FAB2(SCH_1):M_G_DQS_DP<9>
  AF67  M_G_DQS_DP<8>  DDR0_DQS_DP<8>  @BASEBOARD_FAB2_LIB.BASEBOARD_FAB2(SCH_1):M_G_DQS_DP<8>
  R24  M_G_DQS_DP<7>  DDR0_DQS_DP<7>  @BASEBOARD_FAB2_LIB.BASEBOARD_FAB2(SCH_1):M_G_DQS_DP<7>
  N30  M_G_DQS_DP<6>  DDR0_DQS_DP<6>  @BASEBOARD_FAB2_LIB.BASEBOARD_FAB2(SCH_1):M_G_DQS_DP<6>
  N36  M_G_DQS_DP<5>  DDR0_DQS_DP<5>  @BASEBOARD_FAB2_LIB.BASEBOARD_FAB2(SCH_1):M_G_DQS_DP<5>
  E40  M_G_DQS_DP<4>  DDR0_DQS_DP<4>  @BASEBOARD_FAB2_LIB.BASEBOARD_FAB2(SCH_1):M_G_DQS_DP<4>
  P75  M_G_DQS_DP<3>  DDR0_DQS_DP<3>  @BASEBOARD_FAB2_LIB.BASEBOARD_FAB2(SCH_1):M_G_DQS_DP<3>
  R80  M_G_DQS_DP<2>  DDR0_DQS_DP<2>  @BASEBOARD_FAB2_LIB.BASEBOARD_FAB2(SCH_1):M_G_DQS_DP<2>
  P85  M_G_DQS_DP<1>  DDR0_DQS_DP<1>  @BASEBOARD_FAB2_LIB.BASEBOARD_FAB2(SCH_1):M_G_DQS_DP<1>
  AD67  M_G_DQS_DP<17>  DDR0_DQS_DP<17>  @BASEBOARD_FAB2_LIB.BASEBOARD_FAB2(SCH_1):M_G_DQS_DP<17>
  L24  M_G_DQS_DP<16>  DDR0_DQS_DP<16>  @BASEBOARD_FAB2_LIB.BASEBOARD_FAB2(SCH_1):M_G_DQS_DP<16>
  L30  M_G_DQS_DP<15>  DDR0_DQS_DP<15>  @BASEBOARD_FAB2_LIB.BASEBOARD_FAB2(SCH_1):M_G_DQS_DP<15>
  L36  M_G_DQS_DP<14>  DDR0_DQS_DP<14>  @BASEBOARD_FAB2_LIB.BASEBOARD_FAB2(SCH_1):M_G_DQS_DP<14>
  C40  M_G_DQS_DP<13>  DDR0_DQS_DP<13>  @BASEBOARD_FAB2_LIB.BASEBOARD_FAB2(SCH_1):M_G_DQS_DP<13>
  M75  M_G_DQS_DP<12>  DDR0_DQS_DP<12>  @BASEBOARD_FAB2_LIB.BASEBOARD_FAB2(SCH_1):M_G_DQS_DP<12>
  T81  M_G_DQS_DP<11>  DDR0_DQS_DP<11>  @BASEBOARD_FAB2_LIB.BASEBOARD_FAB2(SCH_1):M_G_DQS_DP<11>
  V85  M_G_DQS_DP<10>  DDR0_DQS_DP<10>  @BASEBOARD_FAB2_LIB.BASEBOARD_FAB2(SCH_1):M_G_DQS_DP<10>
  AH85  M_G_DQS_DP<0>  DDR0_DQS_DP<0>  @BASEBOARD_FAB2_LIB.BASEBOARD_FAB2(SCH_1):M_G_DQS_DP<0>
  AL84  M_G_DQS_DN<9>  DDR0_DQS_DN<9>  @BASEBOARD_FAB2_LIB.BASEBOARD_FAB2(SCH_1):M_G_DQS_DN<9>
  AH67  M_G_DQS_DN<8>  DDR0_DQS_DN<8>  @BASEBOARD_FAB2_LIB.BASEBOARD_FAB2(SCH_1):M_G_DQS_DN<8>
  N24  M_G_DQS_DN<7>  DDR0_DQS_DN<7>  @BASEBOARD_FAB2_LIB.BASEBOARD_FAB2(SCH_1):M_G_DQS_DN<7>
  R30  M_G_DQS_DN<6>  DDR0_DQS_DN<6>  @BASEBOARD_FAB2_LIB.BASEBOARD_FAB2(SCH_1):M_G_DQS_DN<6>
  R36  M_G_DQS_DN<5>  DDR0_DQS_DN<5>  @BASEBOARD_FAB2_LIB.BASEBOARD_FAB2(SCH_1):M_G_DQS_DN<5>
  G40  M_G_DQS_DN<4>  DDR0_DQS_DN<4>  @BASEBOARD_FAB2_LIB.BASEBOARD_FAB2(SCH_1):M_G_DQS_DN<4>
  T75  M_G_DQS_DN<3>  DDR0_DQS_DN<3>  @BASEBOARD_FAB2_LIB.BASEBOARD_FAB2(SCH_1):M_G_DQS_DN<3>
  P79  M_G_DQS_DN<2>  DDR0_DQS_DN<2>  @BASEBOARD_FAB2_LIB.BASEBOARD_FAB2(SCH_1):M_G_DQS_DN<2>
  R84  M_G_DQS_DN<1>  DDR0_DQS_DN<1>  @BASEBOARD_FAB2_LIB.BASEBOARD_FAB2(SCH_1):M_G_DQS_DN<1>
  AB67  M_G_DQS_DN<17>  DDR0_DQS_DN<17>  @BASEBOARD_FAB2_LIB.BASEBOARD_FAB2(SCH_1):M_G_DQS_DN<17>
  J24  M_G_DQS_DN<16>  DDR0_DQS_DN<16>  @BASEBOARD_FAB2_LIB.BASEBOARD_FAB2(SCH_1):M_G_DQS_DN<16>
  J30  M_G_DQS_DN<15>  DDR0_DQS_DN<15>  @BASEBOARD_FAB2_LIB.BASEBOARD_FAB2(SCH_1):M_G_DQS_DN<15>
  J36  M_G_DQS_DN<14>  DDR0_DQS_DN<14>  @BASEBOARD_FAB2_LIB.BASEBOARD_FAB2(SCH_1):M_G_DQS_DN<14>
  A40  M_G_DQS_DN<13>  DDR0_DQS_DN<13>  @BASEBOARD_FAB2_LIB.BASEBOARD_FAB2(SCH_1):M_G_DQS_DN<13>
  K75  M_G_DQS_DN<12>  DDR0_DQS_DN<12>  @BASEBOARD_FAB2_LIB.BASEBOARD_FAB2(SCH_1):M_G_DQS_DN<12>
  U82  M_G_DQS_DN<11>  DDR0_DQS_DN<11>  @BASEBOARD_FAB2_LIB.BASEBOARD_FAB2(SCH_1):M_G_DQS_DN<11>
  U84  M_G_DQS_DN<10>  DDR0_DQS_DN<10>  @BASEBOARD_FAB2_LIB.BASEBOARD_FAB2(SCH_1):M_G_DQS_DN<10>
  AJ84  M_G_DQS_DN<0>  DDR0_DQS_DN<0>  @BASEBOARD_FAB2_LIB.BASEBOARD_FAB2(SCH_1):M_G_DQS_DN<0>
  W84  M_G_DQ<9>      DDR0_DQ<9>  @BASEBOARD_FAB2_LIB.BASEBOARD_FAB2(SCH_1):M_G_DQ<9>
  W86  M_G_DQ<8>      DDR0_DQ<8>  @BASEBOARD_FAB2_LIB.BASEBOARD_FAB2(SCH_1):M_G_DQ<8>
  AG84  M_G_DQ<7>      DDR0_DQ<7>  @BASEBOARD_FAB2_LIB.BASEBOARD_FAB2(SCH_1):M_G_DQ<7>
  AG86  M_G_DQ<6>      DDR0_DQ<6>  @BASEBOARD_FAB2_LIB.BASEBOARD_FAB2(SCH_1):M_G_DQ<6>
  K23  M_G_DQ<63>     DDR0_DQ<63>  @BASEBOARD_FAB2_LIB.BASEBOARD_FAB2(SCH_1):M_G_DQ<63>
  H23  M_G_DQ<62>     DDR0_DQ<62>  @BASEBOARD_FAB2_LIB.BASEBOARD_FAB2(SCH_1):M_G_DQ<62>
  N26  M_G_DQ<61>     DDR0_DQ<61>  @BASEBOARD_FAB2_LIB.BASEBOARD_FAB2(SCH_1):M_G_DQ<61>
  L26  M_G_DQ<60>     DDR0_DQ<60>  @BASEBOARD_FAB2_LIB.BASEBOARD_FAB2(SCH_1):M_G_DQ<60>
  AR84  M_G_DQ<5>      DDR0_DQ<5>  @BASEBOARD_FAB2_LIB.BASEBOARD_FAB2(SCH_1):M_G_DQ<5>
  T23  M_G_DQ<59>     DDR0_DQ<59>  @BASEBOARD_FAB2_LIB.BASEBOARD_FAB2(SCH_1):M_G_DQ<59>
  P23  M_G_DQ<58>     DDR0_DQ<58>  @BASEBOARD_FAB2_LIB.BASEBOARD_FAB2(SCH_1):M_G_DQ<58>
  P25  M_G_DQ<57>     DDR0_DQ<57>  @BASEBOARD_FAB2_LIB.BASEBOARD_FAB2(SCH_1):M_G_DQ<57>
  K25  M_G_DQ<56>     DDR0_DQ<56>  @BASEBOARD_FAB2_LIB.BASEBOARD_FAB2(SCH_1):M_G_DQ<56>
  P29  M_G_DQ<55>     DDR0_DQ<55>  @BASEBOARD_FAB2_LIB.BASEBOARD_FAB2(SCH_1):M_G_DQ<55>
  K29  M_G_DQ<54>     DDR0_DQ<54>  @BASEBOARD_FAB2_LIB.BASEBOARD_FAB2(SCH_1):M_G_DQ<54>
  N32  M_G_DQ<53>     DDR0_DQ<53>  @BASEBOARD_FAB2_LIB.BASEBOARD_FAB2(SCH_1):M_G_DQ<53>
  L32  M_G_DQ<52>     DDR0_DQ<52>  @BASEBOARD_FAB2_LIB.BASEBOARD_FAB2(SCH_1):M_G_DQ<52>
  N28  M_G_DQ<51>     DDR0_DQ<51>  @BASEBOARD_FAB2_LIB.BASEBOARD_FAB2(SCH_1):M_G_DQ<51>
  L28  M_G_DQ<50>     DDR0_DQ<50>  @BASEBOARD_FAB2_LIB.BASEBOARD_FAB2(SCH_1):M_G_DQ<50>
  AR86  M_G_DQ<4>      DDR0_DQ<4>  @BASEBOARD_FAB2_LIB.BASEBOARD_FAB2(SCH_1):M_G_DQ<4>
  P31  M_G_DQ<49>     DDR0_DQ<49>  @BASEBOARD_FAB2_LIB.BASEBOARD_FAB2(SCH_1):M_G_DQ<49>
  K31  M_G_DQ<48>     DDR0_DQ<48>  @BASEBOARD_FAB2_LIB.BASEBOARD_FAB2(SCH_1):M_G_DQ<48>
  P35  M_G_DQ<47>     DDR0_DQ<47>  @BASEBOARD_FAB2_LIB.BASEBOARD_FAB2(SCH_1):M_G_DQ<47>
  K35  M_G_DQ<46>     DDR0_DQ<46>  @BASEBOARD_FAB2_LIB.BASEBOARD_FAB2(SCH_1):M_G_DQ<46>
  N38  M_G_DQ<45>     DDR0_DQ<45>  @BASEBOARD_FAB2_LIB.BASEBOARD_FAB2(SCH_1):M_G_DQ<45>
  L38  M_G_DQ<44>     DDR0_DQ<44>  @BASEBOARD_FAB2_LIB.BASEBOARD_FAB2(SCH_1):M_G_DQ<44>
  N34  M_G_DQ<43>     DDR0_DQ<43>  @BASEBOARD_FAB2_LIB.BASEBOARD_FAB2(SCH_1):M_G_DQ<43>
  L34  M_G_DQ<42>     DDR0_DQ<42>  @BASEBOARD_FAB2_LIB.BASEBOARD_FAB2(SCH_1):M_G_DQ<42>
  P37  M_G_DQ<41>     DDR0_DQ<41>  @BASEBOARD_FAB2_LIB.BASEBOARD_FAB2(SCH_1):M_G_DQ<41>
  K37  M_G_DQ<40>     DDR0_DQ<40>  @BASEBOARD_FAB2_LIB.BASEBOARD_FAB2(SCH_1):M_G_DQ<40>
  AE84  M_G_DQ<3>      DDR0_DQ<3>  @BASEBOARD_FAB2_LIB.BASEBOARD_FAB2(SCH_1):M_G_DQ<3>
  F39  M_G_DQ<39>     DDR0_DQ<39>  @BASEBOARD_FAB2_LIB.BASEBOARD_FAB2(SCH_1):M_G_DQ<39>
  B39  M_G_DQ<38>     DDR0_DQ<38>  @BASEBOARD_FAB2_LIB.BASEBOARD_FAB2(SCH_1):M_G_DQ<38>
  F41  M_G_DQ<37>     DDR0_DQ<37>  @BASEBOARD_FAB2_LIB.BASEBOARD_FAB2(SCH_1):M_G_DQ<37>
  E42  M_G_DQ<36>     DDR0_DQ<36>  @BASEBOARD_FAB2_LIB.BASEBOARD_FAB2(SCH_1):M_G_DQ<36>
  E38  M_G_DQ<35>     DDR0_DQ<35>  @BASEBOARD_FAB2_LIB.BASEBOARD_FAB2(SCH_1):M_G_DQ<35>
  C38  M_G_DQ<34>     DDR0_DQ<34>  @BASEBOARD_FAB2_LIB.BASEBOARD_FAB2(SCH_1):M_G_DQ<34>
  B41  M_G_DQ<33>     DDR0_DQ<33>  @BASEBOARD_FAB2_LIB.BASEBOARD_FAB2(SCH_1):M_G_DQ<33>
  C42  M_G_DQ<32>     DDR0_DQ<32>  @BASEBOARD_FAB2_LIB.BASEBOARD_FAB2(SCH_1):M_G_DQ<32>
  R74  M_G_DQ<31>     DDR0_DQ<31>  @BASEBOARD_FAB2_LIB.BASEBOARD_FAB2(SCH_1):M_G_DQ<31>
  L74  M_G_DQ<30>     DDR0_DQ<30>  @BASEBOARD_FAB2_LIB.BASEBOARD_FAB2(SCH_1):M_G_DQ<30>
  AE86  M_G_DQ<2>      DDR0_DQ<2>  @BASEBOARD_FAB2_LIB.BASEBOARD_FAB2(SCH_1):M_G_DQ<2>
  P77  M_G_DQ<29>     DDR0_DQ<29>  @BASEBOARD_FAB2_LIB.BASEBOARD_FAB2(SCH_1):M_G_DQ<29>
  M77  M_G_DQ<28>     DDR0_DQ<28>  @BASEBOARD_FAB2_LIB.BASEBOARD_FAB2(SCH_1):M_G_DQ<28>
  P73  M_G_DQ<27>     DDR0_DQ<27>  @BASEBOARD_FAB2_LIB.BASEBOARD_FAB2(SCH_1):M_G_DQ<27>
  M73  M_G_DQ<26>     DDR0_DQ<26>  @BASEBOARD_FAB2_LIB.BASEBOARD_FAB2(SCH_1):M_G_DQ<26>
  R76  M_G_DQ<25>     DDR0_DQ<25>  @BASEBOARD_FAB2_LIB.BASEBOARD_FAB2(SCH_1):M_G_DQ<25>
  L76  M_G_DQ<24>     DDR0_DQ<24>  @BASEBOARD_FAB2_LIB.BASEBOARD_FAB2(SCH_1):M_G_DQ<24>
  N80  M_G_DQ<23>     DDR0_DQ<23>  @BASEBOARD_FAB2_LIB.BASEBOARD_FAB2(SCH_1):M_G_DQ<23>
  R82  M_G_DQ<22>     DDR0_DQ<22>  @BASEBOARD_FAB2_LIB.BASEBOARD_FAB2(SCH_1):M_G_DQ<22>
  V79  M_G_DQ<21>     DDR0_DQ<21>  @BASEBOARD_FAB2_LIB.BASEBOARD_FAB2(SCH_1):M_G_DQ<21>
  W80  M_G_DQ<20>     DDR0_DQ<20>  @BASEBOARD_FAB2_LIB.BASEBOARD_FAB2(SCH_1):M_G_DQ<20>
  AN84  M_G_DQ<1>      DDR0_DQ<1>  @BASEBOARD_FAB2_LIB.BASEBOARD_FAB2(SCH_1):M_G_DQ<1>
  M81  M_G_DQ<19>     DDR0_DQ<19>  @BASEBOARD_FAB2_LIB.BASEBOARD_FAB2(SCH_1):M_G_DQ<19>
  N82  M_G_DQ<18>     DDR0_DQ<18>  @BASEBOARD_FAB2_LIB.BASEBOARD_FAB2(SCH_1):M_G_DQ<18>
  T79  M_G_DQ<17>     DDR0_DQ<17>  @BASEBOARD_FAB2_LIB.BASEBOARD_FAB2(SCH_1):M_G_DQ<17>
  V81  M_G_DQ<16>     DDR0_DQ<16>  @BASEBOARD_FAB2_LIB.BASEBOARD_FAB2(SCH_1):M_G_DQ<16>
  N84  M_G_DQ<15>     DDR0_DQ<15>  @BASEBOARD_FAB2_LIB.BASEBOARD_FAB2(SCH_1):M_G_DQ<15>
  N86  M_G_DQ<14>     DDR0_DQ<14>  @BASEBOARD_FAB2_LIB.BASEBOARD_FAB2(SCH_1):M_G_DQ<14>
  AA84  M_G_DQ<13>     DDR0_DQ<13>  @BASEBOARD_FAB2_LIB.BASEBOARD_FAB2(SCH_1):M_G_DQ<13>
  AA86  M_G_DQ<12>     DDR0_DQ<12>  @BASEBOARD_FAB2_LIB.BASEBOARD_FAB2(SCH_1):M_G_DQ<12>
  L84  M_G_DQ<11>     DDR0_DQ<11>  @BASEBOARD_FAB2_LIB.BASEBOARD_FAB2(SCH_1):M_G_DQ<11>
  L86  M_G_DQ<10>     DDR0_DQ<10>  @BASEBOARD_FAB2_LIB.BASEBOARD_FAB2(SCH_1):M_G_DQ<10>
  AN86  M_G_DQ<0>      DDR0_DQ<0>  @BASEBOARD_FAB2_LIB.BASEBOARD_FAB2(SCH_1):M_G_DQ<0>
  K45  M_G_CS_N<7>    DDR0_CS_N<7>  @BASEBOARD_FAB2_LIB.BASEBOARD_FAB2(SCH_1):M_G_CS_N<7>
  F45  M_G_CS_N<6>    DDR0_CS_N<6>  @BASEBOARD_FAB2_LIB.BASEBOARD_FAB2(SCH_1):M_G_CS_N<6>
  D49  M_G_CS_N<5>    DDR0_CS_N<5>  @BASEBOARD_FAB2_LIB.BASEBOARD_FAB2(SCH_1):M_G_CS_N<5>
  B51  M_G_CS_N<4>    DDR0_CS_N<4>  @BASEBOARD_FAB2_LIB.BASEBOARD_FAB2(SCH_1):M_G_CS_N<4>
  F47  M_G_CS_N<3>    DDR0_CS_N<3>  @BASEBOARD_FAB2_LIB.BASEBOARD_FAB2(SCH_1):M_G_CS_N<3>
  D47  M_G_CS_N<2>    DDR0_CS_N<2>  @BASEBOARD_FAB2_LIB.BASEBOARD_FAB2(SCH_1):M_G_CS_N<2>
  F49  M_G_CS_N<1>    DDR0_CS_N<1>  @BASEBOARD_FAB2_LIB.BASEBOARD_FAB2(SCH_1):M_G_CS_N<1>
  G52  M_G_CS_N<0>    DDR0_CS_N<0>  @BASEBOARD_FAB2_LIB.BASEBOARD_FAB2(SCH_1):M_G_CS_N<0>
  B57  M_G_CLK_DP<3>  DDR0_CLK_DP<3>  @BASEBOARD_FAB2_LIB.BASEBOARD_FAB2(SCH_1):M_G_CLK_DP<3>
  G56  M_G_CLK_DP<2>  DDR0_CLK_DP<2>  @BASEBOARD_FAB2_LIB.BASEBOARD_FAB2(SCH_1):M_G_CLK_DP<2>
  B55  M_G_CLK_DP<1>  DDR0_CLK_DP<1>  @BASEBOARD_FAB2_LIB.BASEBOARD_FAB2(SCH_1):M_G_CLK_DP<1>
  D55  M_G_CLK_DP<0>  DDR0_CLK_DP<0>  @BASEBOARD_FAB2_LIB.BASEBOARD_FAB2(SCH_1):M_G_CLK_DP<0>
  C56  M_G_CLK_DN<3>  DDR0_CLK_DN<3>  @BASEBOARD_FAB2_LIB.BASEBOARD_FAB2(SCH_1):M_G_CLK_DN<3>
  J56  M_G_CLK_DN<2>  DDR0_CLK_DN<2>  @BASEBOARD_FAB2_LIB.BASEBOARD_FAB2(SCH_1):M_G_CLK_DN<2>
  C54  M_G_CLK_DN<1>  DDR0_CLK_DN<1>  @BASEBOARD_FAB2_LIB.BASEBOARD_FAB2(SCH_1):M_G_CLK_DN<1>
  F55  M_G_CLK_DN<0>  DDR0_CLK_DN<0>  @BASEBOARD_FAB2_LIB.BASEBOARD_FAB2(SCH_1):M_G_CLK_DN<0>
  D63  M_G_CKE<3>     DDR0_CKE<3>  @BASEBOARD_FAB2_LIB.BASEBOARD_FAB2(SCH_1):M_G_CKE<3>
  B63  M_G_CKE<2>     DDR0_CKE<2>  @BASEBOARD_FAB2_LIB.BASEBOARD_FAB2(SCH_1):M_G_CKE<2>
  C64  M_G_CKE<1>     DDR0_CKE<1>  @BASEBOARD_FAB2_LIB.BASEBOARD_FAB2(SCH_1):M_G_CKE<1>
  C62  M_G_CKE<0>     DDR0_CKE<0>  @BASEBOARD_FAB2_LIB.BASEBOARD_FAB2(SCH_1):M_G_CKE<0>
  G46  M_G_C<2>       DDR0_CID<2>  @BASEBOARD_FAB2_LIB.BASEBOARD_FAB2(SCH_1):M_G_C<2>
  F63  M_G_BG<1>      DDR0_BG<1>  @BASEBOARD_FAB2_LIB.BASEBOARD_FAB2(SCH_1):M_G_BG<1>
  D61  M_G_BG<0>      DDR0_BG<0>  @BASEBOARD_FAB2_LIB.BASEBOARD_FAB2(SCH_1):M_G_BG<0>
  G54  M_G_BA<1>      DDR0_BA<1>  @BASEBOARD_FAB2_LIB.BASEBOARD_FAB2(SCH_1):M_G_BA<1>
  C52  M_G_BA<0>      DDR0_BA<0>  @BASEBOARD_FAB2_LIB.BASEBOARD_FAB2(SCH_1):M_G_BA<0>
  B61  M_G_ALERT_N    DDR0_ALERT_N  @BASEBOARD_FAB2_LIB.BASEBOARD_FAB2(SCH_1):M_G_ALERT_N
  J60  M_G_ACT_N      DDR0_ACT_N  @BASEBOARD_FAB2_LIB.BASEBOARD_FAB2(SCH_1):M_G_ACT_N

SKX_EXT_B_BGA1  I169  U2D1   [SKX_EXT_B_BGA1-IC,TBD]
  AV21  XDP_PRESENT_N  DEBUG_EN_N  @BASEBOARD_FAB2_LIB.BASEBOARD_FAB2(SCH_1):XDP_PRESENT_N
  AP17  XDP_CPU_PWR_DEBUG_N  PWR_DEBUG_N  @BASEBOARD_FAB2_LIB.BASEBOARD_FAB2(SCH_1):XDP_CPU_PWR_DEBUG_N
  AK21  VSENSE_P1V8MCP_CPU1_SKT_VSEN  RSVD<221>  @BASEBOARD_FAB2_LIB.BASEBOARD_FAB2(SCH_1):VSENSE_P1V8MCP_CPU1_SKT_VSEN
  AL20  VSENSE_P1V8MCP_CPU1_SKT_VRTN  RSVD<215>  @BASEBOARD_FAB2_LIB.BASEBOARD_FAB2(SCH_1):VSENSE_P1V8MCP_CPU1_SKT_VRTN
  AN14  TP_CPU1_RSVD_TEST_5  TEST_5  @BASEBOARD_FAB2_LIB.BASEBOARD_FAB2(SCH_1):TP_CPU1_RSVD_TEST_5
  AN12  TP_CPU1_RSVD_TEST_4  TEST_4  @BASEBOARD_FAB2_LIB.BASEBOARD_FAB2(SCH_1):TP_CPU1_RSVD_TEST_4
  AM13  TP_CPU1_RSVD_TEST_3  TEST_3  @BASEBOARD_FAB2_LIB.BASEBOARD_FAB2(SCH_1):TP_CPU1_RSVD_TEST_3
  AY13  TP_CPU1_RSVD_TEST_11  TEST_11  @BASEBOARD_FAB2_LIB.BASEBOARD_FAB2(SCH_1):TP_CPU1_RSVD_TEST_11
   A4  TP_CPU1_RSVD_304  RSVD<304>  @BASEBOARD_FAB2_LIB.BASEBOARD_FAB2(SCH_1):TP_CPU1_RSVD_304
   A6  TP_CPU1_RSVD_303  RSVD<303>  @BASEBOARD_FAB2_LIB.BASEBOARD_FAB2(SCH_1):TP_CPU1_RSVD_303
  A24  TP_CPU1_RSVD_300  RSVD<300>  @BASEBOARD_FAB2_LIB.BASEBOARD_FAB2(SCH_1):TP_CPU1_RSVD_300
   B3  TP_CPU1_RSVD_299  RSVD<299>  @BASEBOARD_FAB2_LIB.BASEBOARD_FAB2(SCH_1):TP_CPU1_RSVD_299
   B7  TP_CPU1_RSVD_298  RSVD<298>  @BASEBOARD_FAB2_LIB.BASEBOARD_FAB2(SCH_1):TP_CPU1_RSVD_298
  B77  TP_CPU1_RSVD_293  RSVD<293>  @BASEBOARD_FAB2_LIB.BASEBOARD_FAB2(SCH_1):TP_CPU1_RSVD_293
  B81  TP_CPU1_RSVD_292  RSVD<292>  @BASEBOARD_FAB2_LIB.BASEBOARD_FAB2(SCH_1):TP_CPU1_RSVD_292
   C6  TP_CPU1_RSVD_291  RSVD<291>  @BASEBOARD_FAB2_LIB.BASEBOARD_FAB2(SCH_1):TP_CPU1_RSVD_291
  C18  TP_CPU1_RSVD_290  RSVD<290>  @BASEBOARD_FAB2_LIB.BASEBOARD_FAB2(SCH_1):TP_CPU1_RSVD_290
  C24  TP_CPU1_RSVD_289  RSVD<289>  @BASEBOARD_FAB2_LIB.BASEBOARD_FAB2(SCH_1):TP_CPU1_RSVD_289
  C82  TP_CPU1_RSVD_288  RSVD<288>  @BASEBOARD_FAB2_LIB.BASEBOARD_FAB2(SCH_1):TP_CPU1_RSVD_288
   D5  TP_CPU1_RSVD_287  RSVD<287>  @BASEBOARD_FAB2_LIB.BASEBOARD_FAB2(SCH_1):TP_CPU1_RSVD_287
  D17  TP_CPU1_RSVD_286  RSVD<286>  @BASEBOARD_FAB2_LIB.BASEBOARD_FAB2(SCH_1):TP_CPU1_RSVD_286
  D65  TP_CPU1_RSVD_285  RSVD<285>  @BASEBOARD_FAB2_LIB.BASEBOARD_FAB2(SCH_1):TP_CPU1_RSVD_285
  D83  TP_CPU1_RSVD_284  RSVD<284>  @BASEBOARD_FAB2_LIB.BASEBOARD_FAB2(SCH_1):TP_CPU1_RSVD_284
   E2  TP_CPU1_RSVD_283  RSVD<283>  @BASEBOARD_FAB2_LIB.BASEBOARD_FAB2(SCH_1):TP_CPU1_RSVD_283
   E4  TP_CPU1_RSVD_282  RSVD<282>  @BASEBOARD_FAB2_LIB.BASEBOARD_FAB2(SCH_1):TP_CPU1_RSVD_282
  E24  TP_CPU1_RSVD_281  RSVD<281>  @BASEBOARD_FAB2_LIB.BASEBOARD_FAB2(SCH_1):TP_CPU1_RSVD_281
  E84  TP_CPU1_RSVD_280  RSVD<280>  @BASEBOARD_FAB2_LIB.BASEBOARD_FAB2(SCH_1):TP_CPU1_RSVD_280
   F3  TP_CPU1_RSVD_279  RSVD<279>  @BASEBOARD_FAB2_LIB.BASEBOARD_FAB2(SCH_1):TP_CPU1_RSVD_279
  F23  TP_CPU1_RSVD_278  RSVD<278>  @BASEBOARD_FAB2_LIB.BASEBOARD_FAB2(SCH_1):TP_CPU1_RSVD_278
  F65  TP_CPU1_RSVD_277  RSVD<277>  @BASEBOARD_FAB2_LIB.BASEBOARD_FAB2(SCH_1):TP_CPU1_RSVD_277
  F83  TP_CPU1_RSVD_276  RSVD<276>  @BASEBOARD_FAB2_LIB.BASEBOARD_FAB2(SCH_1):TP_CPU1_RSVD_276
   G2  TP_CPU1_RSVD_275  RSVD<275>  @BASEBOARD_FAB2_LIB.BASEBOARD_FAB2(SCH_1):TP_CPU1_RSVD_275
  G64  TP_CPU1_RSVD_274  RSVD<274>  @BASEBOARD_FAB2_LIB.BASEBOARD_FAB2(SCH_1):TP_CPU1_RSVD_274
  G84  TP_CPU1_RSVD_273  RSVD<273>  @BASEBOARD_FAB2_LIB.BASEBOARD_FAB2(SCH_1):TP_CPU1_RSVD_273
   H1  TP_CPU1_RSVD_272  RSVD<272>  @BASEBOARD_FAB2_LIB.BASEBOARD_FAB2(SCH_1):TP_CPU1_RSVD_272
  H83  TP_CPU1_RSVD_271  RSVD<271>  @BASEBOARD_FAB2_LIB.BASEBOARD_FAB2(SCH_1):TP_CPU1_RSVD_271
  H85  TP_CPU1_RSVD_270  RSVD<270>  @BASEBOARD_FAB2_LIB.BASEBOARD_FAB2(SCH_1):TP_CPU1_RSVD_270
  J46  TP_CPU1_RSVD_269  RSVD<269>  @BASEBOARD_FAB2_LIB.BASEBOARD_FAB2(SCH_1):TP_CPU1_RSVD_269
  J62  TP_CPU1_RSVD_268  RSVD<268>  @BASEBOARD_FAB2_LIB.BASEBOARD_FAB2(SCH_1):TP_CPU1_RSVD_268
  K61  TP_CPU1_RSVD_267  RSVD<267>  @BASEBOARD_FAB2_LIB.BASEBOARD_FAB2(SCH_1):TP_CPU1_RSVD_267
  M63  TP_CPU1_RSVD_266  RSVD<266>  @BASEBOARD_FAB2_LIB.BASEBOARD_FAB2(SCH_1):TP_CPU1_RSVD_266
  P65  TP_CPU1_RSVD_265  RSVD<265>  @BASEBOARD_FAB2_LIB.BASEBOARD_FAB2(SCH_1):TP_CPU1_RSVD_265
  R62  TP_CPU1_RSVD_264  RSVD<264>  @BASEBOARD_FAB2_LIB.BASEBOARD_FAB2(SCH_1):TP_CPU1_RSVD_264
  R66  TP_CPU1_RSVD_263  RSVD<263>  @BASEBOARD_FAB2_LIB.BASEBOARD_FAB2(SCH_1):TP_CPU1_RSVD_263
  T67  TP_CPU1_RSVD_262  RSVD<262>  @BASEBOARD_FAB2_LIB.BASEBOARD_FAB2(SCH_1):TP_CPU1_RSVD_262
  U66  TP_CPU1_RSVD_261  RSVD<261>  @BASEBOARD_FAB2_LIB.BASEBOARD_FAB2(SCH_1):TP_CPU1_RSVD_261
  V65  TP_CPU1_RSVD_260  RSVD<260>  @BASEBOARD_FAB2_LIB.BASEBOARD_FAB2(SCH_1):TP_CPU1_RSVD_260
  V67  TP_CPU1_RSVD_259  RSVD<259>  @BASEBOARD_FAB2_LIB.BASEBOARD_FAB2(SCH_1):TP_CPU1_RSVD_259
  W66  TP_CPU1_RSVD_258  RSVD<258>  @BASEBOARD_FAB2_LIB.BASEBOARD_FAB2(SCH_1):TP_CPU1_RSVD_258
  Y65  TP_CPU1_RSVD_256  RSVD<256>  @BASEBOARD_FAB2_LIB.BASEBOARD_FAB2(SCH_1):TP_CPU1_RSVD_256
  AD47  TP_CPU1_RSVD_254  RSVD<254>  @BASEBOARD_FAB2_LIB.BASEBOARD_FAB2(SCH_1):TP_CPU1_RSVD_254
  AD49  TP_CPU1_RSVD_253  RSVD<253>  @BASEBOARD_FAB2_LIB.BASEBOARD_FAB2(SCH_1):TP_CPU1_RSVD_253
  AD51  TP_CPU1_RSVD_252  RSVD<252>  @BASEBOARD_FAB2_LIB.BASEBOARD_FAB2(SCH_1):TP_CPU1_RSVD_252
  AE46  TP_CPU1_RSVD_251  RSVD<251>  @BASEBOARD_FAB2_LIB.BASEBOARD_FAB2(SCH_1):TP_CPU1_RSVD_251
  AE48  TP_CPU1_RSVD_250  RSVD<250>  @BASEBOARD_FAB2_LIB.BASEBOARD_FAB2(SCH_1):TP_CPU1_RSVD_250
  AE50  TP_CPU1_RSVD_249  RSVD<249>  @BASEBOARD_FAB2_LIB.BASEBOARD_FAB2(SCH_1):TP_CPU1_RSVD_249
  AE52  TP_CPU1_RSVD_248  RSVD<248>  @BASEBOARD_FAB2_LIB.BASEBOARD_FAB2(SCH_1):TP_CPU1_RSVD_248
  AE72  TP_CPU1_RSVD_247  RSVD<247>  @BASEBOARD_FAB2_LIB.BASEBOARD_FAB2(SCH_1):TP_CPU1_RSVD_247
  AF19  TP_CPU1_RSVD_246  RSVD<246>  @BASEBOARD_FAB2_LIB.BASEBOARD_FAB2(SCH_1):TP_CPU1_RSVD_246
  AF47  TP_CPU1_RSVD_245  RSVD<245>  @BASEBOARD_FAB2_LIB.BASEBOARD_FAB2(SCH_1):TP_CPU1_RSVD_245
  AF49  TP_CPU1_RSVD_244  RSVD<244>  @BASEBOARD_FAB2_LIB.BASEBOARD_FAB2(SCH_1):TP_CPU1_RSVD_244
  AF51  TP_CPU1_RSVD_243  RSVD<243>  @BASEBOARD_FAB2_LIB.BASEBOARD_FAB2(SCH_1):TP_CPU1_RSVD_243
  AF53  TP_CPU1_RSVD_242  RSVD<242>  @BASEBOARD_FAB2_LIB.BASEBOARD_FAB2(SCH_1):TP_CPU1_RSVD_242
  AF71  TP_CPU1_RSVD_241  RSVD<241>  @BASEBOARD_FAB2_LIB.BASEBOARD_FAB2(SCH_1):TP_CPU1_RSVD_241
  AG20  TP_CPU1_RSVD_240  RSVD<240>  @BASEBOARD_FAB2_LIB.BASEBOARD_FAB2(SCH_1):TP_CPU1_RSVD_240
  AG48  TP_CPU1_RSVD_239  RSVD<239>  @BASEBOARD_FAB2_LIB.BASEBOARD_FAB2(SCH_1):TP_CPU1_RSVD_239
  AG50  TP_CPU1_RSVD_238  RSVD<238>  @BASEBOARD_FAB2_LIB.BASEBOARD_FAB2(SCH_1):TP_CPU1_RSVD_238
  AG52  TP_CPU1_RSVD_237  RSVD<237>  @BASEBOARD_FAB2_LIB.BASEBOARD_FAB2(SCH_1):TP_CPU1_RSVD_237
  AG54  TP_CPU1_RSVD_236  RSVD<236>  @BASEBOARD_FAB2_LIB.BASEBOARD_FAB2(SCH_1):TP_CPU1_RSVD_236
  AG56  TP_CPU1_RSVD_235  RSVD<235>  @BASEBOARD_FAB2_LIB.BASEBOARD_FAB2(SCH_1):TP_CPU1_RSVD_235
  AG72  TP_CPU1_RSVD_234  RSVD<234>  @BASEBOARD_FAB2_LIB.BASEBOARD_FAB2(SCH_1):TP_CPU1_RSVD_234
  AH15  TP_CPU1_RSVD_233  RSVD<233>  @BASEBOARD_FAB2_LIB.BASEBOARD_FAB2(SCH_1):TP_CPU1_RSVD_233
  AH19  TP_CPU1_RSVD_232  RSVD<232>  @BASEBOARD_FAB2_LIB.BASEBOARD_FAB2(SCH_1):TP_CPU1_RSVD_232
  AH55  TP_CPU1_RSVD_231  RSVD<231>  @BASEBOARD_FAB2_LIB.BASEBOARD_FAB2(SCH_1):TP_CPU1_RSVD_231
  AH57  TP_CPU1_RSVD_230  RSVD<230>  @BASEBOARD_FAB2_LIB.BASEBOARD_FAB2(SCH_1):TP_CPU1_RSVD_230
  AH71  TP_CPU1_RSVD_229  RSVD<229>  @BASEBOARD_FAB2_LIB.BASEBOARD_FAB2(SCH_1):TP_CPU1_RSVD_229
  AH73  TP_CPU1_RSVD_228  RSVD<228>  @BASEBOARD_FAB2_LIB.BASEBOARD_FAB2(SCH_1):TP_CPU1_RSVD_228
  AJ20  TP_CPU1_RSVD_227  RSVD<227>  @BASEBOARD_FAB2_LIB.BASEBOARD_FAB2(SCH_1):TP_CPU1_RSVD_227
  AJ56  TP_CPU1_RSVD_226  RSVD<226>  @BASEBOARD_FAB2_LIB.BASEBOARD_FAB2(SCH_1):TP_CPU1_RSVD_226
  AJ58  TP_CPU1_RSVD_225  RSVD<225>  @BASEBOARD_FAB2_LIB.BASEBOARD_FAB2(SCH_1):TP_CPU1_RSVD_225
  AJ60  TP_CPU1_RSVD_224  RSVD<224>  @BASEBOARD_FAB2_LIB.BASEBOARD_FAB2(SCH_1):TP_CPU1_RSVD_224
  AJ62  TP_CPU1_RSVD_223  RSVD<223>  @BASEBOARD_FAB2_LIB.BASEBOARD_FAB2(SCH_1):TP_CPU1_RSVD_223
  AJ70  TP_CPU1_RSVD_222  RSVD<222>  @BASEBOARD_FAB2_LIB.BASEBOARD_FAB2(SCH_1):TP_CPU1_RSVD_222
  AK57  TP_CPU1_RSVD_219  RSVD<219>  @BASEBOARD_FAB2_LIB.BASEBOARD_FAB2(SCH_1):TP_CPU1_RSVD_219
  AK59  TP_CPU1_RSVD_218  RSVD<218>  @BASEBOARD_FAB2_LIB.BASEBOARD_FAB2(SCH_1):TP_CPU1_RSVD_218
  AK61  TP_CPU1_RSVD_217  RSVD<217>  @BASEBOARD_FAB2_LIB.BASEBOARD_FAB2(SCH_1):TP_CPU1_RSVD_217
  AK69  TP_CPU1_RSVD_216  RSVD<216>  @BASEBOARD_FAB2_LIB.BASEBOARD_FAB2(SCH_1):TP_CPU1_RSVD_216
  AL22  TP_CPU1_RSVD_214  RSVD<214>  @BASEBOARD_FAB2_LIB.BASEBOARD_FAB2(SCH_1):TP_CPU1_RSVD_214
  AL58  TP_CPU1_RSVD_212  RSVD<212>  @BASEBOARD_FAB2_LIB.BASEBOARD_FAB2(SCH_1):TP_CPU1_RSVD_212
  AL60  TP_CPU1_RSVD_211  RSVD<211>  @BASEBOARD_FAB2_LIB.BASEBOARD_FAB2(SCH_1):TP_CPU1_RSVD_211
  AL62  TP_CPU1_RSVD_210  RSVD<210>  @BASEBOARD_FAB2_LIB.BASEBOARD_FAB2(SCH_1):TP_CPU1_RSVD_210
  AM23  TP_CPU1_RSVD_208  RSVD<208>  @BASEBOARD_FAB2_LIB.BASEBOARD_FAB2(SCH_1):TP_CPU1_RSVD_208
  AM59  TP_CPU1_RSVD_205  RSVD<205>  @BASEBOARD_FAB2_LIB.BASEBOARD_FAB2(SCH_1):TP_CPU1_RSVD_205
  AM61  TP_CPU1_RSVD_204  RSVD<204>  @BASEBOARD_FAB2_LIB.BASEBOARD_FAB2(SCH_1):TP_CPU1_RSVD_204
  AN60  TP_CPU1_RSVD_199  RSVD<199>  @BASEBOARD_FAB2_LIB.BASEBOARD_FAB2(SCH_1):TP_CPU1_RSVD_199
  AN62  TP_CPU1_RSVD_198  RSVD<198>  @BASEBOARD_FAB2_LIB.BASEBOARD_FAB2(SCH_1):TP_CPU1_RSVD_198
  AP61  TP_CPU1_RSVD_194  RSVD<194>  @BASEBOARD_FAB2_LIB.BASEBOARD_FAB2(SCH_1):TP_CPU1_RSVD_194
  AM21  PVCCMCP_CPU1   RSVD<209>  @BASEBOARD_FAB2_LIB.BASEBOARD_FAB2(SCH_1):PVCCMCP_CPU1
  AM25  PVCCMCP_CPU1   RSVD<207>  @BASEBOARD_FAB2_LIB.BASEBOARD_FAB2(SCH_1):PVCCMCP_CPU1
  AN18  PVCCMCP_CPU1   RSVD<203>  @BASEBOARD_FAB2_LIB.BASEBOARD_FAB2(SCH_1):PVCCMCP_CPU1
  AN22  PVCCMCP_CPU1   RSVD<202>  @BASEBOARD_FAB2_LIB.BASEBOARD_FAB2(SCH_1):PVCCMCP_CPU1
  AN24  PVCCMCP_CPU1   RSVD<201>  @BASEBOARD_FAB2_LIB.BASEBOARD_FAB2(SCH_1):PVCCMCP_CPU1
  AN26  PVCCMCP_CPU1   RSVD<200>  @BASEBOARD_FAB2_LIB.BASEBOARD_FAB2(SCH_1):PVCCMCP_CPU1
  AP23  PVCCMCP_CPU1   RSVD<197>  @BASEBOARD_FAB2_LIB.BASEBOARD_FAB2(SCH_1):PVCCMCP_CPU1
  AP25  PVCCMCP_CPU1   RSVD<196>  @BASEBOARD_FAB2_LIB.BASEBOARD_FAB2(SCH_1):PVCCMCP_CPU1
  AG46  PD_CPU1_RSVD_TEST_2  TEST_2  @BASEBOARD_FAB2_LIB.BASEBOARD_FAB2(SCH_1):PD_CPU1_RSVD_TEST_2
  AF45  PD_CPU1_RSVD_TEST_1  TEST_1  @BASEBOARD_FAB2_LIB.BASEBOARD_FAB2(SCH_1):PD_CPU1_RSVD_TEST_1
  AW12  PD_CPU1_DMIMODE_OVERRIDE  DMIMODE_OVERRIDE  @BASEBOARD_FAB2_LIB.BASEBOARD_FAB2(SCH_1):PD_CPU1_DMIMODE_OVERRIDE
  A14  P1V8_MCP_CPU1  RSVD<302>  @BASEBOARD_FAB2_LIB.BASEBOARD_FAB2(SCH_1):P1V8_MCP_CPU1
  A16  P1V8_MCP_CPU1  RSVD<301>  @BASEBOARD_FAB2_LIB.BASEBOARD_FAB2(SCH_1):P1V8_MCP_CPU1
  B13  P1V8_MCP_CPU1  RSVD<296>  @BASEBOARD_FAB2_LIB.BASEBOARD_FAB2(SCH_1):P1V8_MCP_CPU1
  B15  P1V8_MCP_CPU1  RSVD<295>  @BASEBOARD_FAB2_LIB.BASEBOARD_FAB2(SCH_1):P1V8_MCP_CPU1
  B17  P1V8_MCP_CPU1  RSVD<294>  @BASEBOARD_FAB2_LIB.BASEBOARD_FAB2(SCH_1):P1V8_MCP_CPU1
  AU14  H_CPU1_FIVR_FAULT_G  FIVR_FAULT  @BASEBOARD_FAB2_LIB.BASEBOARD_FAB2(SCH_1):H_CPU1_FIVR_FAULT_G
  Y23  FM_CPU1_RC_ERROR_N  RSVD<257>  @BASEBOARD_FAB2_LIB.BASEBOARD_FAB2(SCH_1):FM_CPU1_RC_ERROR_N
  AK27  CLK_322M_OSC_CPU1_RC_DP  RSVD<220>  @BASEBOARD_FAB2_LIB.BASEBOARD_FAB2(SCH_1):CLK_322M_OSC_CPU1_RC_DP
  AL26  CLK_322M_OSC_CPU1_RC_DN  RSVD<213>  @BASEBOARD_FAB2_LIB.BASEBOARD_FAB2(SCH_1):CLK_322M_OSC_CPU1_RC_DN
  AM27  CLK_100M_CPU1_RC_REFCLK0_DP  RSVD<206>  @BASEBOARD_FAB2_LIB.BASEBOARD_FAB2(SCH_1):CLK_100M_CPU1_RC_REFCLK0_DP
  AP27  CLK_100M_CPU1_RC_REFCLK0_DN  RSVD<195>  @BASEBOARD_FAB2_LIB.BASEBOARD_FAB2(SCH_1):CLK_100M_CPU1_RC_REFCLK0_DN

SKX_EXT_B_BGA1  I172  U2D1   [SKX_EXT_B_BGA1-IC,TBD]
  Y13  XDP_CPU_TRST_N  TRST_N  @BASEBOARD_FAB2_LIB.BASEBOARD_FAB2(SCH_1):XDP_CPU_TRST_N
  W14  XDP_CPU_TMS      TMS  @BASEBOARD_FAB2_LIB.BASEBOARD_FAB2(SCH_1):XDP_CPU_TMS
  AA14  XDP_CPU_TCK0     TCK  @BASEBOARD_FAB2_LIB.BASEBOARD_FAB2(SCH_1):XDP_CPU_TCK0
  AR12  XDP_CPU_PREQ_N  PREQ_N  @BASEBOARD_FAB2_LIB.BASEBOARD_FAB2(SCH_1):XDP_CPU_PREQ_N
  AG16  XDP_CPU_PRDY_N  PRDY_N  @BASEBOARD_FAB2_LIB.BASEBOARD_FAB2(SCH_1):XDP_CPU_PRDY_N
  AC12  XDP_CPU_OBSFN_B1_MBP7_N  BPM_N<7>  @BASEBOARD_FAB2_LIB.BASEBOARD_FAB2(SCH_1):XDP_CPU_OBSFN_B1_MBP7_N
  AE12  XDP_CPU_OBSFN_B0_MBP6_N  BPM_N<6>  @BASEBOARD_FAB2_LIB.BASEBOARD_FAB2(SCH_1):XDP_CPU_OBSFN_B0_MBP6_N
  AH11  XDP_CPU_MBP1_N  BPM_N<1>  @BASEBOARD_FAB2_LIB.BASEBOARD_FAB2(SCH_1):XDP_CPU_MBP1_N
  AJ10  XDP_CPU_MBP0_N  BPM_N<0>  @BASEBOARD_FAB2_LIB.BASEBOARD_FAB2(SCH_1):XDP_CPU_MBP0_N
  AE14  XDP_CPU1_TDO     TDO  @BASEBOARD_FAB2_LIB.BASEBOARD_FAB2(SCH_1):XDP_CPU1_TDO
  AC14  XDP_CPU1_TDI     TDI  @BASEBOARD_FAB2_LIB.BASEBOARD_FAB2(SCH_1):XDP_CPU1_TDI
  Y11  TP_XDP_CPU1_OBSDATA_B3_MBP5_N  BPM_N<5>  @BASEBOARD_FAB2_LIB.BASEBOARD_FAB2(SCH_1):TP_XDP_CPU1_OBSDATA_B3_MBP5_N
  AA12  TP_XDP_CPU1_OBSDATA_B2_MBP4_N  BPM_N<4>  @BASEBOARD_FAB2_LIB.BASEBOARD_FAB2(SCH_1):TP_XDP_CPU1_OBSDATA_B2_MBP4_N
  AF11  TP_XDP_CPU1_OBSDATA_B1_MBP3_N  BPM_N<3>  @BASEBOARD_FAB2_LIB.BASEBOARD_FAB2(SCH_1):TP_XDP_CPU1_OBSDATA_B1_MBP3_N
  AG10  TP_XDP_CPU1_OBSDATA_B0_MBP2_N  BPM_N<2>  @BASEBOARD_FAB2_LIB.BASEBOARD_FAB2(SCH_1):TP_XDP_CPU1_OBSDATA_B0_MBP2_N
  AU20  TP_CPU1_SOCKET_ID_2  SOCKET_ID<2>  @BASEBOARD_FAB2_LIB.BASEBOARD_FAB2(SCH_1):TP_CPU1_SOCKET_ID_2
  AB17  TP_CPU1_PROC_DIS_G_N  PROCDIS_N  @BASEBOARD_FAB2_LIB.BASEBOARD_FAB2(SCH_1):TP_CPU1_PROC_DIS_G_N
  AP11  TP_CPU1_NMI      NMI  @BASEBOARD_FAB2_LIB.BASEBOARD_FAB2(SCH_1):TP_CPU1_NMI
  DJ44  SVID_DIO1_CPU1  SVIDDATA<1>  @BASEBOARD_FAB2_LIB.BASEBOARD_FAB2(SCH_1):SVID_DIO1_CPU1
  DB45  SVID_DIO0_CPU1  SVIDDATA<0>  @BASEBOARD_FAB2_LIB.BASEBOARD_FAB2(SCH_1):SVID_DIO0_CPU1
  DG44  SVID_CLK1_CPU1  SVIDCLK<1>  @BASEBOARD_FAB2_LIB.BASEBOARD_FAB2(SCH_1):SVID_CLK1_CPU1
  DC44  SVID_CLK0_CPU1  SVIDCLK<0>  @BASEBOARD_FAB2_LIB.BASEBOARD_FAB2(SCH_1):SVID_CLK0_CPU1
  DL44  SVID_ALERT1_CPU1_N  SVIDALERT_N<1>  @BASEBOARD_FAB2_LIB.BASEBOARD_FAB2(SCH_1):SVID_ALERT1_CPU1_N
  DE44  SVID_ALERT0_CPU1_N  SVIDALERT_N<0>  @BASEBOARD_FAB2_LIB.BASEBOARD_FAB2(SCH_1):SVID_ALERT0_CPU1_N
  CW58  SMB_PIROM_CPU1_SDA  SMBDAT  @BASEBOARD_FAB2_LIB.BASEBOARD_FAB2(SCH_1):SMB_PIROM_CPU1_SDA
  CT59  SMB_PIROM_CPU1_SCL  SMBCLK  @BASEBOARD_FAB2_LIB.BASEBOARD_FAB2(SCH_1):SMB_PIROM_CPU1_SCL
  AD17  SMB_DDR_KLM_SDA_G_R  DDR345_SPDSDA  @BASEBOARD_FAB2_LIB.BASEBOARD_FAB2(SCH_1):SMB_DDR_KLM_SDA_G_R
  AE18  SMB_DDR_KLM_SCL_G_R  DDR345_SPDSCL  @BASEBOARD_FAB2_LIB.BASEBOARD_FAB2(SCH_1):SMB_DDR_KLM_SCL_G_R
  AF17  SMB_DDR_GHJ_SDA_G_R  DDR012_SPDSDA  @BASEBOARD_FAB2_LIB.BASEBOARD_FAB2(SCH_1):SMB_DDR_GHJ_SDA_G_R
  AJ18  SMB_DDR_GHJ_SCL_G_R  DDR012_SPDSCL  @BASEBOARD_FAB2_LIB.BASEBOARD_FAB2(SCH_1):SMB_DDR_GHJ_SCL_G_R
  AL18  SMB_CPU1_PE_HP_GTL_SDA  PE_HP_SDA  @BASEBOARD_FAB2_LIB.BASEBOARD_FAB2(SCH_1):SMB_CPU1_PE_HP_GTL_SDA
  AM19  SMB_CPU1_PE_HP_GTL_SCL  PE_HP_SCL  @BASEBOARD_FAB2_LIB.BASEBOARD_FAB2(SCH_1):SMB_CPU1_PE_HP_GTL_SCL
  AP21  RST_CPU1_G_N   RESET_N  @BASEBOARD_FAB2_LIB.BASEBOARD_FAB2(SCH_1):RST_CPU1_G_N
  BC24  PWRGD_CPU1_G   PWRGOOD  @BASEBOARD_FAB2_LIB.BASEBOARD_FAB2(SCH_1):PWRGD_CPU1_G
  CR28  PWRGD_CPU1_DRAMPWROK_KLM_G  DDR345_DRAM_PWR_OK  @BASEBOARD_FAB2_LIB.BASEBOARD_FAB2(SCH_1):PWRGD_CPU1_DRAMPWROK_KLM_G
  AN30  PWRGD_CPU1_DRAMPWROK_GHJ_G  DDR012_DRAM_PWR_OK  @BASEBOARD_FAB2_LIB.BASEBOARD_FAB2(SCH_1):PWRGD_CPU1_DRAMPWROK_GHJ_G
  CU58  PU_PIROM_CPU1_ADDR0  PIROM_ADDR<0>  @BASEBOARD_FAB2_LIB.BASEBOARD_FAB2(SCH_1):PU_PIROM_CPU1_ADDR0
  AW18  PU_CPU1_TXT_AGENT  TXT_AGENT  @BASEBOARD_FAB2_LIB.BASEBOARD_FAB2(SCH_1):PU_CPU1_TXT_AGENT
  AM11  PU_CPU1_TSC_SYNC  TSC_SYNC  @BASEBOARD_FAB2_LIB.BASEBOARD_FAB2(SCH_1):PU_CPU1_TSC_SYNC
  AU16  PU_CPU1_SOCKET_ID_1  SOCKET_ID<1>  @BASEBOARD_FAB2_LIB.BASEBOARD_FAB2(SCH_1):PU_CPU1_SOCKET_ID_1
  AU22  PU_CPU1_SOCKET_ID_0  SOCKET_ID<0>  @BASEBOARD_FAB2_LIB.BASEBOARD_FAB2(SCH_1):PU_CPU1_SOCKET_ID_0
  AR18  PU_CPU1_SAFE_MODE_BOOT  SAFE_MODE_BOOT  @BASEBOARD_FAB2_LIB.BASEBOARD_FAB2(SCH_1):PU_CPU1_SAFE_MODE_BOOT
  AE20  PU_CPU1_LEGACY_SKT  LEGACY_SKT  @BASEBOARD_FAB2_LIB.BASEBOARD_FAB2(SCH_1):PU_CPU1_LEGACY_SKT
  AV17  PU_CPU1_FRMAGENT  FRMAGENT  @BASEBOARD_FAB2_LIB.BASEBOARD_FAB2(SCH_1):PU_CPU1_FRMAGENT
  AJ14  PU_CPU1_EAR_N  EAR_N  @BASEBOARD_FAB2_LIB.BASEBOARD_FAB2(SCH_1):PU_CPU1_EAR_N
  AU12  PECI_CPU_G      PECI  @BASEBOARD_FAB2_LIB.BASEBOARD_FAB2(SCH_1):PECI_CPU_G
  CW56  PD_PIROM_CPU1_ADDR2  PIROM_ADDR<2>  @BASEBOARD_FAB2_LIB.BASEBOARD_FAB2(SCH_1):PD_PIROM_CPU1_ADDR2
  CV57  PD_PIROM_CPU1_ADDR1  PIROM_ADDR<1>  @BASEBOARD_FAB2_LIB.BASEBOARD_FAB2(SCH_1):PD_PIROM_CPU1_ADDR1
  AV15  PD_CPU1_TXT_PLTEN  TXT_PLTEN  @BASEBOARD_FAB2_LIB.BASEBOARD_FAB2(SCH_1):PD_CPU1_TXT_PLTEN
  DC50  PD_CPU1_TEST14  TEST_14  @BASEBOARD_FAB2_LIB.BASEBOARD_FAB2(SCH_1):PD_CPU1_TEST14
  DB51  PD_CPU1_TEST13  TEST_13  @BASEBOARD_FAB2_LIB.BASEBOARD_FAB2(SCH_1):PD_CPU1_TEST13
  AY19  PD_CPU1_TEST12  TEST_12  @BASEBOARD_FAB2_LIB.BASEBOARD_FAB2(SCH_1):PD_CPU1_TEST12
  AW14  PD_CPU1_KSFC_DIS  TEST_15  @BASEBOARD_FAB2_LIB.BASEBOARD_FAB2(SCH_1):PD_CPU1_KSFC_DIS
  BA20  PD_CPU1_BIST_ENABLE  BIST_ENABLE  @BASEBOARD_FAB2_LIB.BASEBOARD_FAB2(SCH_1):PD_CPU1_BIST_ENABLE
  CV61  M_M_CPU_VREF   DDR5_CAVREF  @BASEBOARD_FAB2_LIB.BASEBOARD_FAB2(SCH_1):M_M_CPU_VREF
  CT61  M_L_CPU_VREF   DDR4_CAVREF  @BASEBOARD_FAB2_LIB.BASEBOARD_FAB2(SCH_1):M_L_CPU_VREF
  CP61  M_K_CPU_VREF   DDR3_CAVREF  @BASEBOARD_FAB2_LIB.BASEBOARD_FAB2(SCH_1):M_K_CPU_VREF
  DV63  M_KLM_RST_N    DDR345_RESET_N  @BASEBOARD_FAB2_LIB.BASEBOARD_FAB2(SCH_1):M_KLM_RST_N
  AH63  M_J_CPU_VREF   DDR2_CAVREF  @BASEBOARD_FAB2_LIB.BASEBOARD_FAB2(SCH_1):M_J_CPU_VREF
  AK63  M_H_CPU_VREF   DDR1_CAVREF  @BASEBOARD_FAB2_LIB.BASEBOARD_FAB2(SCH_1):M_H_CPU_VREF
  AJ64  M_G_CPU_VREF   DDR0_CAVREF  @BASEBOARD_FAB2_LIB.BASEBOARD_FAB2(SCH_1):M_G_CPU_VREF
  U64  M_GHJ_RST_N    DDR012_RESET_N  @BASEBOARD_FAB2_LIB.BASEBOARD_FAB2(SCH_1):M_GHJ_RST_N
  AR14  H_PM_SYNC_GTL_R2  PMSYNC  @BASEBOARD_FAB2_LIB.BASEBOARD_FAB2(SCH_1):H_PM_SYNC_GTL_R2
  AT19  H_PMSYNC_CLK_24M_CPU1  PMSYNC_CLK  @BASEBOARD_FAB2_LIB.BASEBOARD_FAB2(SCH_1):H_PMSYNC_CLK_24M_CPU1
  AB15  H_CPU1_THERMTRIP_G_N  THERMTRIP_N  @BASEBOARD_FAB2_LIB.BASEBOARD_FAB2(SCH_1):H_CPU1_THERMTRIP_G_N
  AC16  H_CPU1_PROCHOT_G_N  PROCHOT_N  @BASEBOARD_FAB2_LIB.BASEBOARD_FAB2(SCH_1):H_CPU1_PROCHOT_G_N
  AN20  H_CPU1_MSMI_G_N  MSMI_N  @BASEBOARD_FAB2_LIB.BASEBOARD_FAB2(SCH_1):H_CPU1_MSMI_G_N
  AF13  H_CPU1_MEMKLM_MEMHOT_G_N  MEM_HOT_C345_N  @BASEBOARD_FAB2_LIB.BASEBOARD_FAB2(SCH_1):H_CPU1_MEMKLM_MEMHOT_G_N
  AH13  H_CPU1_MEMGHJ_MEMHOT_G_N  MEM_HOT_C012_N  @BASEBOARD_FAB2_LIB.BASEBOARD_FAB2(SCH_1):H_CPU1_MEMGHJ_MEMHOT_G_N
  AF15  H_CPU1_FAST_WAKE_N  PM_FAST_WAKE_N  @BASEBOARD_FAB2_LIB.BASEBOARD_FAB2(SCH_1):H_CPU1_FAST_WAKE_N
  AL12  H_CPU1_ERR2_G_N  ERROR_N<2>  @BASEBOARD_FAB2_LIB.BASEBOARD_FAB2(SCH_1):H_CPU1_ERR2_G_N
  AK11  H_CPU1_ERR1_G_N  ERROR_N<1>  @BASEBOARD_FAB2_LIB.BASEBOARD_FAB2(SCH_1):H_CPU1_ERR1_G_N
  AJ12  H_CPU1_ERR0_G_N  ERROR_N<0>  @BASEBOARD_FAB2_LIB.BASEBOARD_FAB2(SCH_1):H_CPU1_ERR0_G_N
  AL14  H_CPU1_CATERR_G_N  CATERR_N  @BASEBOARD_FAB2_LIB.BASEBOARD_FAB2(SCH_1):H_CPU1_CATERR_G_N
  BD23  H_CPU1_BMCINIT  BMCINIT  @BASEBOARD_FAB2_LIB.BASEBOARD_FAB2(SCH_1):H_CPU1_BMCINIT
  CV59  FM_CPU1_SM_WP  SM_WP  @BASEBOARD_FAB2_LIB.BASEBOARD_FAB2(SCH_1):FM_CPU1_SM_WP
  AB13  FM_CPU1_SKTOCC_LVT3_N  SKTOCC_N  @BASEBOARD_FAB2_LIB.BASEBOARD_FAB2(SCH_1):FM_CPU1_SKTOCC_LVT3_N
  DB71  FM_CPU1_PROC_ID1  PROC_ID<1>  @BASEBOARD_FAB2_LIB.BASEBOARD_FAB2(SCH_1):FM_CPU1_PROC_ID1
  CY71  FM_CPU1_PROC_ID0  PROC_ID<0>  @BASEBOARD_FAB2_LIB.BASEBOARD_FAB2(SCH_1):FM_CPU1_PROC_ID0
  DA72  FM_CPU1_PKGID2  PKGID<2>  @BASEBOARD_FAB2_LIB.BASEBOARD_FAB2(SCH_1):FM_CPU1_PKGID2
  CW72  FM_CPU1_PKGID1  PKGID<1>  @BASEBOARD_FAB2_LIB.BASEBOARD_FAB2(SCH_1):FM_CPU1_PKGID1
  DC72  FM_CPU1_PKGID0  PKGID<0>  @BASEBOARD_FAB2_LIB.BASEBOARD_FAB2(SCH_1):FM_CPU1_PKGID0
  CU26  CLK_100M_CPU1_BCLK2_DP  BCLK2_DP  @BASEBOARD_FAB2_LIB.BASEBOARD_FAB2(SCH_1):CLK_100M_CPU1_BCLK2_DP
  CT25  CLK_100M_CPU1_BCLK2_DN  BCLK2_DN  @BASEBOARD_FAB2_LIB.BASEBOARD_FAB2(SCH_1):CLK_100M_CPU1_BCLK2_DN
  CP27  CLK_100M_CPU1_BCLK1_DP  BCLK1_DP  @BASEBOARD_FAB2_LIB.BASEBOARD_FAB2(SCH_1):CLK_100M_CPU1_BCLK1_DP
  CR26  CLK_100M_CPU1_BCLK1_DN  BCLK1_DN  @BASEBOARD_FAB2_LIB.BASEBOARD_FAB2(SCH_1):CLK_100M_CPU1_BCLK1_DN
  AW24  CLK_100M_CPU1_BCLK0_DP  BCLK0_DP  @BASEBOARD_FAB2_LIB.BASEBOARD_FAB2(SCH_1):CLK_100M_CPU1_BCLK0_DP
  AU24  CLK_100M_CPU1_BCLK0_DN  BCLK0_DN  @BASEBOARD_FAB2_LIB.BASEBOARD_FAB2(SCH_1):CLK_100M_CPU1_BCLK0_DN
  CK29  A_CPU1_UPI2_RBIAS  UPI2_RBIAS<1>  @BASEBOARD_FAB2_LIB.BASEBOARD_FAB2(SCH_1):A_CPU1_UPI2_RBIAS
  CL28  A_CPU1_UPI2_RBIAS  UPI2_RBIAS<0>  @BASEBOARD_FAB2_LIB.BASEBOARD_FAB2(SCH_1):A_CPU1_UPI2_RBIAS
  AP29  A_CPU1_UPI01_RBIAS  UPI01_RBIAS<1>  @BASEBOARD_FAB2_LIB.BASEBOARD_FAB2(SCH_1):A_CPU1_UPI01_RBIAS
  AT29  A_CPU1_UPI01_RBIAS  UPI01_RBIAS<0>  @BASEBOARD_FAB2_LIB.BASEBOARD_FAB2(SCH_1):A_CPU1_UPI01_RBIAS
  CR30  A_CPU1_PE3_RBIAS  PE3_RBIAS<1>  @BASEBOARD_FAB2_LIB.BASEBOARD_FAB2(SCH_1):A_CPU1_PE3_RBIAS
  CP29  A_CPU1_PE3_RBIAS  PE3_RBIAS<0>  @BASEBOARD_FAB2_LIB.BASEBOARD_FAB2(SCH_1):A_CPU1_PE3_RBIAS
  CL30  A_CPU1_PE012_RBIAS  PE012_RBIAS<1>  @BASEBOARD_FAB2_LIB.BASEBOARD_FAB2(SCH_1):A_CPU1_PE012_RBIAS
  CN30  A_CPU1_PE012_RBIAS  PE012_RBIAS<0>  @BASEBOARD_FAB2_LIB.BASEBOARD_FAB2(SCH_1):A_CPU1_PE012_RBIAS
  CT31  A_CPU1_MCP01_RBIAS  MCP01_RBIAS<1>  @BASEBOARD_FAB2_LIB.BASEBOARD_FAB2(SCH_1):A_CPU1_MCP01_RBIAS
  CU32  A_CPU1_MCP01_RBIAS  MCP01_RBIAS<0>  @BASEBOARD_FAB2_LIB.BASEBOARD_FAB2(SCH_1):A_CPU1_MCP01_RBIAS
  DD49  A_CPU1_KLM_RCOMP2  DDR345_RCOMP<2>  @BASEBOARD_FAB2_LIB.BASEBOARD_FAB2(SCH_1):A_CPU1_KLM_RCOMP2
  DD47  A_CPU1_KLM_RCOMP1  DDR345_RCOMP<1>  @BASEBOARD_FAB2_LIB.BASEBOARD_FAB2(SCH_1):A_CPU1_KLM_RCOMP1
  DC48  A_CPU1_KLM_RCOMP0  DDR345_RCOMP<0>  @BASEBOARD_FAB2_LIB.BASEBOARD_FAB2(SCH_1):A_CPU1_KLM_RCOMP0
  AC42  A_CPU1_GHJ_RCOMP2  DDR012_RCOMP<2>  @BASEBOARD_FAB2_LIB.BASEBOARD_FAB2(SCH_1):A_CPU1_GHJ_RCOMP2
  AB43  A_CPU1_GHJ_RCOMP1  DDR012_RCOMP<1>  @BASEBOARD_FAB2_LIB.BASEBOARD_FAB2(SCH_1):A_CPU1_GHJ_RCOMP1
  Y43  A_CPU1_GHJ_RCOMP0  DDR012_RCOMP<0>  @BASEBOARD_FAB2_LIB.BASEBOARD_FAB2(SCH_1):A_CPU1_GHJ_RCOMP0

NC7SB3157  I255  U2M1   [NC7SB3157_SMLF-IC,C99406-001]
    5  P3V3_STBY        VCC  @BASEBOARD_FAB2_LIB.BASEBOARD_FAB2(SCH_1):P3V3_STBY
    4  JTAG_MCP_MUX_TDI      A  @BASEBOARD_FAB2_LIB.BASEBOARD_FAB2(SCH_1):JTAG_MCP_MUX_TDI
    3  JTAG_MCP_CPU1_TDI     B0  @BASEBOARD_FAB2_LIB.BASEBOARD_FAB2(SCH_1):JTAG_MCP_CPU1_TDI
    1  JTAG_MCP_CPU0_TDI     B1  @BASEBOARD_FAB2_LIB.BASEBOARD_FAB2(SCH_1):JTAG_MCP_CPU0_TDI
    2  GND              GND  @BASEBOARD_FAB2_LIB.BASEBOARD_FAB2(SCH_1):GND
    6  FM_CPU0_CD_PRES      S  @BASEBOARD_FAB2_LIB.BASEBOARD_FAB2(SCH_1):FM_CPU0_CD_PRES

TTL1G07_A_SOP  I110  U2P1   [TTL1G07_A_SOP-74LVC1G07,IC,C88B]
    2  FM_M2_SSD_PEDET      A  @BASEBOARD_FAB2_LIB.BASEBOARD_FAB2(SCH_1):FM_M2_SSD_PEDET
    4  FM_M2_DET_LVC3      Y  @BASEBOARD_FAB2_LIB.BASEBOARD_FAB2(SCH_1):FM_M2_DET_LVC3

TTL2G14  I356  U2R1   [TTL2G14_SMLF-74LVC2G14,IC,D184B]
    3  FP_NMI_BTN_OUT_N   A<0>  @BASEBOARD_FAB2_LIB.BASEBOARD_FAB2(SCH_1):FP_NMI_BTN_OUT_N
    4  FP_NMI_BTN      Y<0>  @BASEBOARD_FAB2_LIB.BASEBOARD_FAB2(SCH_1):FP_NMI_BTN

TTL2G14  I357  U2R1   [TTL2G14_SMLF-74LVC2G14,IC,D184B]
    6  FP_NMI_BTN_R_N   Y<0>  @BASEBOARD_FAB2_LIB.BASEBOARD_FAB2(SCH_1):FP_NMI_BTN_R_N
    1  FP_NMI_BTN      A<0>  @BASEBOARD_FAB2_LIB.BASEBOARD_FAB2(SCH_1):FP_NMI_BTN

PI3B3257A_TSSOPLF  I75  U2T1   [PI3B3257A_TSSOPLF-IC,E16801-001]
    9  TP_SPI_SWITCH1_9     YC  @BASEBOARD_FAB2_LIB.BASEBOARD_FAB2(SCH_1):TP_SPI_SWITCH1_9
    6  TP_SPI_SWITCH1_6    IB1  @BASEBOARD_FAB2_LIB.BASEBOARD_FAB2(SCH_1):TP_SPI_SWITCH1_6
    3  TP_SPI_SWITCH1_3    IA1  @BASEBOARD_FAB2_LIB.BASEBOARD_FAB2(SCH_1):TP_SPI_SWITCH1_3
   14  TP_SPI_SWITCH1_14    ID0  @BASEBOARD_FAB2_LIB.BASEBOARD_FAB2(SCH_1):TP_SPI_SWITCH1_14
   13  TP_SPI_SWITCH1_13    ID1  @BASEBOARD_FAB2_LIB.BASEBOARD_FAB2(SCH_1):TP_SPI_SWITCH1_13
   12  TP_SPI_SWITCH1_12     YD  @BASEBOARD_FAB2_LIB.BASEBOARD_FAB2(SCH_1):TP_SPI_SWITCH1_12
   11  TP_SPI_SWITCH1_11    IC0  @BASEBOARD_FAB2_LIB.BASEBOARD_FAB2(SCH_1):TP_SPI_SWITCH1_11
   10  TP_SPI_SWITCH1_10    IC1  @BASEBOARD_FAB2_LIB.BASEBOARD_FAB2(SCH_1):TP_SPI_SWITCH1_10
    5  SPI_PCH_IO3_R1    IB0  @BASEBOARD_FAB2_LIB.BASEBOARD_FAB2(SCH_1):SPI_PCH_IO3_R1
    2  SPI_PCH_IO2_R1    IA0  @BASEBOARD_FAB2_LIB.BASEBOARD_FAB2(SCH_1):SPI_PCH_IO2_R1
    7  SPI_BIOS_SOCKET_IO3     YB  @BASEBOARD_FAB2_LIB.BASEBOARD_FAB2(SCH_1):SPI_BIOS_SOCKET_IO3
    4  SPI_BIOS_SOCKET_IO2     YA  @BASEBOARD_FAB2_LIB.BASEBOARD_FAB2(SCH_1):SPI_BIOS_SOCKET_IO2
   16  P3V3_STBY        VCC  @BASEBOARD_FAB2_LIB.BASEBOARD_FAB2(SCH_1):P3V3_STBY
    8  GND              GND  @BASEBOARD_FAB2_LIB.BASEBOARD_FAB2(SCH_1):GND
   15  GND               EN  @BASEBOARD_FAB2_LIB.BASEBOARD_FAB2(SCH_1):GND
    1  FM_BIOS_SPI_BMC_CTRL      S  @BASEBOARD_FAB2_LIB.BASEBOARD_FAB2(SCH_1):FM_BIOS_SPI_BMC_CTRL

TTL1G32_A  I100  U2T2   [TTL1G32_A_SOT-74LVC1G32,IC,E60B]
    2  SPI_SWITCH_CS0_N      B  @BASEBOARD_FAB2_LIB.BASEBOARD_FAB2(SCH_1):SPI_SWITCH_CS0_N
    4  SPI_CS0_SECONDARY_N      Y  @BASEBOARD_FAB2_LIB.BASEBOARD_FAB2(SCH_1):SPI_CS0_SECONDARY_N
    1  FM_BACKUP_BIOS_SEL_N      A  @BASEBOARD_FAB2_LIB.BASEBOARD_FAB2(SCH_1):FM_BACKUP_BIOS_SEL_N

TTL1G32_A  I99  U2T3   [TTL1G32_A_SOT-74LVC1G32,IC,E60B]
    2  SPI_SWITCH_CS0_N      B  @BASEBOARD_FAB2_LIB.BASEBOARD_FAB2(SCH_1):SPI_SWITCH_CS0_N
    4  SPI_CS0_PRIMARY_N      Y  @BASEBOARD_FAB2_LIB.BASEBOARD_FAB2(SCH_1):SPI_CS0_PRIMARY_N
    1  FM_DUAL_BIOS_SEL_N      A  @BASEBOARD_FAB2_LIB.BASEBOARD_FAB2(SCH_1):FM_DUAL_BIOS_SEL_N

GTL2014_SM  I30  U2T4   [GTL2014_SM-IC,D66151-001]
    1  PD_GTL2104_4_DIR    DIR  @BASEBOARD_FAB2_LIB.BASEBOARD_FAB2(SCH_1):PD_GTL2104_4_DIR
   14  P3V3             VCC  @BASEBOARD_FAB2_LIB.BASEBOARD_FAB2(SCH_1):P3V3
    4  P0V7_GTL2104_5_VREF   VREF  @BASEBOARD_FAB2_LIB.BASEBOARD_FAB2(SCH_1):P0V7_GTL2104_5_VREF
    5  H_CPU_ERR1_GTL_N     B2  @BASEBOARD_FAB2_LIB.BASEBOARD_FAB2(SCH_1):H_CPU_ERR1_GTL_N
    6  H_CPU_ERR0_GTL_N     B3  @BASEBOARD_FAB2_LIB.BASEBOARD_FAB2(SCH_1):H_CPU_ERR0_GTL_N
    2  H_CPU1_PROCHOT_G_R_N     B0  @BASEBOARD_FAB2_LIB.BASEBOARD_FAB2(SCH_1):H_CPU1_PROCHOT_G_R_N
    3  H_CPU0_PROCHOT_G_R_N     B1  @BASEBOARD_FAB2_LIB.BASEBOARD_FAB2(SCH_1):H_CPU0_PROCHOT_G_R_N
   11  GND            GND<2>  @BASEBOARD_FAB2_LIB.BASEBOARD_FAB2(SCH_1):GND
    8  GND            GND<1>  @BASEBOARD_FAB2_LIB.BASEBOARD_FAB2(SCH_1):GND
    7  GND            GND<0>  @BASEBOARD_FAB2_LIB.BASEBOARD_FAB2(SCH_1):GND
   10  FM_CPU_ERR1_LVT3_R_N     A2  @BASEBOARD_FAB2_LIB.BASEBOARD_FAB2(SCH_1):FM_CPU_ERR1_LVT3_R_N
    9  FM_CPU_ERR0_LVT3_R_N     A3  @BASEBOARD_FAB2_LIB.BASEBOARD_FAB2(SCH_1):FM_CPU_ERR0_LVT3_R_N
   13  FM_CPU1_PROCHOT_LVT3_R_N     A0  @BASEBOARD_FAB2_LIB.BASEBOARD_FAB2(SCH_1):FM_CPU1_PROCHOT_LVT3_R_N
   12  FM_CPU0_PROCHOT_LVT3_R_N     A1  @BASEBOARD_FAB2_LIB.BASEBOARD_FAB2(SCH_1):FM_CPU0_PROCHOT_LVT3_R_N

PCA9617_SSOP  I75  U3B1   [PCA9617_SSOP-IC,G81764-001-GNDA]
    5  TP_SMB_DDR_KLM_EN     EN  @BASEBOARD_FAB2_LIB.BASEBOARD_FAB2(SCH_1):TP_SMB_DDR_KLM_EN
    6  SMB_DDR_KLM_VPP_SDA_R   SDAB  @BASEBOARD_FAB2_LIB.BASEBOARD_FAB2(SCH_1):SMB_DDR_KLM_VPP_SDA_R
    7  SMB_DDR_KLM_VPP_SCL_R   SCLB  @BASEBOARD_FAB2_LIB.BASEBOARD_FAB2(SCH_1):SMB_DDR_KLM_VPP_SCL_R
    3  SMB_DDR_KLM_SDA_G   SDAA  @BASEBOARD_FAB2_LIB.BASEBOARD_FAB2(SCH_1):SMB_DDR_KLM_SDA_G
    2  SMB_DDR_KLM_SCL_G   SCLA  @BASEBOARD_FAB2_LIB.BASEBOARD_FAB2(SCH_1):SMB_DDR_KLM_SCL_G
    8  PVPP_KLM        VCCB  @BASEBOARD_FAB2_LIB.BASEBOARD_FAB2(SCH_1):PVPP_KLM
    1  PVCCIO_CPU1     VCCA  @BASEBOARD_FAB2_LIB.BASEBOARD_FAB2(SCH_1):PVCCIO_CPU1

GTL2014_SM  I42  U3P1   [GTL2014_SM-IC,D66151-001]
   10  RST_CPU0_LVC3_N     A2  @BASEBOARD_FAB2_LIB.BASEBOARD_FAB2(SCH_1):RST_CPU0_LVC3_N
    5  RST_CPU0_G_N      B2  @BASEBOARD_FAB2_LIB.BASEBOARD_FAB2(SCH_1):RST_CPU0_G_N
   12  PWRGD_DRAMPWRGD     A1  @BASEBOARD_FAB2_LIB.BASEBOARD_FAB2(SCH_1):PWRGD_DRAMPWRGD
   13  PWRGD_DRAMPWRGD     A0  @BASEBOARD_FAB2_LIB.BASEBOARD_FAB2(SCH_1):PWRGD_DRAMPWRGD
    9  PWRGD_CPU0_LVC3     A3  @BASEBOARD_FAB2_LIB.BASEBOARD_FAB2(SCH_1):PWRGD_CPU0_LVC3
    6  PWRGD_CPU0_G      B3  @BASEBOARD_FAB2_LIB.BASEBOARD_FAB2(SCH_1):PWRGD_CPU0_G
    2  PWRGD_CPU0_DRAMPWROK_DEF_G     B0  @BASEBOARD_FAB2_LIB.BASEBOARD_FAB2(SCH_1):PWRGD_CPU0_DRAMPWROK_DEF_G
    3  PWRGD_CPU0_DRAMPWROK_ABC_G     B1  @BASEBOARD_FAB2_LIB.BASEBOARD_FAB2(SCH_1):PWRGD_CPU0_DRAMPWROK_ABC_G
    1  PU_GTL2014_1_DIR    DIR  @BASEBOARD_FAB2_LIB.BASEBOARD_FAB2(SCH_1):PU_GTL2014_1_DIR
    4  PD_GTL2014_1_VREF   VREF  @BASEBOARD_FAB2_LIB.BASEBOARD_FAB2(SCH_1):PD_GTL2014_1_VREF
   14  P3V3_STBY        VCC  @BASEBOARD_FAB2_LIB.BASEBOARD_FAB2(SCH_1):P3V3_STBY
   11  GND            GND<2>  @BASEBOARD_FAB2_LIB.BASEBOARD_FAB2(SCH_1):GND
    8  GND            GND<1>  @BASEBOARD_FAB2_LIB.BASEBOARD_FAB2(SCH_1):GND
    7  GND            GND<0>  @BASEBOARD_FAB2_LIB.BASEBOARD_FAB2(SCH_1):GND

GTL2014_SM  I1   U3P2   [GTL2014_SM-IC,D66151-001]
   13  PWRGD_CPUPWRGD_R1     A0  @BASEBOARD_FAB2_LIB.BASEBOARD_FAB2(SCH_1):PWRGD_CPUPWRGD_R1
    2  PWRGD_CPUPWRGD_GTL     B0  @BASEBOARD_FAB2_LIB.BASEBOARD_FAB2(SCH_1):PWRGD_CPUPWRGD_GTL
    1  PD_GTL2104_DIR_1    DIR  @BASEBOARD_FAB2_LIB.BASEBOARD_FAB2(SCH_1):PD_GTL2104_DIR_1
   14  P3V3             VCC  @BASEBOARD_FAB2_LIB.BASEBOARD_FAB2(SCH_1):P3V3
    4  P0V7_GTL2104_VREF_1   VREF  @BASEBOARD_FAB2_LIB.BASEBOARD_FAB2(SCH_1):P0V7_GTL2104_VREF_1
    5  H_CPU_CATERR_G_N     B2  @BASEBOARD_FAB2_LIB.BASEBOARD_FAB2(SCH_1):H_CPU_CATERR_G_N
    6  H_CPU1_THERMTRIP_G_N     B3  @BASEBOARD_FAB2_LIB.BASEBOARD_FAB2(SCH_1):H_CPU1_THERMTRIP_G_N
    3  H_CPU1_FIVR_FAULT_G     B1  @BASEBOARD_FAB2_LIB.BASEBOARD_FAB2(SCH_1):H_CPU1_FIVR_FAULT_G
   11  GND            GND<2>  @BASEBOARD_FAB2_LIB.BASEBOARD_FAB2(SCH_1):GND
    8  GND            GND<1>  @BASEBOARD_FAB2_LIB.BASEBOARD_FAB2(SCH_1):GND
    7  GND            GND<0>  @BASEBOARD_FAB2_LIB.BASEBOARD_FAB2(SCH_1):GND
   10  FM_CPU_CATERR_LVT3_R2_N     A2  @BASEBOARD_FAB2_LIB.BASEBOARD_FAB2(SCH_1):FM_CPU_CATERR_LVT3_R2_N
    9  FM_CPU1_THERMTRIP_LVT3_R_N     A3  @BASEBOARD_FAB2_LIB.BASEBOARD_FAB2(SCH_1):FM_CPU1_THERMTRIP_LVT3_R_N
   12  FM_CPU1_FIVR_FAULT_R_LVT3     A1  @BASEBOARD_FAB2_LIB.BASEBOARD_FAB2(SCH_1):FM_CPU1_FIVR_FAULT_R_LVT3

W25Q256_XSOI  I165  U3T1   [W25Q256_XSOI-IC,H25002-001]
    4  TP_SPI_1_6     NC<6>  @BASEBOARD_FAB2_LIB.BASEBOARD_FAB2(SCH_1):TP_SPI_1_6
    5  TP_SPI_1_5     NC<5>  @BASEBOARD_FAB2_LIB.BASEBOARD_FAB2(SCH_1):TP_SPI_1_5
    6  TP_SPI_1_4     NC<4>  @BASEBOARD_FAB2_LIB.BASEBOARD_FAB2(SCH_1):TP_SPI_1_4
   11  TP_SPI_1_3     NC<3>  @BASEBOARD_FAB2_LIB.BASEBOARD_FAB2(SCH_1):TP_SPI_1_3
   12  TP_SPI_1_2     NC<2>  @BASEBOARD_FAB2_LIB.BASEBOARD_FAB2(SCH_1):TP_SPI_1_2
   13  TP_SPI_1_1     NC<1>  @BASEBOARD_FAB2_LIB.BASEBOARD_FAB2(SCH_1):TP_SPI_1_1
   14  TP_SPI_1_0     NC<0>  @BASEBOARD_FAB2_LIB.BASEBOARD_FAB2(SCH_1):TP_SPI_1_0
   15  SPI_SWITCH_MOSI_R1  DI_IO<0>  @BASEBOARD_FAB2_LIB.BASEBOARD_FAB2(SCH_1):SPI_SWITCH_MOSI_R1
    8  SPI_MISO_R1    DO_IO<1>  @BASEBOARD_FAB2_LIB.BASEBOARD_FAB2(SCH_1):SPI_MISO_R1
    7  SPI_CS0_SECONDARY_R_N   CS_N  @BASEBOARD_FAB2_LIB.BASEBOARD_FAB2(SCH_1):SPI_CS0_SECONDARY_R_N
   16  SPI_CLK_R1       CLK  @BASEBOARD_FAB2_LIB.BASEBOARD_FAB2(SCH_1):SPI_CLK_R1
    3  PU_SPI1_RST    RESET_N  @BASEBOARD_FAB2_LIB.BASEBOARD_FAB2(SCH_1):PU_SPI1_RST
    9  PU_BIOS_SPI_WP1_N  WP_N_IO<2>  @BASEBOARD_FAB2_LIB.BASEBOARD_FAB2(SCH_1):PU_BIOS_SPI_WP1_N
    1  PU_BIOS_SPI_HOLD1_N  HOLD_N_IO<3>  @BASEBOARD_FAB2_LIB.BASEBOARD_FAB2(SCH_1):PU_BIOS_SPI_HOLD1_N
    2  P3V3_STBY        VCC  @BASEBOARD_FAB2_LIB.BASEBOARD_FAB2(SCH_1):P3V3_STBY
   10  GND              GND  @BASEBOARD_FAB2_LIB.BASEBOARD_FAB2(SCH_1):GND

MAX9634_SOT  I120  U4B1   [MAX9634_SOT-IC,H35789-001]
    3  VR_PVDDQ_DEF_AIINSEN_R    OUT  @BASEBOARD_FAB2_LIB.BASEBOARD_FAB2(SCH_1):VR_PVDDQ_DEF_AIINSEN_R
    5  P12V_STBY        RSP  @BASEBOARD_FAB2_LIB.BASEBOARD_FAB2(SCH_1):P12V_STBY
    4  P12V_NVDIMM_DEF    RSN  @BASEBOARD_FAB2_LIB.BASEBOARD_FAB2(SCH_1):P12V_NVDIMM_DEF
    1  GND            GND<1>  @BASEBOARD_FAB2_LIB.BASEBOARD_FAB2(SCH_1):GND
    2  GND            GND<0>  @BASEBOARD_FAB2_LIB.BASEBOARD_FAB2(SCH_1):GND

ADM4073_SM  I53  U4C1   [ADM4073_SM-EMPTY,G12194-001]
    5  VR_FET_SW_P12V_STBY_PVCCIN_CPU0    RSN  @BASEBOARD_FAB2_LIB.BASEBOARD_FAB2(SCH_1):VR_FET_SW_P12V_STBY_PVCCIN_CPU0
    3  VR_FET_SW_P12V_PVCCIN_CPU0_R    VCC  @BASEBOARD_FAB2_LIB.BASEBOARD_FAB2(SCH_1):VR_FET_SW_P12V_PVCCIN_CPU0_R
    4  VR_FET_SW_P12V_PVCCIN_CPU0_R    RSP  @BASEBOARD_FAB2_LIB.BASEBOARD_FAB2(SCH_1):VR_FET_SW_P12V_PVCCIN_CPU0_R
    6  PVCCIN_PVSA_CPU0_IINSEN    OUT  @BASEBOARD_FAB2_LIB.BASEBOARD_FAB2(SCH_1):PVCCIN_PVSA_CPU0_IINSEN
    2  GND            GND<1>  @BASEBOARD_FAB2_LIB.BASEBOARD_FAB2(SCH_1):GND
    1  GND            GND<0>  @BASEBOARD_FAB2_LIB.BASEBOARD_FAB2(SCH_1):GND

GTL2014_SM  I46  U4C2   [GTL2014_SM-IC,D66151-001]
   10  RST_CPU1_LVC3_N     A2  @BASEBOARD_FAB2_LIB.BASEBOARD_FAB2(SCH_1):RST_CPU1_LVC3_N
    5  RST_CPU1_G_N      B2  @BASEBOARD_FAB2_LIB.BASEBOARD_FAB2(SCH_1):RST_CPU1_G_N
   12  PWRGD_DRAMPWRGD     A1  @BASEBOARD_FAB2_LIB.BASEBOARD_FAB2(SCH_1):PWRGD_DRAMPWRGD
   13  PWRGD_DRAMPWRGD     A0  @BASEBOARD_FAB2_LIB.BASEBOARD_FAB2(SCH_1):PWRGD_DRAMPWRGD
    9  PWRGD_CPU1_LVC3     A3  @BASEBOARD_FAB2_LIB.BASEBOARD_FAB2(SCH_1):PWRGD_CPU1_LVC3
    6  PWRGD_CPU1_G      B3  @BASEBOARD_FAB2_LIB.BASEBOARD_FAB2(SCH_1):PWRGD_CPU1_G
    2  PWRGD_CPU1_DRAMPWROK_KLM_G     B0  @BASEBOARD_FAB2_LIB.BASEBOARD_FAB2(SCH_1):PWRGD_CPU1_DRAMPWROK_KLM_G
    3  PWRGD_CPU1_DRAMPWROK_GHJ_G     B1  @BASEBOARD_FAB2_LIB.BASEBOARD_FAB2(SCH_1):PWRGD_CPU1_DRAMPWROK_GHJ_G
    1  PU_GTL2014_2_DIR    DIR  @BASEBOARD_FAB2_LIB.BASEBOARD_FAB2(SCH_1):PU_GTL2014_2_DIR
    4  PD_GTL2014_2_VREF   VREF  @BASEBOARD_FAB2_LIB.BASEBOARD_FAB2(SCH_1):PD_GTL2014_2_VREF
   14  P3V3_STBY        VCC  @BASEBOARD_FAB2_LIB.BASEBOARD_FAB2(SCH_1):P3V3_STBY
   11  GND            GND<2>  @BASEBOARD_FAB2_LIB.BASEBOARD_FAB2(SCH_1):GND
    8  GND            GND<1>  @BASEBOARD_FAB2_LIB.BASEBOARD_FAB2(SCH_1):GND
    7  GND            GND<0>  @BASEBOARD_FAB2_LIB.BASEBOARD_FAB2(SCH_1):GND

MAX9634_SOT  I97  U4F1   [MAX9634_SOT-IC,H35789-001]
    3  VR_PVDDQ_ABC_AIINSEN_R    OUT  @BASEBOARD_FAB2_LIB.BASEBOARD_FAB2(SCH_1):VR_PVDDQ_ABC_AIINSEN_R
    5  P12V_STBY        RSP  @BASEBOARD_FAB2_LIB.BASEBOARD_FAB2(SCH_1):P12V_STBY
    4  P12V_NVDIMM_ABC    RSN  @BASEBOARD_FAB2_LIB.BASEBOARD_FAB2(SCH_1):P12V_NVDIMM_ABC
    1  GND            GND<1>  @BASEBOARD_FAB2_LIB.BASEBOARD_FAB2(SCH_1):GND
    2  GND            GND<0>  @BASEBOARD_FAB2_LIB.BASEBOARD_FAB2(SCH_1):GND

PCA9617_SSOP  I63  U4G1   [PCA9617_SSOP-IC,G81764-001-GNDA]
    5  TP_SMB_DDR_GHJ_EN     EN  @BASEBOARD_FAB2_LIB.BASEBOARD_FAB2(SCH_1):TP_SMB_DDR_GHJ_EN
    6  SMB_DDR_GHJ_VPP_SDA_R   SDAB  @BASEBOARD_FAB2_LIB.BASEBOARD_FAB2(SCH_1):SMB_DDR_GHJ_VPP_SDA_R
    7  SMB_DDR_GHJ_VPP_SCL_R   SCLB  @BASEBOARD_FAB2_LIB.BASEBOARD_FAB2(SCH_1):SMB_DDR_GHJ_VPP_SCL_R
    3  SMB_DDR_GHJ_SDA_G   SDAA  @BASEBOARD_FAB2_LIB.BASEBOARD_FAB2(SCH_1):SMB_DDR_GHJ_SDA_G
    2  SMB_DDR_GHJ_SCL_G   SCLA  @BASEBOARD_FAB2_LIB.BASEBOARD_FAB2(SCH_1):SMB_DDR_GHJ_SCL_G
    8  PVPP_GHJ        VCCB  @BASEBOARD_FAB2_LIB.BASEBOARD_FAB2(SCH_1):PVPP_GHJ
    1  PVCCIO_CPU1     VCCA  @BASEBOARD_FAB2_LIB.BASEBOARD_FAB2(SCH_1):PVCCIO_CPU1

74CBTLV1G125  I206  U4R1   [74CBTLV1G125_SMLF-IC,C88177-00A]
    2  P1V8_MCP_CPU0      A  @BASEBOARD_FAB2_LIB.BASEBOARD_FAB2(SCH_1):P1V8_MCP_CPU0
    4  JTAG_MCP_CPU0_TDI_R      B  @BASEBOARD_FAB2_LIB.BASEBOARD_FAB2(SCH_1):JTAG_MCP_CPU0_TDI_R
    1  FM_CPU0_PKGID1   OE_N  @BASEBOARD_FAB2_LIB.BASEBOARD_FAB2(SCH_1):FM_CPU0_PKGID1

SKX_EXT_B_BGA1  I286  U5D1   [SKX_EXT_B_BGA1-IC,TBD]
  DN78  GND            VSS<133>  @BASEBOARD_FAB2_LIB.BASEBOARD_FAB2(SCH_1):GND
  DP67  GND            VSS<132>  @BASEBOARD_FAB2_LIB.BASEBOARD_FAB2(SCH_1):GND
  DP69  GND            VSS<131>  @BASEBOARD_FAB2_LIB.BASEBOARD_FAB2(SCH_1):GND
  DP71  GND            VSS<130>  @BASEBOARD_FAB2_LIB.BASEBOARD_FAB2(SCH_1):GND
  DP81  GND            VSS<129>  @BASEBOARD_FAB2_LIB.BASEBOARD_FAB2(SCH_1):GND
  DP83  GND            VSS<128>  @BASEBOARD_FAB2_LIB.BASEBOARD_FAB2(SCH_1):GND
  BR26  GND            VSS<127>  @BASEBOARD_FAB2_LIB.BASEBOARD_FAB2(SCH_1):GND
  DR6  GND            VSS<126>  @BASEBOARD_FAB2_LIB.BASEBOARD_FAB2(SCH_1):GND
  CA20  GND            VSS<125>  @BASEBOARD_FAB2_LIB.BASEBOARD_FAB2(SCH_1):GND
  CL22  GND            VSS<124>  @BASEBOARD_FAB2_LIB.BASEBOARD_FAB2(SCH_1):GND
  DR20  GND            VSS<123>  @BASEBOARD_FAB2_LIB.BASEBOARD_FAB2(SCH_1):GND
  DR22  GND            VSS<122>  @BASEBOARD_FAB2_LIB.BASEBOARD_FAB2(SCH_1):GND
  DR24  GND            VSS<121>  @BASEBOARD_FAB2_LIB.BASEBOARD_FAB2(SCH_1):GND
  DR26  GND            VSS<120>  @BASEBOARD_FAB2_LIB.BASEBOARD_FAB2(SCH_1):GND
  DR28  GND            VSS<119>  @BASEBOARD_FAB2_LIB.BASEBOARD_FAB2(SCH_1):GND
  DR30  GND            VSS<118>  @BASEBOARD_FAB2_LIB.BASEBOARD_FAB2(SCH_1):GND
  DR32  GND            VSS<117>  @BASEBOARD_FAB2_LIB.BASEBOARD_FAB2(SCH_1):GND
  DR34  GND            VSS<116>  @BASEBOARD_FAB2_LIB.BASEBOARD_FAB2(SCH_1):GND
  DR36  GND            VSS<115>  @BASEBOARD_FAB2_LIB.BASEBOARD_FAB2(SCH_1):GND
  DR38  GND            VSS<114>  @BASEBOARD_FAB2_LIB.BASEBOARD_FAB2(SCH_1):GND
  DR40  GND            VSS<113>  @BASEBOARD_FAB2_LIB.BASEBOARD_FAB2(SCH_1):GND
  DR42  GND            VSS<112>  @BASEBOARD_FAB2_LIB.BASEBOARD_FAB2(SCH_1):GND
  DR66  GND            VSS<111>  @BASEBOARD_FAB2_LIB.BASEBOARD_FAB2(SCH_1):GND
  DR68  GND            VSS<110>  @BASEBOARD_FAB2_LIB.BASEBOARD_FAB2(SCH_1):GND
  DR70  GND            VSS<109>  @BASEBOARD_FAB2_LIB.BASEBOARD_FAB2(SCH_1):GND
  DR72  GND            VSS<108>  @BASEBOARD_FAB2_LIB.BASEBOARD_FAB2(SCH_1):GND
  DR74  GND            VSS<107>  @BASEBOARD_FAB2_LIB.BASEBOARD_FAB2(SCH_1):GND
  DR76  GND            VSS<106>  @BASEBOARD_FAB2_LIB.BASEBOARD_FAB2(SCH_1):GND
  DR78  GND            VSS<105>  @BASEBOARD_FAB2_LIB.BASEBOARD_FAB2(SCH_1):GND
  DT3  GND            VSS<104>  @BASEBOARD_FAB2_LIB.BASEBOARD_FAB2(SCH_1):GND
  DT17  GND            VSS<103>  @BASEBOARD_FAB2_LIB.BASEBOARD_FAB2(SCH_1):GND
  DH21  GND            VSS<102>  @BASEBOARD_FAB2_LIB.BASEBOARD_FAB2(SCH_1):GND
  DT65  GND            VSS<101>  @BASEBOARD_FAB2_LIB.BASEBOARD_FAB2(SCH_1):GND
  DT69  GND            VSS<100>  @BASEBOARD_FAB2_LIB.BASEBOARD_FAB2(SCH_1):GND
  DT79  GND            VSS<99>  @BASEBOARD_FAB2_LIB.BASEBOARD_FAB2(SCH_1):GND
  DT83  GND            VSS<98>  @BASEBOARD_FAB2_LIB.BASEBOARD_FAB2(SCH_1):GND
  DT85  GND            VSS<97>  @BASEBOARD_FAB2_LIB.BASEBOARD_FAB2(SCH_1):GND
  DU10  GND            VSS<96>  @BASEBOARD_FAB2_LIB.BASEBOARD_FAB2(SCH_1):GND
  DU14  GND            VSS<95>  @BASEBOARD_FAB2_LIB.BASEBOARD_FAB2(SCH_1):GND
  CN14  GND            VSS<94>  @BASEBOARD_FAB2_LIB.BASEBOARD_FAB2(SCH_1):GND
  DU22  GND            VSS<93>  @BASEBOARD_FAB2_LIB.BASEBOARD_FAB2(SCH_1):GND
  DU26  GND            VSS<92>  @BASEBOARD_FAB2_LIB.BASEBOARD_FAB2(SCH_1):GND
  DU32  GND            VSS<91>  @BASEBOARD_FAB2_LIB.BASEBOARD_FAB2(SCH_1):GND
  DU38  GND            VSS<90>  @BASEBOARD_FAB2_LIB.BASEBOARD_FAB2(SCH_1):GND
  DU70  GND            VSS<89>  @BASEBOARD_FAB2_LIB.BASEBOARD_FAB2(SCH_1):GND
  DU72  GND            VSS<88>  @BASEBOARD_FAB2_LIB.BASEBOARD_FAB2(SCH_1):GND
  DU78  GND            VSS<87>  @BASEBOARD_FAB2_LIB.BASEBOARD_FAB2(SCH_1):GND
  DU80  GND            VSS<86>  @BASEBOARD_FAB2_LIB.BASEBOARD_FAB2(SCH_1):GND
  DU82  GND            VSS<85>  @BASEBOARD_FAB2_LIB.BASEBOARD_FAB2(SCH_1):GND
  DU84  GND            VSS<84>  @BASEBOARD_FAB2_LIB.BASEBOARD_FAB2(SCH_1):GND
  DV21  GND            VSS<83>  @BASEBOARD_FAB2_LIB.BASEBOARD_FAB2(SCH_1):GND
  DV25  GND            VSS<82>  @BASEBOARD_FAB2_LIB.BASEBOARD_FAB2(SCH_1):GND
  DV27  GND            VSS<81>  @BASEBOARD_FAB2_LIB.BASEBOARD_FAB2(SCH_1):GND
  DV31  GND            VSS<80>  @BASEBOARD_FAB2_LIB.BASEBOARD_FAB2(SCH_1):GND
  DV33  GND            VSS<79>  @BASEBOARD_FAB2_LIB.BASEBOARD_FAB2(SCH_1):GND
  DV37  GND            VSS<78>  @BASEBOARD_FAB2_LIB.BASEBOARD_FAB2(SCH_1):GND
  DV39  GND            VSS<77>  @BASEBOARD_FAB2_LIB.BASEBOARD_FAB2(SCH_1):GND
  DV73  GND            VSS<76>  @BASEBOARD_FAB2_LIB.BASEBOARD_FAB2(SCH_1):GND
  DV77  GND            VSS<75>  @BASEBOARD_FAB2_LIB.BASEBOARD_FAB2(SCH_1):GND
  DV81  GND            VSS<74>  @BASEBOARD_FAB2_LIB.BASEBOARD_FAB2(SCH_1):GND
  DW12  GND            VSS<73>  @BASEBOARD_FAB2_LIB.BASEBOARD_FAB2(SCH_1):GND
  DW20  GND            VSS<72>  @BASEBOARD_FAB2_LIB.BASEBOARD_FAB2(SCH_1):GND
  DW24  GND            VSS<71>  @BASEBOARD_FAB2_LIB.BASEBOARD_FAB2(SCH_1):GND
  DW28  GND            VSS<70>  @BASEBOARD_FAB2_LIB.BASEBOARD_FAB2(SCH_1):GND
  DW30  GND            VSS<69>  @BASEBOARD_FAB2_LIB.BASEBOARD_FAB2(SCH_1):GND
  DW34  GND            VSS<68>  @BASEBOARD_FAB2_LIB.BASEBOARD_FAB2(SCH_1):GND
  DW36  GND            VSS<67>  @BASEBOARD_FAB2_LIB.BASEBOARD_FAB2(SCH_1):GND
  DW40  GND            VSS<66>  @BASEBOARD_FAB2_LIB.BASEBOARD_FAB2(SCH_1):GND
  DW64  GND            VSS<65>  @BASEBOARD_FAB2_LIB.BASEBOARD_FAB2(SCH_1):GND
  DW66  GND            VSS<64>  @BASEBOARD_FAB2_LIB.BASEBOARD_FAB2(SCH_1):GND
  DW68  GND            VSS<63>  @BASEBOARD_FAB2_LIB.BASEBOARD_FAB2(SCH_1):GND
  DW70  GND            VSS<62>  @BASEBOARD_FAB2_LIB.BASEBOARD_FAB2(SCH_1):GND
  DW72  GND            VSS<61>  @BASEBOARD_FAB2_LIB.BASEBOARD_FAB2(SCH_1):GND
  DW74  GND            VSS<60>  @BASEBOARD_FAB2_LIB.BASEBOARD_FAB2(SCH_1):GND
  DW76  GND            VSS<59>  @BASEBOARD_FAB2_LIB.BASEBOARD_FAB2(SCH_1):GND
  DW8  GND            VSS<58>  @BASEBOARD_FAB2_LIB.BASEBOARD_FAB2(SCH_1):GND
  DW82  GND            VSS<57>  @BASEBOARD_FAB2_LIB.BASEBOARD_FAB2(SCH_1):GND
  DW84  GND            VSS<56>  @BASEBOARD_FAB2_LIB.BASEBOARD_FAB2(SCH_1):GND
  DY5  GND            VSS<55>  @BASEBOARD_FAB2_LIB.BASEBOARD_FAB2(SCH_1):GND
  DY19  GND            VSS<54>  @BASEBOARD_FAB2_LIB.BASEBOARD_FAB2(SCH_1):GND
  DY23  GND            VSS<53>  @BASEBOARD_FAB2_LIB.BASEBOARD_FAB2(SCH_1):GND
  DY29  GND            VSS<52>  @BASEBOARD_FAB2_LIB.BASEBOARD_FAB2(SCH_1):GND
  DY35  GND            VSS<51>  @BASEBOARD_FAB2_LIB.BASEBOARD_FAB2(SCH_1):GND
  DY41  GND            VSS<50>  @BASEBOARD_FAB2_LIB.BASEBOARD_FAB2(SCH_1):GND
  DY71  GND            VSS<49>  @BASEBOARD_FAB2_LIB.BASEBOARD_FAB2(SCH_1):GND
  DY75  GND            VSS<48>  @BASEBOARD_FAB2_LIB.BASEBOARD_FAB2(SCH_1):GND
  EA6  GND            VSS<47>  @BASEBOARD_FAB2_LIB.BASEBOARD_FAB2(SCH_1):GND
  J16  GND            VSS<46>  @BASEBOARD_FAB2_LIB.BASEBOARD_FAB2(SCH_1):GND
  EA16  GND            VSS<45>  @BASEBOARD_FAB2_LIB.BASEBOARD_FAB2(SCH_1):GND
  EA20  GND            VSS<44>  @BASEBOARD_FAB2_LIB.BASEBOARD_FAB2(SCH_1):GND
  EA22  GND            VSS<43>  @BASEBOARD_FAB2_LIB.BASEBOARD_FAB2(SCH_1):GND
  EA42  GND            VSS<42>  @BASEBOARD_FAB2_LIB.BASEBOARD_FAB2(SCH_1):GND
  EA64  GND            VSS<41>  @BASEBOARD_FAB2_LIB.BASEBOARD_FAB2(SCH_1):GND
  EA70  GND            VSS<40>  @BASEBOARD_FAB2_LIB.BASEBOARD_FAB2(SCH_1):GND
  EA76  GND            VSS<39>  @BASEBOARD_FAB2_LIB.BASEBOARD_FAB2(SCH_1):GND
  EA78  GND            VSS<38>  @BASEBOARD_FAB2_LIB.BASEBOARD_FAB2(SCH_1):GND
  EA80  GND            VSS<37>  @BASEBOARD_FAB2_LIB.BASEBOARD_FAB2(SCH_1):GND
  EA82  GND            VSS<36>  @BASEBOARD_FAB2_LIB.BASEBOARD_FAB2(SCH_1):GND
  EB13  GND            VSS<35>  @BASEBOARD_FAB2_LIB.BASEBOARD_FAB2(SCH_1):GND
  BR18  GND            VSS<34>  @BASEBOARD_FAB2_LIB.BASEBOARD_FAB2(SCH_1):GND
  EB23  GND            VSS<33>  @BASEBOARD_FAB2_LIB.BASEBOARD_FAB2(SCH_1):GND
  EB25  GND            VSS<32>  @BASEBOARD_FAB2_LIB.BASEBOARD_FAB2(SCH_1):GND
  EB27  GND            VSS<31>  @BASEBOARD_FAB2_LIB.BASEBOARD_FAB2(SCH_1):GND
  EB29  GND            VSS<30>  @BASEBOARD_FAB2_LIB.BASEBOARD_FAB2(SCH_1):GND
  EB31  GND            VSS<29>  @BASEBOARD_FAB2_LIB.BASEBOARD_FAB2(SCH_1):GND
  EB33  GND            VSS<28>  @BASEBOARD_FAB2_LIB.BASEBOARD_FAB2(SCH_1):GND
  EB35  GND            VSS<27>  @BASEBOARD_FAB2_LIB.BASEBOARD_FAB2(SCH_1):GND
  EB37  GND            VSS<26>  @BASEBOARD_FAB2_LIB.BASEBOARD_FAB2(SCH_1):GND
  EB39  GND            VSS<25>  @BASEBOARD_FAB2_LIB.BASEBOARD_FAB2(SCH_1):GND
  EB41  GND            VSS<24>  @BASEBOARD_FAB2_LIB.BASEBOARD_FAB2(SCH_1):GND
  EB65  GND            VSS<23>  @BASEBOARD_FAB2_LIB.BASEBOARD_FAB2(SCH_1):GND
  EB69  GND            VSS<22>  @BASEBOARD_FAB2_LIB.BASEBOARD_FAB2(SCH_1):GND
  EC10  GND            VSS<21>  @BASEBOARD_FAB2_LIB.BASEBOARD_FAB2(SCH_1):GND
  EC70  GND            VSS<20>  @BASEBOARD_FAB2_LIB.BASEBOARD_FAB2(SCH_1):GND
  EC72  GND            VSS<19>  @BASEBOARD_FAB2_LIB.BASEBOARD_FAB2(SCH_1):GND
  EC74  GND            VSS<18>  @BASEBOARD_FAB2_LIB.BASEBOARD_FAB2(SCH_1):GND
  EC76  GND            VSS<17>  @BASEBOARD_FAB2_LIB.BASEBOARD_FAB2(SCH_1):GND
  ED11  GND            VSS<16>  @BASEBOARD_FAB2_LIB.BASEBOARD_FAB2(SCH_1):GND
  ED15  GND            VSS<15>  @BASEBOARD_FAB2_LIB.BASEBOARD_FAB2(SCH_1):GND
  ED23  GND            VSS<14>  @BASEBOARD_FAB2_LIB.BASEBOARD_FAB2(SCH_1):GND
  ED29  GND            VSS<13>  @BASEBOARD_FAB2_LIB.BASEBOARD_FAB2(SCH_1):GND
  ED35  GND            VSS<12>  @BASEBOARD_FAB2_LIB.BASEBOARD_FAB2(SCH_1):GND
  ED77  GND            VSS<11>  @BASEBOARD_FAB2_LIB.BASEBOARD_FAB2(SCH_1):GND
  EE24  GND            VSS<10>  @BASEBOARD_FAB2_LIB.BASEBOARD_FAB2(SCH_1):GND
  EE28  GND            VSS<9>  @BASEBOARD_FAB2_LIB.BASEBOARD_FAB2(SCH_1):GND
  EE30  GND            VSS<8>  @BASEBOARD_FAB2_LIB.BASEBOARD_FAB2(SCH_1):GND
  EE34  GND            VSS<7>  @BASEBOARD_FAB2_LIB.BASEBOARD_FAB2(SCH_1):GND
  EE36  GND            VSS<6>  @BASEBOARD_FAB2_LIB.BASEBOARD_FAB2(SCH_1):GND
  EE70  GND            VSS<5>  @BASEBOARD_FAB2_LIB.BASEBOARD_FAB2(SCH_1):GND
  EE76  GND            VSS<4>  @BASEBOARD_FAB2_LIB.BASEBOARD_FAB2(SCH_1):GND
  EE78  GND            VSS<3>  @BASEBOARD_FAB2_LIB.BASEBOARD_FAB2(SCH_1):GND
  EF71  GND            VSS<2>  @BASEBOARD_FAB2_LIB.BASEBOARD_FAB2(SCH_1):GND
  EF75  GND            VSS<1>  @BASEBOARD_FAB2_LIB.BASEBOARD_FAB2(SCH_1):GND
  EF79  GND            VSS<0>  @BASEBOARD_FAB2_LIB.BASEBOARD_FAB2(SCH_1):GND

SKX_EXT_B_BGA1  I285  U5D1   [SKX_EXT_B_BGA1-IC,TBD]
  DA48  GND            VSS<293>  @BASEBOARD_FAB2_LIB.BASEBOARD_FAB2(SCH_1):GND
  DA50  GND            VSS<292>  @BASEBOARD_FAB2_LIB.BASEBOARD_FAB2(SCH_1):GND
  DA64  GND            VSS<291>  @BASEBOARD_FAB2_LIB.BASEBOARD_FAB2(SCH_1):GND
  DA70  GND            VSS<290>  @BASEBOARD_FAB2_LIB.BASEBOARD_FAB2(SCH_1):GND
  DA74  GND            VSS<289>  @BASEBOARD_FAB2_LIB.BASEBOARD_FAB2(SCH_1):GND
  DA76  GND            VSS<288>  @BASEBOARD_FAB2_LIB.BASEBOARD_FAB2(SCH_1):GND
  DA78  GND            VSS<287>  @BASEBOARD_FAB2_LIB.BASEBOARD_FAB2(SCH_1):GND
  DA80  GND            VSS<286>  @BASEBOARD_FAB2_LIB.BASEBOARD_FAB2(SCH_1):GND
  DB3  GND            VSS<285>  @BASEBOARD_FAB2_LIB.BASEBOARD_FAB2(SCH_1):GND
  DB13  GND            VSS<284>  @BASEBOARD_FAB2_LIB.BASEBOARD_FAB2(SCH_1):GND
  DB17  GND            VSS<283>  @BASEBOARD_FAB2_LIB.BASEBOARD_FAB2(SCH_1):GND
  DB23  GND            VSS<282>  @BASEBOARD_FAB2_LIB.BASEBOARD_FAB2(SCH_1):GND
  DB25  GND            VSS<281>  @BASEBOARD_FAB2_LIB.BASEBOARD_FAB2(SCH_1):GND
  DB39  GND            VSS<280>  @BASEBOARD_FAB2_LIB.BASEBOARD_FAB2(SCH_1):GND
  DB41  GND            VSS<279>  @BASEBOARD_FAB2_LIB.BASEBOARD_FAB2(SCH_1):GND
  DB47  GND            VSS<278>  @BASEBOARD_FAB2_LIB.BASEBOARD_FAB2(SCH_1):GND
  DB49  GND            VSS<277>  @BASEBOARD_FAB2_LIB.BASEBOARD_FAB2(SCH_1):GND
  DB73  GND            VSS<276>  @BASEBOARD_FAB2_LIB.BASEBOARD_FAB2(SCH_1):GND
  DB77  GND            VSS<275>  @BASEBOARD_FAB2_LIB.BASEBOARD_FAB2(SCH_1):GND
  DB83  GND            VSS<274>  @BASEBOARD_FAB2_LIB.BASEBOARD_FAB2(SCH_1):GND
  DB85  GND            VSS<273>  @BASEBOARD_FAB2_LIB.BASEBOARD_FAB2(SCH_1):GND
  DC14  GND            VSS<272>  @BASEBOARD_FAB2_LIB.BASEBOARD_FAB2(SCH_1):GND
  DC24  GND            VSS<271>  @BASEBOARD_FAB2_LIB.BASEBOARD_FAB2(SCH_1):GND
  DC26  GND            VSS<270>  @BASEBOARD_FAB2_LIB.BASEBOARD_FAB2(SCH_1):GND
  DC32  GND            VSS<269>  @BASEBOARD_FAB2_LIB.BASEBOARD_FAB2(SCH_1):GND
  DC38  GND            VSS<268>  @BASEBOARD_FAB2_LIB.BASEBOARD_FAB2(SCH_1):GND
  DC42  GND            VSS<267>  @BASEBOARD_FAB2_LIB.BASEBOARD_FAB2(SCH_1):GND
  DC64  GND            VSS<266>  @BASEBOARD_FAB2_LIB.BASEBOARD_FAB2(SCH_1):GND
  DC66  GND            VSS<265>  @BASEBOARD_FAB2_LIB.BASEBOARD_FAB2(SCH_1):GND
  DC68  GND            VSS<264>  @BASEBOARD_FAB2_LIB.BASEBOARD_FAB2(SCH_1):GND
  DC70  GND            VSS<263>  @BASEBOARD_FAB2_LIB.BASEBOARD_FAB2(SCH_1):GND
  DC78  GND            VSS<262>  @BASEBOARD_FAB2_LIB.BASEBOARD_FAB2(SCH_1):GND
  DC84  GND            VSS<261>  @BASEBOARD_FAB2_LIB.BASEBOARD_FAB2(SCH_1):GND
  DC86  GND            VSS<260>  @BASEBOARD_FAB2_LIB.BASEBOARD_FAB2(SCH_1):GND
  DD11  GND            VSS<259>  @BASEBOARD_FAB2_LIB.BASEBOARD_FAB2(SCH_1):GND
  DD23  GND            VSS<258>  @BASEBOARD_FAB2_LIB.BASEBOARD_FAB2(SCH_1):GND
  DD27  GND            VSS<257>  @BASEBOARD_FAB2_LIB.BASEBOARD_FAB2(SCH_1):GND
  DD31  GND            VSS<256>  @BASEBOARD_FAB2_LIB.BASEBOARD_FAB2(SCH_1):GND
  DD33  GND            VSS<255>  @BASEBOARD_FAB2_LIB.BASEBOARD_FAB2(SCH_1):GND
  DD37  GND            VSS<254>  @BASEBOARD_FAB2_LIB.BASEBOARD_FAB2(SCH_1):GND
  DD71  GND            VSS<253>  @BASEBOARD_FAB2_LIB.BASEBOARD_FAB2(SCH_1):GND
  DD73  GND            VSS<252>  @BASEBOARD_FAB2_LIB.BASEBOARD_FAB2(SCH_1):GND
  DD75  GND            VSS<251>  @BASEBOARD_FAB2_LIB.BASEBOARD_FAB2(SCH_1):GND
  DD81  GND            VSS<250>  @BASEBOARD_FAB2_LIB.BASEBOARD_FAB2(SCH_1):GND
  DD83  GND            VSS<249>  @BASEBOARD_FAB2_LIB.BASEBOARD_FAB2(SCH_1):GND
  DE6  GND            VSS<248>  @BASEBOARD_FAB2_LIB.BASEBOARD_FAB2(SCH_1):GND
  DE8  GND            VSS<247>  @BASEBOARD_FAB2_LIB.BASEBOARD_FAB2(SCH_1):GND
  DE18  GND            VSS<246>  @BASEBOARD_FAB2_LIB.BASEBOARD_FAB2(SCH_1):GND
  DE20  GND            VSS<245>  @BASEBOARD_FAB2_LIB.BASEBOARD_FAB2(SCH_1):GND
  DE24  GND            VSS<244>  @BASEBOARD_FAB2_LIB.BASEBOARD_FAB2(SCH_1):GND
  DE28  GND            VSS<243>  @BASEBOARD_FAB2_LIB.BASEBOARD_FAB2(SCH_1):GND
  DE30  GND            VSS<242>  @BASEBOARD_FAB2_LIB.BASEBOARD_FAB2(SCH_1):GND
  DE34  GND            VSS<241>  @BASEBOARD_FAB2_LIB.BASEBOARD_FAB2(SCH_1):GND
  DE36  GND            VSS<240>  @BASEBOARD_FAB2_LIB.BASEBOARD_FAB2(SCH_1):GND
  DE64  GND            VSS<239>  @BASEBOARD_FAB2_LIB.BASEBOARD_FAB2(SCH_1):GND
  DE70  GND            VSS<238>  @BASEBOARD_FAB2_LIB.BASEBOARD_FAB2(SCH_1):GND
  DE72  GND            VSS<237>  @BASEBOARD_FAB2_LIB.BASEBOARD_FAB2(SCH_1):GND
  DE78  GND            VSS<236>  @BASEBOARD_FAB2_LIB.BASEBOARD_FAB2(SCH_1):GND
  DF5  GND            VSS<235>  @BASEBOARD_FAB2_LIB.BASEBOARD_FAB2(SCH_1):GND
  DF7  GND            VSS<234>  @BASEBOARD_FAB2_LIB.BASEBOARD_FAB2(SCH_1):GND
  H51  GND            VSS<233>  @BASEBOARD_FAB2_LIB.BASEBOARD_FAB2(SCH_1):GND
  DF19  GND            VSS<232>  @BASEBOARD_FAB2_LIB.BASEBOARD_FAB2(SCH_1):GND
  DF29  GND            VSS<231>  @BASEBOARD_FAB2_LIB.BASEBOARD_FAB2(SCH_1):GND
  DF35  GND            VSS<230>  @BASEBOARD_FAB2_LIB.BASEBOARD_FAB2(SCH_1):GND
  DF37  GND            VSS<229>  @BASEBOARD_FAB2_LIB.BASEBOARD_FAB2(SCH_1):GND
  DF39  GND            VSS<228>  @BASEBOARD_FAB2_LIB.BASEBOARD_FAB2(SCH_1):GND
  DF41  GND            VSS<227>  @BASEBOARD_FAB2_LIB.BASEBOARD_FAB2(SCH_1):GND
  DF65  GND            VSS<226>  @BASEBOARD_FAB2_LIB.BASEBOARD_FAB2(SCH_1):GND
  DF69  GND            VSS<225>  @BASEBOARD_FAB2_LIB.BASEBOARD_FAB2(SCH_1):GND
  DF73  GND            VSS<224>  @BASEBOARD_FAB2_LIB.BASEBOARD_FAB2(SCH_1):GND
  DF79  GND            VSS<223>  @BASEBOARD_FAB2_LIB.BASEBOARD_FAB2(SCH_1):GND
  DF83  GND            VSS<222>  @BASEBOARD_FAB2_LIB.BASEBOARD_FAB2(SCH_1):GND
  DF85  GND            VSS<221>  @BASEBOARD_FAB2_LIB.BASEBOARD_FAB2(SCH_1):GND
  DG2  GND            VSS<220>  @BASEBOARD_FAB2_LIB.BASEBOARD_FAB2(SCH_1):GND
  H49  GND            VSS<219>  @BASEBOARD_FAB2_LIB.BASEBOARD_FAB2(SCH_1):GND
  DG14  GND            VSS<218>  @BASEBOARD_FAB2_LIB.BASEBOARD_FAB2(SCH_1):GND
  DG16  GND            VSS<217>  @BASEBOARD_FAB2_LIB.BASEBOARD_FAB2(SCH_1):GND
  DG24  GND            VSS<216>  @BASEBOARD_FAB2_LIB.BASEBOARD_FAB2(SCH_1):GND
  DG66  GND            VSS<215>  @BASEBOARD_FAB2_LIB.BASEBOARD_FAB2(SCH_1):GND
  DG68  GND            VSS<214>  @BASEBOARD_FAB2_LIB.BASEBOARD_FAB2(SCH_1):GND
  DG76  GND            VSS<213>  @BASEBOARD_FAB2_LIB.BASEBOARD_FAB2(SCH_1):GND
  DG78  GND            VSS<212>  @BASEBOARD_FAB2_LIB.BASEBOARD_FAB2(SCH_1):GND
  DG80  GND            VSS<211>  @BASEBOARD_FAB2_LIB.BASEBOARD_FAB2(SCH_1):GND
  DG82  GND            VSS<210>  @BASEBOARD_FAB2_LIB.BASEBOARD_FAB2(SCH_1):GND
  DH13  GND            VSS<209>  @BASEBOARD_FAB2_LIB.BASEBOARD_FAB2(SCH_1):GND
  DH15  GND            VSS<208>  @BASEBOARD_FAB2_LIB.BASEBOARD_FAB2(SCH_1):GND
  DH23  GND            VSS<207>  @BASEBOARD_FAB2_LIB.BASEBOARD_FAB2(SCH_1):GND
  DH25  GND            VSS<206>  @BASEBOARD_FAB2_LIB.BASEBOARD_FAB2(SCH_1):GND
  DH27  GND            VSS<205>  @BASEBOARD_FAB2_LIB.BASEBOARD_FAB2(SCH_1):GND
  DH29  GND            VSS<204>  @BASEBOARD_FAB2_LIB.BASEBOARD_FAB2(SCH_1):GND
  DH31  GND            VSS<203>  @BASEBOARD_FAB2_LIB.BASEBOARD_FAB2(SCH_1):GND
  DH33  GND            VSS<202>  @BASEBOARD_FAB2_LIB.BASEBOARD_FAB2(SCH_1):GND
  DH35  GND            VSS<201>  @BASEBOARD_FAB2_LIB.BASEBOARD_FAB2(SCH_1):GND
  DH37  GND            VSS<200>  @BASEBOARD_FAB2_LIB.BASEBOARD_FAB2(SCH_1):GND
  DH41  GND            VSS<199>  @BASEBOARD_FAB2_LIB.BASEBOARD_FAB2(SCH_1):GND
  DH67  GND            VSS<198>  @BASEBOARD_FAB2_LIB.BASEBOARD_FAB2(SCH_1):GND
  DH71  GND            VSS<197>  @BASEBOARD_FAB2_LIB.BASEBOARD_FAB2(SCH_1):GND
  DH73  GND            VSS<196>  @BASEBOARD_FAB2_LIB.BASEBOARD_FAB2(SCH_1):GND
  DH79  GND            VSS<195>  @BASEBOARD_FAB2_LIB.BASEBOARD_FAB2(SCH_1):GND
  DH81  GND            VSS<194>  @BASEBOARD_FAB2_LIB.BASEBOARD_FAB2(SCH_1):GND
  DH83  GND            VSS<193>  @BASEBOARD_FAB2_LIB.BASEBOARD_FAB2(SCH_1):GND
  DJ2  GND            VSS<192>  @BASEBOARD_FAB2_LIB.BASEBOARD_FAB2(SCH_1):GND
  DJ10  GND            VSS<191>  @BASEBOARD_FAB2_LIB.BASEBOARD_FAB2(SCH_1):GND
  H47  GND            VSS<190>  @BASEBOARD_FAB2_LIB.BASEBOARD_FAB2(SCH_1):GND
  DJ22  GND            VSS<189>  @BASEBOARD_FAB2_LIB.BASEBOARD_FAB2(SCH_1):GND
  DJ38  GND            VSS<188>  @BASEBOARD_FAB2_LIB.BASEBOARD_FAB2(SCH_1):GND
  DJ42  GND            VSS<187>  @BASEBOARD_FAB2_LIB.BASEBOARD_FAB2(SCH_1):GND
  DJ68  GND            VSS<186>  @BASEBOARD_FAB2_LIB.BASEBOARD_FAB2(SCH_1):GND
  DJ74  GND            VSS<185>  @BASEBOARD_FAB2_LIB.BASEBOARD_FAB2(SCH_1):GND
  DJ78  GND            VSS<184>  @BASEBOARD_FAB2_LIB.BASEBOARD_FAB2(SCH_1):GND
  DJ82  GND            VSS<183>  @BASEBOARD_FAB2_LIB.BASEBOARD_FAB2(SCH_1):GND
  DJ84  GND            VSS<182>  @BASEBOARD_FAB2_LIB.BASEBOARD_FAB2(SCH_1):GND
  DK7  GND            VSS<181>  @BASEBOARD_FAB2_LIB.BASEBOARD_FAB2(SCH_1):GND
  DK23  GND            VSS<180>  @BASEBOARD_FAB2_LIB.BASEBOARD_FAB2(SCH_1):GND
  DK29  GND            VSS<179>  @BASEBOARD_FAB2_LIB.BASEBOARD_FAB2(SCH_1):GND
  DK35  GND            VSS<178>  @BASEBOARD_FAB2_LIB.BASEBOARD_FAB2(SCH_1):GND
  DK39  GND            VSS<177>  @BASEBOARD_FAB2_LIB.BASEBOARD_FAB2(SCH_1):GND
  DK41  GND            VSS<176>  @BASEBOARD_FAB2_LIB.BASEBOARD_FAB2(SCH_1):GND
  DK73  GND            VSS<175>  @BASEBOARD_FAB2_LIB.BASEBOARD_FAB2(SCH_1):GND
  DK75  GND            VSS<174>  @BASEBOARD_FAB2_LIB.BASEBOARD_FAB2(SCH_1):GND
  DK77  GND            VSS<173>  @BASEBOARD_FAB2_LIB.BASEBOARD_FAB2(SCH_1):GND
  DK83  GND            VSS<172>  @BASEBOARD_FAB2_LIB.BASEBOARD_FAB2(SCH_1):GND
  DK85  GND            VSS<171>  @BASEBOARD_FAB2_LIB.BASEBOARD_FAB2(SCH_1):GND
  DL16  GND            VSS<170>  @BASEBOARD_FAB2_LIB.BASEBOARD_FAB2(SCH_1):GND
  DL18  GND            VSS<169>  @BASEBOARD_FAB2_LIB.BASEBOARD_FAB2(SCH_1):GND
  DL4  GND            VSS<168>  @BASEBOARD_FAB2_LIB.BASEBOARD_FAB2(SCH_1):GND
  DL22  GND            VSS<167>  @BASEBOARD_FAB2_LIB.BASEBOARD_FAB2(SCH_1):GND
  DL24  GND            VSS<166>  @BASEBOARD_FAB2_LIB.BASEBOARD_FAB2(SCH_1):GND
  DL28  GND            VSS<165>  @BASEBOARD_FAB2_LIB.BASEBOARD_FAB2(SCH_1):GND
  DL30  GND            VSS<164>  @BASEBOARD_FAB2_LIB.BASEBOARD_FAB2(SCH_1):GND
  DL34  GND            VSS<163>  @BASEBOARD_FAB2_LIB.BASEBOARD_FAB2(SCH_1):GND
  DL36  GND            VSS<162>  @BASEBOARD_FAB2_LIB.BASEBOARD_FAB2(SCH_1):GND
  DL40  GND            VSS<161>  @BASEBOARD_FAB2_LIB.BASEBOARD_FAB2(SCH_1):GND
  DL68  GND            VSS<160>  @BASEBOARD_FAB2_LIB.BASEBOARD_FAB2(SCH_1):GND
  DL70  GND            VSS<159>  @BASEBOARD_FAB2_LIB.BASEBOARD_FAB2(SCH_1):GND
  DL74  GND            VSS<158>  @BASEBOARD_FAB2_LIB.BASEBOARD_FAB2(SCH_1):GND
  DL76  GND            VSS<157>  @BASEBOARD_FAB2_LIB.BASEBOARD_FAB2(SCH_1):GND
  DL78  GND            VSS<156>  @BASEBOARD_FAB2_LIB.BASEBOARD_FAB2(SCH_1):GND
  DL80  GND            VSS<155>  @BASEBOARD_FAB2_LIB.BASEBOARD_FAB2(SCH_1):GND
  DM15  GND            VSS<154>  @BASEBOARD_FAB2_LIB.BASEBOARD_FAB2(SCH_1):GND
  H45  GND            VSS<153>  @BASEBOARD_FAB2_LIB.BASEBOARD_FAB2(SCH_1):GND
  DM25  GND            VSS<152>  @BASEBOARD_FAB2_LIB.BASEBOARD_FAB2(SCH_1):GND
  DM27  GND            VSS<151>  @BASEBOARD_FAB2_LIB.BASEBOARD_FAB2(SCH_1):GND
  DM31  GND            VSS<150>  @BASEBOARD_FAB2_LIB.BASEBOARD_FAB2(SCH_1):GND
  DM33  GND            VSS<149>  @BASEBOARD_FAB2_LIB.BASEBOARD_FAB2(SCH_1):GND
  DM37  GND            VSS<148>  @BASEBOARD_FAB2_LIB.BASEBOARD_FAB2(SCH_1):GND
  DM39  GND            VSS<147>  @BASEBOARD_FAB2_LIB.BASEBOARD_FAB2(SCH_1):GND
  DM65  GND            VSS<146>  @BASEBOARD_FAB2_LIB.BASEBOARD_FAB2(SCH_1):GND
  DM73  GND            VSS<145>  @BASEBOARD_FAB2_LIB.BASEBOARD_FAB2(SCH_1):GND
  DM77  GND            VSS<144>  @BASEBOARD_FAB2_LIB.BASEBOARD_FAB2(SCH_1):GND
  DM83  GND            VSS<143>  @BASEBOARD_FAB2_LIB.BASEBOARD_FAB2(SCH_1):GND
  DN2  GND            VSS<142>  @BASEBOARD_FAB2_LIB.BASEBOARD_FAB2(SCH_1):GND
  BH17  GND            VSS<141>  @BASEBOARD_FAB2_LIB.BASEBOARD_FAB2(SCH_1):GND
  DN12  GND            VSS<140>  @BASEBOARD_FAB2_LIB.BASEBOARD_FAB2(SCH_1):GND
  DN22  GND            VSS<139>  @BASEBOARD_FAB2_LIB.BASEBOARD_FAB2(SCH_1):GND
  DN26  GND            VSS<138>  @BASEBOARD_FAB2_LIB.BASEBOARD_FAB2(SCH_1):GND
  DN32  GND            VSS<137>  @BASEBOARD_FAB2_LIB.BASEBOARD_FAB2(SCH_1):GND
  DN38  GND            VSS<136>  @BASEBOARD_FAB2_LIB.BASEBOARD_FAB2(SCH_1):GND
  DN68  GND            VSS<135>  @BASEBOARD_FAB2_LIB.BASEBOARD_FAB2(SCH_1):GND
  DN72  GND            VSS<134>  @BASEBOARD_FAB2_LIB.BASEBOARD_FAB2(SCH_1):GND

SKX_EXT_B_BGA1  I284  U5D1   [SKX_EXT_B_BGA1-IC,TBD]
  P47  GND            VSS<453>  @BASEBOARD_FAB2_LIB.BASEBOARD_FAB2(SCH_1):GND
  CJ62  GND            VSS<452>  @BASEBOARD_FAB2_LIB.BASEBOARD_FAB2(SCH_1):GND
  CJ74  GND            VSS<451>  @BASEBOARD_FAB2_LIB.BASEBOARD_FAB2(SCH_1):GND
  CJ76  GND            VSS<450>  @BASEBOARD_FAB2_LIB.BASEBOARD_FAB2(SCH_1):GND
  CJ78  GND            VSS<449>  @BASEBOARD_FAB2_LIB.BASEBOARD_FAB2(SCH_1):GND
  CJ82  GND            VSS<448>  @BASEBOARD_FAB2_LIB.BASEBOARD_FAB2(SCH_1):GND
  CJ84  GND            VSS<447>  @BASEBOARD_FAB2_LIB.BASEBOARD_FAB2(SCH_1):GND
  CJ86  GND            VSS<446>  @BASEBOARD_FAB2_LIB.BASEBOARD_FAB2(SCH_1):GND
  CK11  GND            VSS<445>  @BASEBOARD_FAB2_LIB.BASEBOARD_FAB2(SCH_1):GND
  CK15  GND            VSS<444>  @BASEBOARD_FAB2_LIB.BASEBOARD_FAB2(SCH_1):GND
  CK21  GND            VSS<443>  @BASEBOARD_FAB2_LIB.BASEBOARD_FAB2(SCH_1):GND
  CK27  GND            VSS<442>  @BASEBOARD_FAB2_LIB.BASEBOARD_FAB2(SCH_1):GND
  CK63  GND            VSS<441>  @BASEBOARD_FAB2_LIB.BASEBOARD_FAB2(SCH_1):GND
  CK65  GND            VSS<440>  @BASEBOARD_FAB2_LIB.BASEBOARD_FAB2(SCH_1):GND
  CK67  GND            VSS<439>  @BASEBOARD_FAB2_LIB.BASEBOARD_FAB2(SCH_1):GND
  CK69  GND            VSS<438>  @BASEBOARD_FAB2_LIB.BASEBOARD_FAB2(SCH_1):GND
  CK71  GND            VSS<437>  @BASEBOARD_FAB2_LIB.BASEBOARD_FAB2(SCH_1):GND
  CK73  GND            VSS<436>  @BASEBOARD_FAB2_LIB.BASEBOARD_FAB2(SCH_1):GND
  CK75  GND            VSS<435>  @BASEBOARD_FAB2_LIB.BASEBOARD_FAB2(SCH_1):GND
  CK83  GND            VSS<434>  @BASEBOARD_FAB2_LIB.BASEBOARD_FAB2(SCH_1):GND
  CK85  GND            VSS<433>  @BASEBOARD_FAB2_LIB.BASEBOARD_FAB2(SCH_1):GND
  CL8  GND            VSS<432>  @BASEBOARD_FAB2_LIB.BASEBOARD_FAB2(SCH_1):GND
  CL14  GND            VSS<431>  @BASEBOARD_FAB2_LIB.BASEBOARD_FAB2(SCH_1):GND
  CL18  GND            VSS<430>  @BASEBOARD_FAB2_LIB.BASEBOARD_FAB2(SCH_1):GND
  P45  GND            VSS<429>  @BASEBOARD_FAB2_LIB.BASEBOARD_FAB2(SCH_1):GND
  H63  GND            VSS<428>  @BASEBOARD_FAB2_LIB.BASEBOARD_FAB2(SCH_1):GND
  CL62  GND            VSS<427>  @BASEBOARD_FAB2_LIB.BASEBOARD_FAB2(SCH_1):GND
  CL64  GND            VSS<426>  @BASEBOARD_FAB2_LIB.BASEBOARD_FAB2(SCH_1):GND
  CL66  GND            VSS<425>  @BASEBOARD_FAB2_LIB.BASEBOARD_FAB2(SCH_1):GND
  CL74  GND            VSS<424>  @BASEBOARD_FAB2_LIB.BASEBOARD_FAB2(SCH_1):GND
  CL76  GND            VSS<423>  @BASEBOARD_FAB2_LIB.BASEBOARD_FAB2(SCH_1):GND
  CL78  GND            VSS<422>  @BASEBOARD_FAB2_LIB.BASEBOARD_FAB2(SCH_1):GND
  CL80  GND            VSS<421>  @BASEBOARD_FAB2_LIB.BASEBOARD_FAB2(SCH_1):GND
  CM19  GND            VSS<420>  @BASEBOARD_FAB2_LIB.BASEBOARD_FAB2(SCH_1):GND
  CM29  GND            VSS<419>  @BASEBOARD_FAB2_LIB.BASEBOARD_FAB2(SCH_1):GND
  CM5  GND            VSS<418>  @BASEBOARD_FAB2_LIB.BASEBOARD_FAB2(SCH_1):GND
  CM31  GND            VSS<417>  @BASEBOARD_FAB2_LIB.BASEBOARD_FAB2(SCH_1):GND
  CM61  GND            VSS<416>  @BASEBOARD_FAB2_LIB.BASEBOARD_FAB2(SCH_1):GND
  CM63  GND            VSS<415>  @BASEBOARD_FAB2_LIB.BASEBOARD_FAB2(SCH_1):GND
  CM67  GND            VSS<414>  @BASEBOARD_FAB2_LIB.BASEBOARD_FAB2(SCH_1):GND
  CM73  GND            VSS<413>  @BASEBOARD_FAB2_LIB.BASEBOARD_FAB2(SCH_1):GND
  CM77  GND            VSS<412>  @BASEBOARD_FAB2_LIB.BASEBOARD_FAB2(SCH_1):GND
  CM83  GND            VSS<411>  @BASEBOARD_FAB2_LIB.BASEBOARD_FAB2(SCH_1):GND
  CM85  GND            VSS<410>  @BASEBOARD_FAB2_LIB.BASEBOARD_FAB2(SCH_1):GND
  CN2  GND            VSS<409>  @BASEBOARD_FAB2_LIB.BASEBOARD_FAB2(SCH_1):GND
  CN12  GND            VSS<408>  @BASEBOARD_FAB2_LIB.BASEBOARD_FAB2(SCH_1):GND
  H61  GND            VSS<407>  @BASEBOARD_FAB2_LIB.BASEBOARD_FAB2(SCH_1):GND
  CN26  GND            VSS<406>  @BASEBOARD_FAB2_LIB.BASEBOARD_FAB2(SCH_1):GND
  CN32  GND            VSS<405>  @BASEBOARD_FAB2_LIB.BASEBOARD_FAB2(SCH_1):GND
  CN60  GND            VSS<404>  @BASEBOARD_FAB2_LIB.BASEBOARD_FAB2(SCH_1):GND
  CN62  GND            VSS<403>  @BASEBOARD_FAB2_LIB.BASEBOARD_FAB2(SCH_1):GND
  CN68  GND            VSS<402>  @BASEBOARD_FAB2_LIB.BASEBOARD_FAB2(SCH_1):GND
  CN78  GND            VSS<401>  @BASEBOARD_FAB2_LIB.BASEBOARD_FAB2(SCH_1):GND
  CP1  GND            VSS<400>  @BASEBOARD_FAB2_LIB.BASEBOARD_FAB2(SCH_1):GND
  H59  GND            VSS<399>  @BASEBOARD_FAB2_LIB.BASEBOARD_FAB2(SCH_1):GND
  CP25  GND            VSS<398>  @BASEBOARD_FAB2_LIB.BASEBOARD_FAB2(SCH_1):GND
  CP59  GND            VSS<397>  @BASEBOARD_FAB2_LIB.BASEBOARD_FAB2(SCH_1):GND
  CP69  GND            VSS<396>  @BASEBOARD_FAB2_LIB.BASEBOARD_FAB2(SCH_1):GND
  CP73  GND            VSS<395>  @BASEBOARD_FAB2_LIB.BASEBOARD_FAB2(SCH_1):GND
  CP75  GND            VSS<394>  @BASEBOARD_FAB2_LIB.BASEBOARD_FAB2(SCH_1):GND
  CP81  GND            VSS<393>  @BASEBOARD_FAB2_LIB.BASEBOARD_FAB2(SCH_1):GND
  CP83  GND            VSS<392>  @BASEBOARD_FAB2_LIB.BASEBOARD_FAB2(SCH_1):GND
  CR6  GND            VSS<391>  @BASEBOARD_FAB2_LIB.BASEBOARD_FAB2(SCH_1):GND
  CR10  GND            VSS<390>  @BASEBOARD_FAB2_LIB.BASEBOARD_FAB2(SCH_1):GND
  CR22  GND            VSS<389>  @BASEBOARD_FAB2_LIB.BASEBOARD_FAB2(SCH_1):GND
  CR24  GND            VSS<388>  @BASEBOARD_FAB2_LIB.BASEBOARD_FAB2(SCH_1):GND
  CR32  GND            VSS<387>  @BASEBOARD_FAB2_LIB.BASEBOARD_FAB2(SCH_1):GND
  CR58  GND            VSS<386>  @BASEBOARD_FAB2_LIB.BASEBOARD_FAB2(SCH_1):GND
  CR62  GND            VSS<385>  @BASEBOARD_FAB2_LIB.BASEBOARD_FAB2(SCH_1):GND
  CR64  GND            VSS<384>  @BASEBOARD_FAB2_LIB.BASEBOARD_FAB2(SCH_1):GND
  CR66  GND            VSS<383>  @BASEBOARD_FAB2_LIB.BASEBOARD_FAB2(SCH_1):GND
  CR68  GND            VSS<382>  @BASEBOARD_FAB2_LIB.BASEBOARD_FAB2(SCH_1):GND
  CR78  GND            VSS<381>  @BASEBOARD_FAB2_LIB.BASEBOARD_FAB2(SCH_1):GND
  CR86  GND            VSS<380>  @BASEBOARD_FAB2_LIB.BASEBOARD_FAB2(SCH_1):GND
  H57  GND            VSS<379>  @BASEBOARD_FAB2_LIB.BASEBOARD_FAB2(SCH_1):GND
  CT13  GND            VSS<378>  @BASEBOARD_FAB2_LIB.BASEBOARD_FAB2(SCH_1):GND
  CT19  GND            VSS<377>  @BASEBOARD_FAB2_LIB.BASEBOARD_FAB2(SCH_1):GND
  CT27  GND            VSS<376>  @BASEBOARD_FAB2_LIB.BASEBOARD_FAB2(SCH_1):GND
  CT29  GND            VSS<375>  @BASEBOARD_FAB2_LIB.BASEBOARD_FAB2(SCH_1):GND
  CT33  GND            VSS<374>  @BASEBOARD_FAB2_LIB.BASEBOARD_FAB2(SCH_1):GND
  CT35  GND            VSS<373>  @BASEBOARD_FAB2_LIB.BASEBOARD_FAB2(SCH_1):GND
  CT57  GND            VSS<372>  @BASEBOARD_FAB2_LIB.BASEBOARD_FAB2(SCH_1):GND
  CT73  GND            VSS<371>  @BASEBOARD_FAB2_LIB.BASEBOARD_FAB2(SCH_1):GND
  CT79  GND            VSS<370>  @BASEBOARD_FAB2_LIB.BASEBOARD_FAB2(SCH_1):GND
  CT83  GND            VSS<369>  @BASEBOARD_FAB2_LIB.BASEBOARD_FAB2(SCH_1):GND
  CT85  GND            VSS<368>  @BASEBOARD_FAB2_LIB.BASEBOARD_FAB2(SCH_1):GND
  CU4  GND            VSS<367>  @BASEBOARD_FAB2_LIB.BASEBOARD_FAB2(SCH_1):GND
  CU22  GND            VSS<366>  @BASEBOARD_FAB2_LIB.BASEBOARD_FAB2(SCH_1):GND
  CU28  GND            VSS<365>  @BASEBOARD_FAB2_LIB.BASEBOARD_FAB2(SCH_1):GND
  CU30  GND            VSS<364>  @BASEBOARD_FAB2_LIB.BASEBOARD_FAB2(SCH_1):GND
  CU34  GND            VSS<363>  @BASEBOARD_FAB2_LIB.BASEBOARD_FAB2(SCH_1):GND
  CU36  GND            VSS<362>  @BASEBOARD_FAB2_LIB.BASEBOARD_FAB2(SCH_1):GND
  CU56  GND            VSS<361>  @BASEBOARD_FAB2_LIB.BASEBOARD_FAB2(SCH_1):GND
  CU62  GND            VSS<360>  @BASEBOARD_FAB2_LIB.BASEBOARD_FAB2(SCH_1):GND
  CU68  GND            VSS<359>  @BASEBOARD_FAB2_LIB.BASEBOARD_FAB2(SCH_1):GND
  CU76  GND            VSS<358>  @BASEBOARD_FAB2_LIB.BASEBOARD_FAB2(SCH_1):GND
  CU78  GND            VSS<357>  @BASEBOARD_FAB2_LIB.BASEBOARD_FAB2(SCH_1):GND
  CU80  GND            VSS<356>  @BASEBOARD_FAB2_LIB.BASEBOARD_FAB2(SCH_1):GND
  CU82  GND            VSS<355>  @BASEBOARD_FAB2_LIB.BASEBOARD_FAB2(SCH_1):GND
  CU86  GND            VSS<354>  @BASEBOARD_FAB2_LIB.BASEBOARD_FAB2(SCH_1):GND
  CV1  GND            VSS<353>  @BASEBOARD_FAB2_LIB.BASEBOARD_FAB2(SCH_1):GND
  H55  GND            VSS<352>  @BASEBOARD_FAB2_LIB.BASEBOARD_FAB2(SCH_1):GND
  CV17  GND            VSS<351>  @BASEBOARD_FAB2_LIB.BASEBOARD_FAB2(SCH_1):GND
  CV25  GND            VSS<350>  @BASEBOARD_FAB2_LIB.BASEBOARD_FAB2(SCH_1):GND
  CV27  GND            VSS<349>  @BASEBOARD_FAB2_LIB.BASEBOARD_FAB2(SCH_1):GND
  CV31  GND            VSS<348>  @BASEBOARD_FAB2_LIB.BASEBOARD_FAB2(SCH_1):GND
  CV33  GND            VSS<347>  @BASEBOARD_FAB2_LIB.BASEBOARD_FAB2(SCH_1):GND
  CV37  GND            VSS<346>  @BASEBOARD_FAB2_LIB.BASEBOARD_FAB2(SCH_1):GND
  CV39  GND            VSS<345>  @BASEBOARD_FAB2_LIB.BASEBOARD_FAB2(SCH_1):GND
  CV41  GND            VSS<344>  @BASEBOARD_FAB2_LIB.BASEBOARD_FAB2(SCH_1):GND
  CV53  GND            VSS<343>  @BASEBOARD_FAB2_LIB.BASEBOARD_FAB2(SCH_1):GND
  CV55  GND            VSS<342>  @BASEBOARD_FAB2_LIB.BASEBOARD_FAB2(SCH_1):GND
  CV63  GND            VSS<341>  @BASEBOARD_FAB2_LIB.BASEBOARD_FAB2(SCH_1):GND
  CV67  GND            VSS<340>  @BASEBOARD_FAB2_LIB.BASEBOARD_FAB2(SCH_1):GND
  CV73  GND            VSS<339>  @BASEBOARD_FAB2_LIB.BASEBOARD_FAB2(SCH_1):GND
  CV79  GND            VSS<338>  @BASEBOARD_FAB2_LIB.BASEBOARD_FAB2(SCH_1):GND
  CV81  GND            VSS<337>  @BASEBOARD_FAB2_LIB.BASEBOARD_FAB2(SCH_1):GND
  CV83  GND            VSS<336>  @BASEBOARD_FAB2_LIB.BASEBOARD_FAB2(SCH_1):GND
  CW12  GND            VSS<335>  @BASEBOARD_FAB2_LIB.BASEBOARD_FAB2(SCH_1):GND
  CW26  GND            VSS<334>  @BASEBOARD_FAB2_LIB.BASEBOARD_FAB2(SCH_1):GND
  CW32  GND            VSS<333>  @BASEBOARD_FAB2_LIB.BASEBOARD_FAB2(SCH_1):GND
  CW38  GND            VSS<332>  @BASEBOARD_FAB2_LIB.BASEBOARD_FAB2(SCH_1):GND
  CW40  GND            VSS<331>  @BASEBOARD_FAB2_LIB.BASEBOARD_FAB2(SCH_1):GND
  CW42  GND            VSS<330>  @BASEBOARD_FAB2_LIB.BASEBOARD_FAB2(SCH_1):GND
  CW52  GND            VSS<329>  @BASEBOARD_FAB2_LIB.BASEBOARD_FAB2(SCH_1):GND
  CW54  GND            VSS<328>  @BASEBOARD_FAB2_LIB.BASEBOARD_FAB2(SCH_1):GND
  CW64  GND            VSS<327>  @BASEBOARD_FAB2_LIB.BASEBOARD_FAB2(SCH_1):GND
  CW66  GND            VSS<326>  @BASEBOARD_FAB2_LIB.BASEBOARD_FAB2(SCH_1):GND
  CW68  GND            VSS<325>  @BASEBOARD_FAB2_LIB.BASEBOARD_FAB2(SCH_1):GND
  CW74  GND            VSS<324>  @BASEBOARD_FAB2_LIB.BASEBOARD_FAB2(SCH_1):GND
  CW78  GND            VSS<323>  @BASEBOARD_FAB2_LIB.BASEBOARD_FAB2(SCH_1):GND
  CW82  GND            VSS<322>  @BASEBOARD_FAB2_LIB.BASEBOARD_FAB2(SCH_1):GND
  CY1  GND            VSS<321>  @BASEBOARD_FAB2_LIB.BASEBOARD_FAB2(SCH_1):GND
  CY9  GND            VSS<320>  @BASEBOARD_FAB2_LIB.BASEBOARD_FAB2(SCH_1):GND
  CY13  GND            VSS<319>  @BASEBOARD_FAB2_LIB.BASEBOARD_FAB2(SCH_1):GND
  CY15  GND            VSS<318>  @BASEBOARD_FAB2_LIB.BASEBOARD_FAB2(SCH_1):GND
  CY21  GND            VSS<317>  @BASEBOARD_FAB2_LIB.BASEBOARD_FAB2(SCH_1):GND
  CY41  GND            VSS<316>  @BASEBOARD_FAB2_LIB.BASEBOARD_FAB2(SCH_1):GND
  CY45  GND            VSS<315>  @BASEBOARD_FAB2_LIB.BASEBOARD_FAB2(SCH_1):GND
  CY51  GND            VSS<314>  @BASEBOARD_FAB2_LIB.BASEBOARD_FAB2(SCH_1):GND
  CY59  GND            VSS<313>  @BASEBOARD_FAB2_LIB.BASEBOARD_FAB2(SCH_1):GND
  CY61  GND            VSS<312>  @BASEBOARD_FAB2_LIB.BASEBOARD_FAB2(SCH_1):GND
  CY65  GND            VSS<311>  @BASEBOARD_FAB2_LIB.BASEBOARD_FAB2(SCH_1):GND
  CY69  GND            VSS<310>  @BASEBOARD_FAB2_LIB.BASEBOARD_FAB2(SCH_1):GND
  CY75  GND            VSS<309>  @BASEBOARD_FAB2_LIB.BASEBOARD_FAB2(SCH_1):GND
  CY77  GND            VSS<308>  @BASEBOARD_FAB2_LIB.BASEBOARD_FAB2(SCH_1):GND
  CY83  GND            VSS<307>  @BASEBOARD_FAB2_LIB.BASEBOARD_FAB2(SCH_1):GND
  CY85  GND            VSS<306>  @BASEBOARD_FAB2_LIB.BASEBOARD_FAB2(SCH_1):GND
  DA6  GND            VSS<305>  @BASEBOARD_FAB2_LIB.BASEBOARD_FAB2(SCH_1):GND
  H53  GND            VSS<304>  @BASEBOARD_FAB2_LIB.BASEBOARD_FAB2(SCH_1):GND
  DA18  GND            VSS<303>  @BASEBOARD_FAB2_LIB.BASEBOARD_FAB2(SCH_1):GND
  DA26  GND            VSS<302>  @BASEBOARD_FAB2_LIB.BASEBOARD_FAB2(SCH_1):GND
  DA28  GND            VSS<301>  @BASEBOARD_FAB2_LIB.BASEBOARD_FAB2(SCH_1):GND
  DA30  GND            VSS<300>  @BASEBOARD_FAB2_LIB.BASEBOARD_FAB2(SCH_1):GND
  DA32  GND            VSS<299>  @BASEBOARD_FAB2_LIB.BASEBOARD_FAB2(SCH_1):GND
  DA34  GND            VSS<298>  @BASEBOARD_FAB2_LIB.BASEBOARD_FAB2(SCH_1):GND
  DA36  GND            VSS<297>  @BASEBOARD_FAB2_LIB.BASEBOARD_FAB2(SCH_1):GND
  DA38  GND            VSS<296>  @BASEBOARD_FAB2_LIB.BASEBOARD_FAB2(SCH_1):GND
  DA44  GND            VSS<295>  @BASEBOARD_FAB2_LIB.BASEBOARD_FAB2(SCH_1):GND
  DA46  GND            VSS<294>  @BASEBOARD_FAB2_LIB.BASEBOARD_FAB2(SCH_1):GND

SKX_EXT_B_BGA1  I283  U5D1   [SKX_EXT_B_BGA1-IC,TBD]
  BG74  GND            VSS<613>  @BASEBOARD_FAB2_LIB.BASEBOARD_FAB2(SCH_1):GND
  BG76  GND            VSS<612>  @BASEBOARD_FAB2_LIB.BASEBOARD_FAB2(SCH_1):GND
  BG78  GND            VSS<611>  @BASEBOARD_FAB2_LIB.BASEBOARD_FAB2(SCH_1):GND
  BG80  GND            VSS<610>  @BASEBOARD_FAB2_LIB.BASEBOARD_FAB2(SCH_1):GND
  BG82  GND            VSS<609>  @BASEBOARD_FAB2_LIB.BASEBOARD_FAB2(SCH_1):GND
  BH7  GND            VSS<608>  @BASEBOARD_FAB2_LIB.BASEBOARD_FAB2(SCH_1):GND
  BH9  GND            VSS<607>  @BASEBOARD_FAB2_LIB.BASEBOARD_FAB2(SCH_1):GND
  BH11  GND            VSS<606>  @BASEBOARD_FAB2_LIB.BASEBOARD_FAB2(SCH_1):GND
  BH15  GND            VSS<605>  @BASEBOARD_FAB2_LIB.BASEBOARD_FAB2(SCH_1):GND
  BH21  GND            VSS<604>  @BASEBOARD_FAB2_LIB.BASEBOARD_FAB2(SCH_1):GND
  BJ4  GND            VSS<603>  @BASEBOARD_FAB2_LIB.BASEBOARD_FAB2(SCH_1):GND
  BJ6  GND            VSS<602>  @BASEBOARD_FAB2_LIB.BASEBOARD_FAB2(SCH_1):GND
  BK3  GND            VSS<601>  @BASEBOARD_FAB2_LIB.BASEBOARD_FAB2(SCH_1):GND
  BK7  GND            VSS<600>  @BASEBOARD_FAB2_LIB.BASEBOARD_FAB2(SCH_1):GND
  BK11  GND            VSS<599>  @BASEBOARD_FAB2_LIB.BASEBOARD_FAB2(SCH_1):GND
  BK19  GND            VSS<598>  @BASEBOARD_FAB2_LIB.BASEBOARD_FAB2(SCH_1):GND
  BL6  GND            VSS<597>  @BASEBOARD_FAB2_LIB.BASEBOARD_FAB2(SCH_1):GND
  BL10  GND            VSS<596>  @BASEBOARD_FAB2_LIB.BASEBOARD_FAB2(SCH_1):GND
  BL12  GND            VSS<595>  @BASEBOARD_FAB2_LIB.BASEBOARD_FAB2(SCH_1):GND
  P61  GND            VSS<594>  @BASEBOARD_FAB2_LIB.BASEBOARD_FAB2(SCH_1):GND
  BL22  GND            VSS<593>  @BASEBOARD_FAB2_LIB.BASEBOARD_FAB2(SCH_1):GND
  BL24  GND            VSS<592>  @BASEBOARD_FAB2_LIB.BASEBOARD_FAB2(SCH_1):GND
  BL64  GND            VSS<591>  @BASEBOARD_FAB2_LIB.BASEBOARD_FAB2(SCH_1):GND
  BL66  GND            VSS<590>  @BASEBOARD_FAB2_LIB.BASEBOARD_FAB2(SCH_1):GND
  BL68  GND            VSS<589>  @BASEBOARD_FAB2_LIB.BASEBOARD_FAB2(SCH_1):GND
  BL70  GND            VSS<588>  @BASEBOARD_FAB2_LIB.BASEBOARD_FAB2(SCH_1):GND
  BL72  GND            VSS<587>  @BASEBOARD_FAB2_LIB.BASEBOARD_FAB2(SCH_1):GND
  BL74  GND            VSS<586>  @BASEBOARD_FAB2_LIB.BASEBOARD_FAB2(SCH_1):GND
  BL76  GND            VSS<585>  @BASEBOARD_FAB2_LIB.BASEBOARD_FAB2(SCH_1):GND
  BL78  GND            VSS<584>  @BASEBOARD_FAB2_LIB.BASEBOARD_FAB2(SCH_1):GND
  BL80  GND            VSS<583>  @BASEBOARD_FAB2_LIB.BASEBOARD_FAB2(SCH_1):GND
  BL82  GND            VSS<582>  @BASEBOARD_FAB2_LIB.BASEBOARD_FAB2(SCH_1):GND
  BM9  GND            VSS<581>  @BASEBOARD_FAB2_LIB.BASEBOARD_FAB2(SCH_1):GND
  BM13  GND            VSS<580>  @BASEBOARD_FAB2_LIB.BASEBOARD_FAB2(SCH_1):GND
  BM15  GND            VSS<579>  @BASEBOARD_FAB2_LIB.BASEBOARD_FAB2(SCH_1):GND
  P59  GND            VSS<578>  @BASEBOARD_FAB2_LIB.BASEBOARD_FAB2(SCH_1):GND
  BM25  GND            VSS<577>  @BASEBOARD_FAB2_LIB.BASEBOARD_FAB2(SCH_1):GND
  BN6  GND            VSS<576>  @BASEBOARD_FAB2_LIB.BASEBOARD_FAB2(SCH_1):GND
  BN10  GND            VSS<575>  @BASEBOARD_FAB2_LIB.BASEBOARD_FAB2(SCH_1):GND
  BN20  GND            VSS<574>  @BASEBOARD_FAB2_LIB.BASEBOARD_FAB2(SCH_1):GND
  BN26  GND            VSS<573>  @BASEBOARD_FAB2_LIB.BASEBOARD_FAB2(SCH_1):GND
  BP3  GND            VSS<572>  @BASEBOARD_FAB2_LIB.BASEBOARD_FAB2(SCH_1):GND
  BP27  GND            VSS<571>  @BASEBOARD_FAB2_LIB.BASEBOARD_FAB2(SCH_1):GND
  BR6  GND            VSS<570>  @BASEBOARD_FAB2_LIB.BASEBOARD_FAB2(SCH_1):GND
  BR10  GND            VSS<569>  @BASEBOARD_FAB2_LIB.BASEBOARD_FAB2(SCH_1):GND
  BR16  GND            VSS<568>  @BASEBOARD_FAB2_LIB.BASEBOARD_FAB2(SCH_1):GND
  P57  GND            VSS<567>  @BASEBOARD_FAB2_LIB.BASEBOARD_FAB2(SCH_1):GND
  BR64  GND            VSS<566>  @BASEBOARD_FAB2_LIB.BASEBOARD_FAB2(SCH_1):GND
  BR66  GND            VSS<565>  @BASEBOARD_FAB2_LIB.BASEBOARD_FAB2(SCH_1):GND
  BR68  GND            VSS<564>  @BASEBOARD_FAB2_LIB.BASEBOARD_FAB2(SCH_1):GND
  BR70  GND            VSS<563>  @BASEBOARD_FAB2_LIB.BASEBOARD_FAB2(SCH_1):GND
  BR72  GND            VSS<562>  @BASEBOARD_FAB2_LIB.BASEBOARD_FAB2(SCH_1):GND
  BR74  GND            VSS<561>  @BASEBOARD_FAB2_LIB.BASEBOARD_FAB2(SCH_1):GND
  BR76  GND            VSS<560>  @BASEBOARD_FAB2_LIB.BASEBOARD_FAB2(SCH_1):GND
  BR78  GND            VSS<559>  @BASEBOARD_FAB2_LIB.BASEBOARD_FAB2(SCH_1):GND
  BR80  GND            VSS<558>  @BASEBOARD_FAB2_LIB.BASEBOARD_FAB2(SCH_1):GND
  BR82  GND            VSS<557>  @BASEBOARD_FAB2_LIB.BASEBOARD_FAB2(SCH_1):GND
  BT3  GND            VSS<556>  @BASEBOARD_FAB2_LIB.BASEBOARD_FAB2(SCH_1):GND
  BT5  GND            VSS<555>  @BASEBOARD_FAB2_LIB.BASEBOARD_FAB2(SCH_1):GND
  BT21  GND            VSS<554>  @BASEBOARD_FAB2_LIB.BASEBOARD_FAB2(SCH_1):GND
  BT23  GND            VSS<553>  @BASEBOARD_FAB2_LIB.BASEBOARD_FAB2(SCH_1):GND
  BT25  GND            VSS<552>  @BASEBOARD_FAB2_LIB.BASEBOARD_FAB2(SCH_1):GND
  BU8  GND            VSS<551>  @BASEBOARD_FAB2_LIB.BASEBOARD_FAB2(SCH_1):GND
  BV5  GND            VSS<550>  @BASEBOARD_FAB2_LIB.BASEBOARD_FAB2(SCH_1):GND
  BU10  GND            VSS<549>  @BASEBOARD_FAB2_LIB.BASEBOARD_FAB2(SCH_1):GND
  BV17  GND            VSS<548>  @BASEBOARD_FAB2_LIB.BASEBOARD_FAB2(SCH_1):GND
  BV25  GND            VSS<547>  @BASEBOARD_FAB2_LIB.BASEBOARD_FAB2(SCH_1):GND
  BW6  GND            VSS<546>  @BASEBOARD_FAB2_LIB.BASEBOARD_FAB2(SCH_1):GND
  P55  GND            VSS<545>  @BASEBOARD_FAB2_LIB.BASEBOARD_FAB2(SCH_1):GND
  BW12  GND            VSS<544>  @BASEBOARD_FAB2_LIB.BASEBOARD_FAB2(SCH_1):GND
  BW14  GND            VSS<543>  @BASEBOARD_FAB2_LIB.BASEBOARD_FAB2(SCH_1):GND
  BW16  GND            VSS<542>  @BASEBOARD_FAB2_LIB.BASEBOARD_FAB2(SCH_1):GND
  BW18  GND            VSS<541>  @BASEBOARD_FAB2_LIB.BASEBOARD_FAB2(SCH_1):GND
  BW26  GND            VSS<540>  @BASEBOARD_FAB2_LIB.BASEBOARD_FAB2(SCH_1):GND
  BW72  GND            VSS<539>  @BASEBOARD_FAB2_LIB.BASEBOARD_FAB2(SCH_1):GND
  BW74  GND            VSS<538>  @BASEBOARD_FAB2_LIB.BASEBOARD_FAB2(SCH_1):GND
  BW76  GND            VSS<537>  @BASEBOARD_FAB2_LIB.BASEBOARD_FAB2(SCH_1):GND
  BW78  GND            VSS<536>  @BASEBOARD_FAB2_LIB.BASEBOARD_FAB2(SCH_1):GND
  BW80  GND            VSS<535>  @BASEBOARD_FAB2_LIB.BASEBOARD_FAB2(SCH_1):GND
  BW82  GND            VSS<534>  @BASEBOARD_FAB2_LIB.BASEBOARD_FAB2(SCH_1):GND
  BY11  GND            VSS<533>  @BASEBOARD_FAB2_LIB.BASEBOARD_FAB2(SCH_1):GND
  BY13  GND            VSS<532>  @BASEBOARD_FAB2_LIB.BASEBOARD_FAB2(SCH_1):GND
  BY23  GND            VSS<531>  @BASEBOARD_FAB2_LIB.BASEBOARD_FAB2(SCH_1):GND
  BY63  GND            VSS<530>  @BASEBOARD_FAB2_LIB.BASEBOARD_FAB2(SCH_1):GND
  BY65  GND            VSS<529>  @BASEBOARD_FAB2_LIB.BASEBOARD_FAB2(SCH_1):GND
  BY67  GND            VSS<528>  @BASEBOARD_FAB2_LIB.BASEBOARD_FAB2(SCH_1):GND
  BY69  GND            VSS<527>  @BASEBOARD_FAB2_LIB.BASEBOARD_FAB2(SCH_1):GND
  BY71  GND            VSS<526>  @BASEBOARD_FAB2_LIB.BASEBOARD_FAB2(SCH_1):GND
  CA2  GND            VSS<525>  @BASEBOARD_FAB2_LIB.BASEBOARD_FAB2(SCH_1):GND
  CA6  GND            VSS<524>  @BASEBOARD_FAB2_LIB.BASEBOARD_FAB2(SCH_1):GND
  CA8  GND            VSS<523>  @BASEBOARD_FAB2_LIB.BASEBOARD_FAB2(SCH_1):GND
  CA10  GND            VSS<522>  @BASEBOARD_FAB2_LIB.BASEBOARD_FAB2(SCH_1):GND
  CA14  GND            VSS<521>  @BASEBOARD_FAB2_LIB.BASEBOARD_FAB2(SCH_1):GND
  CA18  GND            VSS<520>  @BASEBOARD_FAB2_LIB.BASEBOARD_FAB2(SCH_1):GND
  CA26  GND            VSS<519>  @BASEBOARD_FAB2_LIB.BASEBOARD_FAB2(SCH_1):GND
  CA64  GND            VSS<518>  @BASEBOARD_FAB2_LIB.BASEBOARD_FAB2(SCH_1):GND
  CA66  GND            VSS<517>  @BASEBOARD_FAB2_LIB.BASEBOARD_FAB2(SCH_1):GND
  CA68  GND            VSS<516>  @BASEBOARD_FAB2_LIB.BASEBOARD_FAB2(SCH_1):GND
  CA70  GND            VSS<515>  @BASEBOARD_FAB2_LIB.BASEBOARD_FAB2(SCH_1):GND
  CB7  GND            VSS<514>  @BASEBOARD_FAB2_LIB.BASEBOARD_FAB2(SCH_1):GND
  CB9  GND            VSS<513>  @BASEBOARD_FAB2_LIB.BASEBOARD_FAB2(SCH_1):GND
  CB27  GND            VSS<512>  @BASEBOARD_FAB2_LIB.BASEBOARD_FAB2(SCH_1):GND
  CB63  GND            VSS<511>  @BASEBOARD_FAB2_LIB.BASEBOARD_FAB2(SCH_1):GND
  CB71  GND            VSS<510>  @BASEBOARD_FAB2_LIB.BASEBOARD_FAB2(SCH_1):GND
  CC4  GND            VSS<509>  @BASEBOARD_FAB2_LIB.BASEBOARD_FAB2(SCH_1):GND
  CC16  GND            VSS<508>  @BASEBOARD_FAB2_LIB.BASEBOARD_FAB2(SCH_1):GND
  CC18  GND            VSS<507>  @BASEBOARD_FAB2_LIB.BASEBOARD_FAB2(SCH_1):GND
  CC24  GND            VSS<506>  @BASEBOARD_FAB2_LIB.BASEBOARD_FAB2(SCH_1):GND
  CC64  GND            VSS<505>  @BASEBOARD_FAB2_LIB.BASEBOARD_FAB2(SCH_1):GND
  CC72  GND            VSS<504>  @BASEBOARD_FAB2_LIB.BASEBOARD_FAB2(SCH_1):GND
  CC74  GND            VSS<503>  @BASEBOARD_FAB2_LIB.BASEBOARD_FAB2(SCH_1):GND
  CC76  GND            VSS<502>  @BASEBOARD_FAB2_LIB.BASEBOARD_FAB2(SCH_1):GND
  CC78  GND            VSS<501>  @BASEBOARD_FAB2_LIB.BASEBOARD_FAB2(SCH_1):GND
  CC80  GND            VSS<500>  @BASEBOARD_FAB2_LIB.BASEBOARD_FAB2(SCH_1):GND
  CC82  GND            VSS<499>  @BASEBOARD_FAB2_LIB.BASEBOARD_FAB2(SCH_1):GND
  CD5  GND            VSS<498>  @BASEBOARD_FAB2_LIB.BASEBOARD_FAB2(SCH_1):GND
  CD13  GND            VSS<497>  @BASEBOARD_FAB2_LIB.BASEBOARD_FAB2(SCH_1):GND
  CD63  GND            VSS<496>  @BASEBOARD_FAB2_LIB.BASEBOARD_FAB2(SCH_1):GND
  CD73  GND            VSS<495>  @BASEBOARD_FAB2_LIB.BASEBOARD_FAB2(SCH_1):GND
  CD75  GND            VSS<494>  @BASEBOARD_FAB2_LIB.BASEBOARD_FAB2(SCH_1):GND
  CD77  GND            VSS<493>  @BASEBOARD_FAB2_LIB.BASEBOARD_FAB2(SCH_1):GND
  CD79  GND            VSS<492>  @BASEBOARD_FAB2_LIB.BASEBOARD_FAB2(SCH_1):GND
  CD81  GND            VSS<491>  @BASEBOARD_FAB2_LIB.BASEBOARD_FAB2(SCH_1):GND
  CE10  GND            VSS<490>  @BASEBOARD_FAB2_LIB.BASEBOARD_FAB2(SCH_1):GND
  CE14  GND            VSS<489>  @BASEBOARD_FAB2_LIB.BASEBOARD_FAB2(SCH_1):GND
  CE20  GND            VSS<488>  @BASEBOARD_FAB2_LIB.BASEBOARD_FAB2(SCH_1):GND
  CE26  GND            VSS<487>  @BASEBOARD_FAB2_LIB.BASEBOARD_FAB2(SCH_1):GND
  CE62  GND            VSS<486>  @BASEBOARD_FAB2_LIB.BASEBOARD_FAB2(SCH_1):GND
  CE70  GND            VSS<485>  @BASEBOARD_FAB2_LIB.BASEBOARD_FAB2(SCH_1):GND
  CE82  GND            VSS<484>  @BASEBOARD_FAB2_LIB.BASEBOARD_FAB2(SCH_1):GND
  P53  GND            VSS<483>  @BASEBOARD_FAB2_LIB.BASEBOARD_FAB2(SCH_1):GND
  CF9  GND            VSS<482>  @BASEBOARD_FAB2_LIB.BASEBOARD_FAB2(SCH_1):GND
  CF63  GND            VSS<481>  @BASEBOARD_FAB2_LIB.BASEBOARD_FAB2(SCH_1):GND
  CF69  GND            VSS<480>  @BASEBOARD_FAB2_LIB.BASEBOARD_FAB2(SCH_1):GND
  CF71  GND            VSS<479>  @BASEBOARD_FAB2_LIB.BASEBOARD_FAB2(SCH_1):GND
  CF77  GND            VSS<478>  @BASEBOARD_FAB2_LIB.BASEBOARD_FAB2(SCH_1):GND
  CF83  GND            VSS<477>  @BASEBOARD_FAB2_LIB.BASEBOARD_FAB2(SCH_1):GND
  P51  GND            VSS<476>  @BASEBOARD_FAB2_LIB.BASEBOARD_FAB2(SCH_1):GND
  CG18  GND            VSS<475>  @BASEBOARD_FAB2_LIB.BASEBOARD_FAB2(SCH_1):GND
  CG22  GND            VSS<474>  @BASEBOARD_FAB2_LIB.BASEBOARD_FAB2(SCH_1):GND
  CG62  GND            VSS<473>  @BASEBOARD_FAB2_LIB.BASEBOARD_FAB2(SCH_1):GND
  CG68  GND            VSS<472>  @BASEBOARD_FAB2_LIB.BASEBOARD_FAB2(SCH_1):GND
  CG72  GND            VSS<471>  @BASEBOARD_FAB2_LIB.BASEBOARD_FAB2(SCH_1):GND
  CG80  GND            VSS<470>  @BASEBOARD_FAB2_LIB.BASEBOARD_FAB2(SCH_1):GND
  CH1  GND            VSS<469>  @BASEBOARD_FAB2_LIB.BASEBOARD_FAB2(SCH_1):GND
  CH3  GND            VSS<468>  @BASEBOARD_FAB2_LIB.BASEBOARD_FAB2(SCH_1):GND
  CH15  GND            VSS<467>  @BASEBOARD_FAB2_LIB.BASEBOARD_FAB2(SCH_1):GND
  CH19  GND            VSS<466>  @BASEBOARD_FAB2_LIB.BASEBOARD_FAB2(SCH_1):GND
  CH63  GND            VSS<465>  @BASEBOARD_FAB2_LIB.BASEBOARD_FAB2(SCH_1):GND
  CH67  GND            VSS<464>  @BASEBOARD_FAB2_LIB.BASEBOARD_FAB2(SCH_1):GND
  CH73  GND            VSS<463>  @BASEBOARD_FAB2_LIB.BASEBOARD_FAB2(SCH_1):GND
  CH79  GND            VSS<462>  @BASEBOARD_FAB2_LIB.BASEBOARD_FAB2(SCH_1):GND
  CH81  GND            VSS<461>  @BASEBOARD_FAB2_LIB.BASEBOARD_FAB2(SCH_1):GND
  CH83  GND            VSS<460>  @BASEBOARD_FAB2_LIB.BASEBOARD_FAB2(SCH_1):GND
  CJ2  GND            VSS<459>  @BASEBOARD_FAB2_LIB.BASEBOARD_FAB2(SCH_1):GND
  CJ6  GND            VSS<458>  @BASEBOARD_FAB2_LIB.BASEBOARD_FAB2(SCH_1):GND
  CJ8  GND            VSS<457>  @BASEBOARD_FAB2_LIB.BASEBOARD_FAB2(SCH_1):GND
  CJ10  GND            VSS<456>  @BASEBOARD_FAB2_LIB.BASEBOARD_FAB2(SCH_1):GND
  CJ12  GND            VSS<455>  @BASEBOARD_FAB2_LIB.BASEBOARD_FAB2(SCH_1):GND
  P49  GND            VSS<454>  @BASEBOARD_FAB2_LIB.BASEBOARD_FAB2(SCH_1):GND

SKX_EXT_B_BGA1  I23  U5D1   [SKX_EXT_B_BGA1-IC,TBD]
  AL76  GND            VSS<773>  @BASEBOARD_FAB2_LIB.BASEBOARD_FAB2(SCH_1):GND
  AL78  GND            VSS<772>  @BASEBOARD_FAB2_LIB.BASEBOARD_FAB2(SCH_1):GND
  AL80  GND            VSS<771>  @BASEBOARD_FAB2_LIB.BASEBOARD_FAB2(SCH_1):GND
  AL82  GND            VSS<770>  @BASEBOARD_FAB2_LIB.BASEBOARD_FAB2(SCH_1):GND
  AL86  GND            VSS<769>  @BASEBOARD_FAB2_LIB.BASEBOARD_FAB2(SCH_1):GND
  AM1  GND            VSS<768>  @BASEBOARD_FAB2_LIB.BASEBOARD_FAB2(SCH_1):GND
  AC50  GND            VSS<767>  @BASEBOARD_FAB2_LIB.BASEBOARD_FAB2(SCH_1):GND
  AM31  GND            VSS<766>  @BASEBOARD_FAB2_LIB.BASEBOARD_FAB2(SCH_1):GND
  AM57  GND            VSS<765>  @BASEBOARD_FAB2_LIB.BASEBOARD_FAB2(SCH_1):GND
  AM63  GND            VSS<764>  @BASEBOARD_FAB2_LIB.BASEBOARD_FAB2(SCH_1):GND
  AM69  GND            VSS<763>  @BASEBOARD_FAB2_LIB.BASEBOARD_FAB2(SCH_1):GND
  AM73  GND            VSS<762>  @BASEBOARD_FAB2_LIB.BASEBOARD_FAB2(SCH_1):GND
  AM79  GND            VSS<761>  @BASEBOARD_FAB2_LIB.BASEBOARD_FAB2(SCH_1):GND
  AM83  GND            VSS<760>  @BASEBOARD_FAB2_LIB.BASEBOARD_FAB2(SCH_1):GND
  AN2  GND            VSS<759>  @BASEBOARD_FAB2_LIB.BASEBOARD_FAB2(SCH_1):GND
  AN6  GND            VSS<758>  @BASEBOARD_FAB2_LIB.BASEBOARD_FAB2(SCH_1):GND
  AN28  GND            VSS<757>  @BASEBOARD_FAB2_LIB.BASEBOARD_FAB2(SCH_1):GND
  AN58  GND            VSS<756>  @BASEBOARD_FAB2_LIB.BASEBOARD_FAB2(SCH_1):GND
  AN78  GND            VSS<755>  @BASEBOARD_FAB2_LIB.BASEBOARD_FAB2(SCH_1):GND
  AP5  GND            VSS<754>  @BASEBOARD_FAB2_LIB.BASEBOARD_FAB2(SCH_1):GND
  AP9  GND            VSS<753>  @BASEBOARD_FAB2_LIB.BASEBOARD_FAB2(SCH_1):GND
  AP13  GND            VSS<752>  @BASEBOARD_FAB2_LIB.BASEBOARD_FAB2(SCH_1):GND
  AP19  GND            VSS<751>  @BASEBOARD_FAB2_LIB.BASEBOARD_FAB2(SCH_1):GND
  AP31  GND            VSS<750>  @BASEBOARD_FAB2_LIB.BASEBOARD_FAB2(SCH_1):GND
  AP59  GND            VSS<749>  @BASEBOARD_FAB2_LIB.BASEBOARD_FAB2(SCH_1):GND
  AP63  GND            VSS<748>  @BASEBOARD_FAB2_LIB.BASEBOARD_FAB2(SCH_1):GND
  AP65  GND            VSS<747>  @BASEBOARD_FAB2_LIB.BASEBOARD_FAB2(SCH_1):GND
  AP67  GND            VSS<746>  @BASEBOARD_FAB2_LIB.BASEBOARD_FAB2(SCH_1):GND
  AP69  GND            VSS<745>  @BASEBOARD_FAB2_LIB.BASEBOARD_FAB2(SCH_1):GND
  AP73  GND            VSS<744>  @BASEBOARD_FAB2_LIB.BASEBOARD_FAB2(SCH_1):GND
  AP75  GND            VSS<743>  @BASEBOARD_FAB2_LIB.BASEBOARD_FAB2(SCH_1):GND
  AP81  GND            VSS<742>  @BASEBOARD_FAB2_LIB.BASEBOARD_FAB2(SCH_1):GND
  AP83  GND            VSS<741>  @BASEBOARD_FAB2_LIB.BASEBOARD_FAB2(SCH_1):GND
  AP85  GND            VSS<740>  @BASEBOARD_FAB2_LIB.BASEBOARD_FAB2(SCH_1):GND
  AR10  GND            VSS<739>  @BASEBOARD_FAB2_LIB.BASEBOARD_FAB2(SCH_1):GND
  AR24  GND            VSS<738>  @BASEBOARD_FAB2_LIB.BASEBOARD_FAB2(SCH_1):GND
  AR30  GND            VSS<737>  @BASEBOARD_FAB2_LIB.BASEBOARD_FAB2(SCH_1):GND
  AR60  GND            VSS<736>  @BASEBOARD_FAB2_LIB.BASEBOARD_FAB2(SCH_1):GND
  AR72  GND            VSS<735>  @BASEBOARD_FAB2_LIB.BASEBOARD_FAB2(SCH_1):GND
  AR78  GND            VSS<734>  @BASEBOARD_FAB2_LIB.BASEBOARD_FAB2(SCH_1):GND
  AC48  GND            VSS<733>  @BASEBOARD_FAB2_LIB.BASEBOARD_FAB2(SCH_1):GND
  P63  GND            VSS<732>  @BASEBOARD_FAB2_LIB.BASEBOARD_FAB2(SCH_1):GND
  AT15  GND            VSS<731>  @BASEBOARD_FAB2_LIB.BASEBOARD_FAB2(SCH_1):GND
  AT17  GND            VSS<730>  @BASEBOARD_FAB2_LIB.BASEBOARD_FAB2(SCH_1):GND
  AT21  GND            VSS<729>  @BASEBOARD_FAB2_LIB.BASEBOARD_FAB2(SCH_1):GND
  AT27  GND            VSS<728>  @BASEBOARD_FAB2_LIB.BASEBOARD_FAB2(SCH_1):GND
  AT61  GND            VSS<727>  @BASEBOARD_FAB2_LIB.BASEBOARD_FAB2(SCH_1):GND
  AT63  GND            VSS<726>  @BASEBOARD_FAB2_LIB.BASEBOARD_FAB2(SCH_1):GND
  AT69  GND            VSS<725>  @BASEBOARD_FAB2_LIB.BASEBOARD_FAB2(SCH_1):GND
  AT73  GND            VSS<724>  @BASEBOARD_FAB2_LIB.BASEBOARD_FAB2(SCH_1):GND
  AT77  GND            VSS<723>  @BASEBOARD_FAB2_LIB.BASEBOARD_FAB2(SCH_1):GND
  AT83  GND            VSS<722>  @BASEBOARD_FAB2_LIB.BASEBOARD_FAB2(SCH_1):GND
  AT85  GND            VSS<721>  @BASEBOARD_FAB2_LIB.BASEBOARD_FAB2(SCH_1):GND
  AU2  GND            VSS<720>  @BASEBOARD_FAB2_LIB.BASEBOARD_FAB2(SCH_1):GND
  AU6  GND            VSS<719>  @BASEBOARD_FAB2_LIB.BASEBOARD_FAB2(SCH_1):GND
  AU26  GND            VSS<718>  @BASEBOARD_FAB2_LIB.BASEBOARD_FAB2(SCH_1):GND
  AU28  GND            VSS<717>  @BASEBOARD_FAB2_LIB.BASEBOARD_FAB2(SCH_1):GND
  AU62  GND            VSS<716>  @BASEBOARD_FAB2_LIB.BASEBOARD_FAB2(SCH_1):GND
  AU64  GND            VSS<715>  @BASEBOARD_FAB2_LIB.BASEBOARD_FAB2(SCH_1):GND
  AU68  GND            VSS<714>  @BASEBOARD_FAB2_LIB.BASEBOARD_FAB2(SCH_1):GND
  AU74  GND            VSS<713>  @BASEBOARD_FAB2_LIB.BASEBOARD_FAB2(SCH_1):GND
  AU76  GND            VSS<712>  @BASEBOARD_FAB2_LIB.BASEBOARD_FAB2(SCH_1):GND
  AU78  GND            VSS<711>  @BASEBOARD_FAB2_LIB.BASEBOARD_FAB2(SCH_1):GND
  AU80  GND            VSS<710>  @BASEBOARD_FAB2_LIB.BASEBOARD_FAB2(SCH_1):GND
  AU84  GND            VSS<709>  @BASEBOARD_FAB2_LIB.BASEBOARD_FAB2(SCH_1):GND
  AU86  GND            VSS<708>  @BASEBOARD_FAB2_LIB.BASEBOARD_FAB2(SCH_1):GND
  AV1  GND            VSS<707>  @BASEBOARD_FAB2_LIB.BASEBOARD_FAB2(SCH_1):GND
  AV3  GND            VSS<706>  @BASEBOARD_FAB2_LIB.BASEBOARD_FAB2(SCH_1):GND
  AV7  GND            VSS<705>  @BASEBOARD_FAB2_LIB.BASEBOARD_FAB2(SCH_1):GND
  AV11  GND            VSS<704>  @BASEBOARD_FAB2_LIB.BASEBOARD_FAB2(SCH_1):GND
  AV13  GND            VSS<703>  @BASEBOARD_FAB2_LIB.BASEBOARD_FAB2(SCH_1):GND
  AV19  GND            VSS<702>  @BASEBOARD_FAB2_LIB.BASEBOARD_FAB2(SCH_1):GND
  AV23  GND            VSS<701>  @BASEBOARD_FAB2_LIB.BASEBOARD_FAB2(SCH_1):GND
  AV25  GND            VSS<700>  @BASEBOARD_FAB2_LIB.BASEBOARD_FAB2(SCH_1):GND
  AV63  GND            VSS<699>  @BASEBOARD_FAB2_LIB.BASEBOARD_FAB2(SCH_1):GND
  AV65  GND            VSS<698>  @BASEBOARD_FAB2_LIB.BASEBOARD_FAB2(SCH_1):GND
  AV67  GND            VSS<697>  @BASEBOARD_FAB2_LIB.BASEBOARD_FAB2(SCH_1):GND
  AV75  GND            VSS<696>  @BASEBOARD_FAB2_LIB.BASEBOARD_FAB2(SCH_1):GND
  AV83  GND            VSS<695>  @BASEBOARD_FAB2_LIB.BASEBOARD_FAB2(SCH_1):GND
  AW2  GND            VSS<694>  @BASEBOARD_FAB2_LIB.BASEBOARD_FAB2(SCH_1):GND
  AW10  GND            VSS<693>  @BASEBOARD_FAB2_LIB.BASEBOARD_FAB2(SCH_1):GND
  AW62  GND            VSS<692>  @BASEBOARD_FAB2_LIB.BASEBOARD_FAB2(SCH_1):GND
  AW66  GND            VSS<691>  @BASEBOARD_FAB2_LIB.BASEBOARD_FAB2(SCH_1):GND
  AW68  GND            VSS<690>  @BASEBOARD_FAB2_LIB.BASEBOARD_FAB2(SCH_1):GND
  AW70  GND            VSS<689>  @BASEBOARD_FAB2_LIB.BASEBOARD_FAB2(SCH_1):GND
  AW72  GND            VSS<688>  @BASEBOARD_FAB2_LIB.BASEBOARD_FAB2(SCH_1):GND
  AW74  GND            VSS<687>  @BASEBOARD_FAB2_LIB.BASEBOARD_FAB2(SCH_1):GND
  AW78  GND            VSS<686>  @BASEBOARD_FAB2_LIB.BASEBOARD_FAB2(SCH_1):GND
  AW82  GND            VSS<685>  @BASEBOARD_FAB2_LIB.BASEBOARD_FAB2(SCH_1):GND
  AW84  GND            VSS<684>  @BASEBOARD_FAB2_LIB.BASEBOARD_FAB2(SCH_1):GND
  AY5  GND            VSS<683>  @BASEBOARD_FAB2_LIB.BASEBOARD_FAB2(SCH_1):GND
  AY15  GND            VSS<682>  @BASEBOARD_FAB2_LIB.BASEBOARD_FAB2(SCH_1):GND
  AY17  GND            VSS<681>  @BASEBOARD_FAB2_LIB.BASEBOARD_FAB2(SCH_1):GND
  AY21  GND            VSS<680>  @BASEBOARD_FAB2_LIB.BASEBOARD_FAB2(SCH_1):GND
  AY23  GND            VSS<679>  @BASEBOARD_FAB2_LIB.BASEBOARD_FAB2(SCH_1):GND
  AY25  GND            VSS<678>  @BASEBOARD_FAB2_LIB.BASEBOARD_FAB2(SCH_1):GND
  AY63  GND            VSS<677>  @BASEBOARD_FAB2_LIB.BASEBOARD_FAB2(SCH_1):GND
  AY79  GND            VSS<676>  @BASEBOARD_FAB2_LIB.BASEBOARD_FAB2(SCH_1):GND
  AY81  GND            VSS<675>  @BASEBOARD_FAB2_LIB.BASEBOARD_FAB2(SCH_1):GND
  BA2  GND            VSS<674>  @BASEBOARD_FAB2_LIB.BASEBOARD_FAB2(SCH_1):GND
  BA6  GND            VSS<673>  @BASEBOARD_FAB2_LIB.BASEBOARD_FAB2(SCH_1):GND
  BA12  GND            VSS<672>  @BASEBOARD_FAB2_LIB.BASEBOARD_FAB2(SCH_1):GND
  BA62  GND            VSS<671>  @BASEBOARD_FAB2_LIB.BASEBOARD_FAB2(SCH_1):GND
  BA68  GND            VSS<670>  @BASEBOARD_FAB2_LIB.BASEBOARD_FAB2(SCH_1):GND
  BA74  GND            VSS<669>  @BASEBOARD_FAB2_LIB.BASEBOARD_FAB2(SCH_1):GND
  BA80  GND            VSS<668>  @BASEBOARD_FAB2_LIB.BASEBOARD_FAB2(SCH_1):GND
  BA84  GND            VSS<667>  @BASEBOARD_FAB2_LIB.BASEBOARD_FAB2(SCH_1):GND
  BB19  GND            VSS<666>  @BASEBOARD_FAB2_LIB.BASEBOARD_FAB2(SCH_1):GND
  BB23  GND            VSS<665>  @BASEBOARD_FAB2_LIB.BASEBOARD_FAB2(SCH_1):GND
  BB63  GND            VSS<664>  @BASEBOARD_FAB2_LIB.BASEBOARD_FAB2(SCH_1):GND
  BB69  GND            VSS<663>  @BASEBOARD_FAB2_LIB.BASEBOARD_FAB2(SCH_1):GND
  BB73  GND            VSS<662>  @BASEBOARD_FAB2_LIB.BASEBOARD_FAB2(SCH_1):GND
  BB75  GND            VSS<661>  @BASEBOARD_FAB2_LIB.BASEBOARD_FAB2(SCH_1):GND
  BB77  GND            VSS<660>  @BASEBOARD_FAB2_LIB.BASEBOARD_FAB2(SCH_1):GND
  BB79  GND            VSS<659>  @BASEBOARD_FAB2_LIB.BASEBOARD_FAB2(SCH_1):GND
  BB81  GND            VSS<658>  @BASEBOARD_FAB2_LIB.BASEBOARD_FAB2(SCH_1):GND
  BB83  GND            VSS<657>  @BASEBOARD_FAB2_LIB.BASEBOARD_FAB2(SCH_1):GND
  BC4  GND            VSS<656>  @BASEBOARD_FAB2_LIB.BASEBOARD_FAB2(SCH_1):GND
  BC8  GND            VSS<655>  @BASEBOARD_FAB2_LIB.BASEBOARD_FAB2(SCH_1):GND
  BC12  GND            VSS<654>  @BASEBOARD_FAB2_LIB.BASEBOARD_FAB2(SCH_1):GND
  BC16  GND            VSS<653>  @BASEBOARD_FAB2_LIB.BASEBOARD_FAB2(SCH_1):GND
  BC70  GND            VSS<652>  @BASEBOARD_FAB2_LIB.BASEBOARD_FAB2(SCH_1):GND
  BC72  GND            VSS<651>  @BASEBOARD_FAB2_LIB.BASEBOARD_FAB2(SCH_1):GND
  BC74  GND            VSS<650>  @BASEBOARD_FAB2_LIB.BASEBOARD_FAB2(SCH_1):GND
  BC76  GND            VSS<649>  @BASEBOARD_FAB2_LIB.BASEBOARD_FAB2(SCH_1):GND
  BC78  GND            VSS<648>  @BASEBOARD_FAB2_LIB.BASEBOARD_FAB2(SCH_1):GND
  BC80  GND            VSS<647>  @BASEBOARD_FAB2_LIB.BASEBOARD_FAB2(SCH_1):GND
  BC82  GND            VSS<646>  @BASEBOARD_FAB2_LIB.BASEBOARD_FAB2(SCH_1):GND
  BD5  GND            VSS<645>  @BASEBOARD_FAB2_LIB.BASEBOARD_FAB2(SCH_1):GND
  BD11  GND            VSS<644>  @BASEBOARD_FAB2_LIB.BASEBOARD_FAB2(SCH_1):GND
  BD15  GND            VSS<643>  @BASEBOARD_FAB2_LIB.BASEBOARD_FAB2(SCH_1):GND
  BD21  GND            VSS<642>  @BASEBOARD_FAB2_LIB.BASEBOARD_FAB2(SCH_1):GND
  BD27  GND            VSS<641>  @BASEBOARD_FAB2_LIB.BASEBOARD_FAB2(SCH_1):GND
  BD63  GND            VSS<640>  @BASEBOARD_FAB2_LIB.BASEBOARD_FAB2(SCH_1):GND
  BD71  GND            VSS<639>  @BASEBOARD_FAB2_LIB.BASEBOARD_FAB2(SCH_1):GND
  BE4  GND            VSS<638>  @BASEBOARD_FAB2_LIB.BASEBOARD_FAB2(SCH_1):GND
  BE6  GND            VSS<637>  @BASEBOARD_FAB2_LIB.BASEBOARD_FAB2(SCH_1):GND
  BE8  GND            VSS<636>  @BASEBOARD_FAB2_LIB.BASEBOARD_FAB2(SCH_1):GND
  BE10  GND            VSS<635>  @BASEBOARD_FAB2_LIB.BASEBOARD_FAB2(SCH_1):GND
  BE26  GND            VSS<634>  @BASEBOARD_FAB2_LIB.BASEBOARD_FAB2(SCH_1):GND
  BE64  GND            VSS<633>  @BASEBOARD_FAB2_LIB.BASEBOARD_FAB2(SCH_1):GND
  BE66  GND            VSS<632>  @BASEBOARD_FAB2_LIB.BASEBOARD_FAB2(SCH_1):GND
  BE68  GND            VSS<631>  @BASEBOARD_FAB2_LIB.BASEBOARD_FAB2(SCH_1):GND
  BE70  GND            VSS<630>  @BASEBOARD_FAB2_LIB.BASEBOARD_FAB2(SCH_1):GND
  BF9  GND            VSS<629>  @BASEBOARD_FAB2_LIB.BASEBOARD_FAB2(SCH_1):GND
  BF15  GND            VSS<628>  @BASEBOARD_FAB2_LIB.BASEBOARD_FAB2(SCH_1):GND
  BF17  GND            VSS<627>  @BASEBOARD_FAB2_LIB.BASEBOARD_FAB2(SCH_1):GND
  BF19  GND            VSS<626>  @BASEBOARD_FAB2_LIB.BASEBOARD_FAB2(SCH_1):GND
  BF25  GND            VSS<625>  @BASEBOARD_FAB2_LIB.BASEBOARD_FAB2(SCH_1):GND
  BF63  GND            VSS<624>  @BASEBOARD_FAB2_LIB.BASEBOARD_FAB2(SCH_1):GND
  BF65  GND            VSS<623>  @BASEBOARD_FAB2_LIB.BASEBOARD_FAB2(SCH_1):GND
  BF67  GND            VSS<622>  @BASEBOARD_FAB2_LIB.BASEBOARD_FAB2(SCH_1):GND
  BF69  GND            VSS<621>  @BASEBOARD_FAB2_LIB.BASEBOARD_FAB2(SCH_1):GND
  BF71  GND            VSS<620>  @BASEBOARD_FAB2_LIB.BASEBOARD_FAB2(SCH_1):GND
  BG6  GND            VSS<619>  @BASEBOARD_FAB2_LIB.BASEBOARD_FAB2(SCH_1):GND
  BG8  GND            VSS<618>  @BASEBOARD_FAB2_LIB.BASEBOARD_FAB2(SCH_1):GND
  BG10  GND            VSS<617>  @BASEBOARD_FAB2_LIB.BASEBOARD_FAB2(SCH_1):GND
  BG22  GND            VSS<616>  @BASEBOARD_FAB2_LIB.BASEBOARD_FAB2(SCH_1):GND
  BG24  GND            VSS<615>  @BASEBOARD_FAB2_LIB.BASEBOARD_FAB2(SCH_1):GND
  BG72  GND            VSS<614>  @BASEBOARD_FAB2_LIB.BASEBOARD_FAB2(SCH_1):GND

SKX_EXT_B_BGA1  I22  U5D1   [SKX_EXT_B_BGA1-IC,TBD]
  AA18  GND            VSS<933>  @BASEBOARD_FAB2_LIB.BASEBOARD_FAB2(SCH_1):GND
  AA22  GND            VSS<932>  @BASEBOARD_FAB2_LIB.BASEBOARD_FAB2(SCH_1):GND
  AA24  GND            VSS<931>  @BASEBOARD_FAB2_LIB.BASEBOARD_FAB2(SCH_1):GND
  AA30  GND            VSS<930>  @BASEBOARD_FAB2_LIB.BASEBOARD_FAB2(SCH_1):GND
  AA36  GND            VSS<929>  @BASEBOARD_FAB2_LIB.BASEBOARD_FAB2(SCH_1):GND
  AA42  GND            VSS<928>  @BASEBOARD_FAB2_LIB.BASEBOARD_FAB2(SCH_1):GND
  AA64  GND            VSS<927>  @BASEBOARD_FAB2_LIB.BASEBOARD_FAB2(SCH_1):GND
  AA66  GND            VSS<926>  @BASEBOARD_FAB2_LIB.BASEBOARD_FAB2(SCH_1):GND
  AA68  GND            VSS<925>  @BASEBOARD_FAB2_LIB.BASEBOARD_FAB2(SCH_1):GND
  AA76  GND            VSS<924>  @BASEBOARD_FAB2_LIB.BASEBOARD_FAB2(SCH_1):GND
  AA78  GND            VSS<923>  @BASEBOARD_FAB2_LIB.BASEBOARD_FAB2(SCH_1):GND
  AA80  GND            VSS<922>  @BASEBOARD_FAB2_LIB.BASEBOARD_FAB2(SCH_1):GND
  AA82  GND            VSS<921>  @BASEBOARD_FAB2_LIB.BASEBOARD_FAB2(SCH_1):GND
  AB1  GND            VSS<920>  @BASEBOARD_FAB2_LIB.BASEBOARD_FAB2(SCH_1):GND
  AB5  GND            VSS<919>  @BASEBOARD_FAB2_LIB.BASEBOARD_FAB2(SCH_1):GND
  AB11  GND            VSS<918>  @BASEBOARD_FAB2_LIB.BASEBOARD_FAB2(SCH_1):GND
  AB21  GND            VSS<917>  @BASEBOARD_FAB2_LIB.BASEBOARD_FAB2(SCH_1):GND
  AB23  GND            VSS<916>  @BASEBOARD_FAB2_LIB.BASEBOARD_FAB2(SCH_1):GND
  AB25  GND            VSS<915>  @BASEBOARD_FAB2_LIB.BASEBOARD_FAB2(SCH_1):GND
  AB29  GND            VSS<914>  @BASEBOARD_FAB2_LIB.BASEBOARD_FAB2(SCH_1):GND
  AB31  GND            VSS<913>  @BASEBOARD_FAB2_LIB.BASEBOARD_FAB2(SCH_1):GND
  AB35  GND            VSS<912>  @BASEBOARD_FAB2_LIB.BASEBOARD_FAB2(SCH_1):GND
  AB37  GND            VSS<911>  @BASEBOARD_FAB2_LIB.BASEBOARD_FAB2(SCH_1):GND
  AB41  GND            VSS<910>  @BASEBOARD_FAB2_LIB.BASEBOARD_FAB2(SCH_1):GND
  AB65  GND            VSS<909>  @BASEBOARD_FAB2_LIB.BASEBOARD_FAB2(SCH_1):GND
  AB69  GND            VSS<908>  @BASEBOARD_FAB2_LIB.BASEBOARD_FAB2(SCH_1):GND
  AB73  GND            VSS<907>  @BASEBOARD_FAB2_LIB.BASEBOARD_FAB2(SCH_1):GND
  AB79  GND            VSS<906>  @BASEBOARD_FAB2_LIB.BASEBOARD_FAB2(SCH_1):GND
  AB83  GND            VSS<905>  @BASEBOARD_FAB2_LIB.BASEBOARD_FAB2(SCH_1):GND
  AB85  GND            VSS<904>  @BASEBOARD_FAB2_LIB.BASEBOARD_FAB2(SCH_1):GND
  AC18  GND            VSS<903>  @BASEBOARD_FAB2_LIB.BASEBOARD_FAB2(SCH_1):GND
  AC22  GND            VSS<902>  @BASEBOARD_FAB2_LIB.BASEBOARD_FAB2(SCH_1):GND
  AC26  GND            VSS<901>  @BASEBOARD_FAB2_LIB.BASEBOARD_FAB2(SCH_1):GND
  AC28  GND            VSS<900>  @BASEBOARD_FAB2_LIB.BASEBOARD_FAB2(SCH_1):GND
  AC32  GND            VSS<899>  @BASEBOARD_FAB2_LIB.BASEBOARD_FAB2(SCH_1):GND
  AC34  GND            VSS<898>  @BASEBOARD_FAB2_LIB.BASEBOARD_FAB2(SCH_1):GND
  AC38  GND            VSS<897>  @BASEBOARD_FAB2_LIB.BASEBOARD_FAB2(SCH_1):GND
  AC40  GND            VSS<896>  @BASEBOARD_FAB2_LIB.BASEBOARD_FAB2(SCH_1):GND
  AC64  GND            VSS<895>  @BASEBOARD_FAB2_LIB.BASEBOARD_FAB2(SCH_1):GND
  AC70  GND            VSS<894>  @BASEBOARD_FAB2_LIB.BASEBOARD_FAB2(SCH_1):GND
  AC72  GND            VSS<893>  @BASEBOARD_FAB2_LIB.BASEBOARD_FAB2(SCH_1):GND
  AC78  GND            VSS<892>  @BASEBOARD_FAB2_LIB.BASEBOARD_FAB2(SCH_1):GND
  AC84  GND            VSS<891>  @BASEBOARD_FAB2_LIB.BASEBOARD_FAB2(SCH_1):GND
  AC86  GND            VSS<890>  @BASEBOARD_FAB2_LIB.BASEBOARD_FAB2(SCH_1):GND
  AD3  GND            VSS<889>  @BASEBOARD_FAB2_LIB.BASEBOARD_FAB2(SCH_1):GND
  AD7  GND            VSS<888>  @BASEBOARD_FAB2_LIB.BASEBOARD_FAB2(SCH_1):GND
  AD9  GND            VSS<887>  @BASEBOARD_FAB2_LIB.BASEBOARD_FAB2(SCH_1):GND
  AD11  GND            VSS<886>  @BASEBOARD_FAB2_LIB.BASEBOARD_FAB2(SCH_1):GND
  AD13  GND            VSS<885>  @BASEBOARD_FAB2_LIB.BASEBOARD_FAB2(SCH_1):GND
  AD15  GND            VSS<884>  @BASEBOARD_FAB2_LIB.BASEBOARD_FAB2(SCH_1):GND
  AD19  GND            VSS<883>  @BASEBOARD_FAB2_LIB.BASEBOARD_FAB2(SCH_1):GND
  AD21  GND            VSS<882>  @BASEBOARD_FAB2_LIB.BASEBOARD_FAB2(SCH_1):GND
  AD27  GND            VSS<881>  @BASEBOARD_FAB2_LIB.BASEBOARD_FAB2(SCH_1):GND
  AD33  GND            VSS<880>  @BASEBOARD_FAB2_LIB.BASEBOARD_FAB2(SCH_1):GND
  AD39  GND            VSS<879>  @BASEBOARD_FAB2_LIB.BASEBOARD_FAB2(SCH_1):GND
  AD43  GND            VSS<878>  @BASEBOARD_FAB2_LIB.BASEBOARD_FAB2(SCH_1):GND
  AD71  GND            VSS<877>  @BASEBOARD_FAB2_LIB.BASEBOARD_FAB2(SCH_1):GND
  AD73  GND            VSS<876>  @BASEBOARD_FAB2_LIB.BASEBOARD_FAB2(SCH_1):GND
  AD75  GND            VSS<875>  @BASEBOARD_FAB2_LIB.BASEBOARD_FAB2(SCH_1):GND
  AD81  GND            VSS<874>  @BASEBOARD_FAB2_LIB.BASEBOARD_FAB2(SCH_1):GND
  AD83  GND            VSS<873>  @BASEBOARD_FAB2_LIB.BASEBOARD_FAB2(SCH_1):GND
  AD85  GND            VSS<872>  @BASEBOARD_FAB2_LIB.BASEBOARD_FAB2(SCH_1):GND
  AE4  GND            VSS<871>  @BASEBOARD_FAB2_LIB.BASEBOARD_FAB2(SCH_1):GND
  AE8  GND            VSS<870>  @BASEBOARD_FAB2_LIB.BASEBOARD_FAB2(SCH_1):GND
  AC54  GND            VSS<869>  @BASEBOARD_FAB2_LIB.BASEBOARD_FAB2(SCH_1):GND
  AE16  GND            VSS<868>  @BASEBOARD_FAB2_LIB.BASEBOARD_FAB2(SCH_1):GND
  AE38  GND            VSS<867>  @BASEBOARD_FAB2_LIB.BASEBOARD_FAB2(SCH_1):GND
  AE40  GND            VSS<866>  @BASEBOARD_FAB2_LIB.BASEBOARD_FAB2(SCH_1):GND
  AE42  GND            VSS<865>  @BASEBOARD_FAB2_LIB.BASEBOARD_FAB2(SCH_1):GND
  AE64  GND            VSS<864>  @BASEBOARD_FAB2_LIB.BASEBOARD_FAB2(SCH_1):GND
  AE66  GND            VSS<863>  @BASEBOARD_FAB2_LIB.BASEBOARD_FAB2(SCH_1):GND
  AE68  GND            VSS<862>  @BASEBOARD_FAB2_LIB.BASEBOARD_FAB2(SCH_1):GND
  AE70  GND            VSS<861>  @BASEBOARD_FAB2_LIB.BASEBOARD_FAB2(SCH_1):GND
  AE78  GND            VSS<860>  @BASEBOARD_FAB2_LIB.BASEBOARD_FAB2(SCH_1):GND
  AF1  GND            VSS<859>  @BASEBOARD_FAB2_LIB.BASEBOARD_FAB2(SCH_1):GND
  AC52  GND            VSS<858>  @BASEBOARD_FAB2_LIB.BASEBOARD_FAB2(SCH_1):GND
  AF9  GND            VSS<857>  @BASEBOARD_FAB2_LIB.BASEBOARD_FAB2(SCH_1):GND
  AF21  GND            VSS<856>  @BASEBOARD_FAB2_LIB.BASEBOARD_FAB2(SCH_1):GND
  AF23  GND            VSS<855>  @BASEBOARD_FAB2_LIB.BASEBOARD_FAB2(SCH_1):GND
  AF25  GND            VSS<854>  @BASEBOARD_FAB2_LIB.BASEBOARD_FAB2(SCH_1):GND
  AF27  GND            VSS<853>  @BASEBOARD_FAB2_LIB.BASEBOARD_FAB2(SCH_1):GND
  AF29  GND            VSS<852>  @BASEBOARD_FAB2_LIB.BASEBOARD_FAB2(SCH_1):GND
  AF31  GND            VSS<851>  @BASEBOARD_FAB2_LIB.BASEBOARD_FAB2(SCH_1):GND
  AF33  GND            VSS<850>  @BASEBOARD_FAB2_LIB.BASEBOARD_FAB2(SCH_1):GND
  AF37  GND            VSS<849>  @BASEBOARD_FAB2_LIB.BASEBOARD_FAB2(SCH_1):GND
  AF39  GND            VSS<848>  @BASEBOARD_FAB2_LIB.BASEBOARD_FAB2(SCH_1):GND
  AF41  GND            VSS<847>  @BASEBOARD_FAB2_LIB.BASEBOARD_FAB2(SCH_1):GND
  AF73  GND            VSS<846>  @BASEBOARD_FAB2_LIB.BASEBOARD_FAB2(SCH_1):GND
  AF77  GND            VSS<845>  @BASEBOARD_FAB2_LIB.BASEBOARD_FAB2(SCH_1):GND
  AF83  GND            VSS<844>  @BASEBOARD_FAB2_LIB.BASEBOARD_FAB2(SCH_1):GND
  AF85  GND            VSS<843>  @BASEBOARD_FAB2_LIB.BASEBOARD_FAB2(SCH_1):GND
  AG12  GND            VSS<842>  @BASEBOARD_FAB2_LIB.BASEBOARD_FAB2(SCH_1):GND
  AG14  GND            VSS<841>  @BASEBOARD_FAB2_LIB.BASEBOARD_FAB2(SCH_1):GND
  AG18  GND            VSS<840>  @BASEBOARD_FAB2_LIB.BASEBOARD_FAB2(SCH_1):GND
  AG36  GND            VSS<839>  @BASEBOARD_FAB2_LIB.BASEBOARD_FAB2(SCH_1):GND
  AG64  GND            VSS<838>  @BASEBOARD_FAB2_LIB.BASEBOARD_FAB2(SCH_1):GND
  AG70  GND            VSS<837>  @BASEBOARD_FAB2_LIB.BASEBOARD_FAB2(SCH_1):GND
  AG74  GND            VSS<836>  @BASEBOARD_FAB2_LIB.BASEBOARD_FAB2(SCH_1):GND
  AG76  GND            VSS<835>  @BASEBOARD_FAB2_LIB.BASEBOARD_FAB2(SCH_1):GND
  AG78  GND            VSS<834>  @BASEBOARD_FAB2_LIB.BASEBOARD_FAB2(SCH_1):GND
  AG80  GND            VSS<833>  @BASEBOARD_FAB2_LIB.BASEBOARD_FAB2(SCH_1):GND
  AH1  GND            VSS<832>  @BASEBOARD_FAB2_LIB.BASEBOARD_FAB2(SCH_1):GND
  AH5  GND            VSS<831>  @BASEBOARD_FAB2_LIB.BASEBOARD_FAB2(SCH_1):GND
  AH21  GND            VSS<830>  @BASEBOARD_FAB2_LIB.BASEBOARD_FAB2(SCH_1):GND
  AH27  GND            VSS<829>  @BASEBOARD_FAB2_LIB.BASEBOARD_FAB2(SCH_1):GND
  AH33  GND            VSS<828>  @BASEBOARD_FAB2_LIB.BASEBOARD_FAB2(SCH_1):GND
  AH35  GND            VSS<827>  @BASEBOARD_FAB2_LIB.BASEBOARD_FAB2(SCH_1):GND
  AH45  GND            VSS<826>  @BASEBOARD_FAB2_LIB.BASEBOARD_FAB2(SCH_1):GND
  AH47  GND            VSS<825>  @BASEBOARD_FAB2_LIB.BASEBOARD_FAB2(SCH_1):GND
  AH49  GND            VSS<824>  @BASEBOARD_FAB2_LIB.BASEBOARD_FAB2(SCH_1):GND
  AH51  GND            VSS<823>  @BASEBOARD_FAB2_LIB.BASEBOARD_FAB2(SCH_1):GND
  AH53  GND            VSS<822>  @BASEBOARD_FAB2_LIB.BASEBOARD_FAB2(SCH_1):GND
  AH59  GND            VSS<821>  @BASEBOARD_FAB2_LIB.BASEBOARD_FAB2(SCH_1):GND
  AH61  GND            VSS<820>  @BASEBOARD_FAB2_LIB.BASEBOARD_FAB2(SCH_1):GND
  AH65  GND            VSS<819>  @BASEBOARD_FAB2_LIB.BASEBOARD_FAB2(SCH_1):GND
  AH69  GND            VSS<818>  @BASEBOARD_FAB2_LIB.BASEBOARD_FAB2(SCH_1):GND
  AH75  GND            VSS<817>  @BASEBOARD_FAB2_LIB.BASEBOARD_FAB2(SCH_1):GND
  AH77  GND            VSS<816>  @BASEBOARD_FAB2_LIB.BASEBOARD_FAB2(SCH_1):GND
  AH83  GND            VSS<815>  @BASEBOARD_FAB2_LIB.BASEBOARD_FAB2(SCH_1):GND
  AJ8  GND            VSS<814>  @BASEBOARD_FAB2_LIB.BASEBOARD_FAB2(SCH_1):GND
  AJ22  GND            VSS<813>  @BASEBOARD_FAB2_LIB.BASEBOARD_FAB2(SCH_1):GND
  AJ26  GND            VSS<812>  @BASEBOARD_FAB2_LIB.BASEBOARD_FAB2(SCH_1):GND
  AJ28  GND            VSS<811>  @BASEBOARD_FAB2_LIB.BASEBOARD_FAB2(SCH_1):GND
  AJ32  GND            VSS<810>  @BASEBOARD_FAB2_LIB.BASEBOARD_FAB2(SCH_1):GND
  AJ34  GND            VSS<809>  @BASEBOARD_FAB2_LIB.BASEBOARD_FAB2(SCH_1):GND
  AJ46  GND            VSS<808>  @BASEBOARD_FAB2_LIB.BASEBOARD_FAB2(SCH_1):GND
  AJ48  GND            VSS<807>  @BASEBOARD_FAB2_LIB.BASEBOARD_FAB2(SCH_1):GND
  AJ50  GND            VSS<806>  @BASEBOARD_FAB2_LIB.BASEBOARD_FAB2(SCH_1):GND
  AJ52  GND            VSS<805>  @BASEBOARD_FAB2_LIB.BASEBOARD_FAB2(SCH_1):GND
  AJ54  GND            VSS<804>  @BASEBOARD_FAB2_LIB.BASEBOARD_FAB2(SCH_1):GND
  AJ66  GND            VSS<803>  @BASEBOARD_FAB2_LIB.BASEBOARD_FAB2(SCH_1):GND
  AJ68  GND            VSS<802>  @BASEBOARD_FAB2_LIB.BASEBOARD_FAB2(SCH_1):GND
  AJ74  GND            VSS<801>  @BASEBOARD_FAB2_LIB.BASEBOARD_FAB2(SCH_1):GND
  AJ78  GND            VSS<800>  @BASEBOARD_FAB2_LIB.BASEBOARD_FAB2(SCH_1):GND
  AJ82  GND            VSS<799>  @BASEBOARD_FAB2_LIB.BASEBOARD_FAB2(SCH_1):GND
  AJ86  GND            VSS<798>  @BASEBOARD_FAB2_LIB.BASEBOARD_FAB2(SCH_1):GND
  AK9  GND            VSS<797>  @BASEBOARD_FAB2_LIB.BASEBOARD_FAB2(SCH_1):GND
  AK13  GND            VSS<796>  @BASEBOARD_FAB2_LIB.BASEBOARD_FAB2(SCH_1):GND
  AK19  GND            VSS<795>  @BASEBOARD_FAB2_LIB.BASEBOARD_FAB2(SCH_1):GND
  AK23  GND            VSS<794>  @BASEBOARD_FAB2_LIB.BASEBOARD_FAB2(SCH_1):GND
  AK25  GND            VSS<793>  @BASEBOARD_FAB2_LIB.BASEBOARD_FAB2(SCH_1):GND
  AK29  GND            VSS<792>  @BASEBOARD_FAB2_LIB.BASEBOARD_FAB2(SCH_1):GND
  AK31  GND            VSS<791>  @BASEBOARD_FAB2_LIB.BASEBOARD_FAB2(SCH_1):GND
  AK33  GND            VSS<790>  @BASEBOARD_FAB2_LIB.BASEBOARD_FAB2(SCH_1):GND
  AK55  GND            VSS<789>  @BASEBOARD_FAB2_LIB.BASEBOARD_FAB2(SCH_1):GND
  AK65  GND            VSS<788>  @BASEBOARD_FAB2_LIB.BASEBOARD_FAB2(SCH_1):GND
  AK67  GND            VSS<787>  @BASEBOARD_FAB2_LIB.BASEBOARD_FAB2(SCH_1):GND
  AK73  GND            VSS<786>  @BASEBOARD_FAB2_LIB.BASEBOARD_FAB2(SCH_1):GND
  AK79  GND            VSS<785>  @BASEBOARD_FAB2_LIB.BASEBOARD_FAB2(SCH_1):GND
  AK81  GND            VSS<784>  @BASEBOARD_FAB2_LIB.BASEBOARD_FAB2(SCH_1):GND
  AK83  GND            VSS<783>  @BASEBOARD_FAB2_LIB.BASEBOARD_FAB2(SCH_1):GND
  AK85  GND            VSS<782>  @BASEBOARD_FAB2_LIB.BASEBOARD_FAB2(SCH_1):GND
  AL4  GND            VSS<781>  @BASEBOARD_FAB2_LIB.BASEBOARD_FAB2(SCH_1):GND
  AL10  GND            VSS<780>  @BASEBOARD_FAB2_LIB.BASEBOARD_FAB2(SCH_1):GND
  AL24  GND            VSS<779>  @BASEBOARD_FAB2_LIB.BASEBOARD_FAB2(SCH_1):GND
  AL30  GND            VSS<778>  @BASEBOARD_FAB2_LIB.BASEBOARD_FAB2(SCH_1):GND
  AL32  GND            VSS<777>  @BASEBOARD_FAB2_LIB.BASEBOARD_FAB2(SCH_1):GND
  AL56  GND            VSS<776>  @BASEBOARD_FAB2_LIB.BASEBOARD_FAB2(SCH_1):GND
  AL64  GND            VSS<775>  @BASEBOARD_FAB2_LIB.BASEBOARD_FAB2(SCH_1):GND
  AL68  GND            VSS<774>  @BASEBOARD_FAB2_LIB.BASEBOARD_FAB2(SCH_1):GND

SKX_EXT_B_BGA1  I21  U5D1   [SKX_EXT_B_BGA1-IC,TBD]
  J76  GND            VSS<1093>  @BASEBOARD_FAB2_LIB.BASEBOARD_FAB2(SCH_1):GND
  J82  GND            VSS<1092>  @BASEBOARD_FAB2_LIB.BASEBOARD_FAB2(SCH_1):GND
  J84  GND            VSS<1091>  @BASEBOARD_FAB2_LIB.BASEBOARD_FAB2(SCH_1):GND
   K1  GND            VSS<1090>  @BASEBOARD_FAB2_LIB.BASEBOARD_FAB2(SCH_1):GND
  K11  GND            VSS<1089>  @BASEBOARD_FAB2_LIB.BASEBOARD_FAB2(SCH_1):GND
  K13  GND            VSS<1088>  @BASEBOARD_FAB2_LIB.BASEBOARD_FAB2(SCH_1):GND
  K17  GND            VSS<1087>  @BASEBOARD_FAB2_LIB.BASEBOARD_FAB2(SCH_1):GND
  DB7  GND            VSS<1086>  @BASEBOARD_FAB2_LIB.BASEBOARD_FAB2(SCH_1):GND
  K27  GND            VSS<1085>  @BASEBOARD_FAB2_LIB.BASEBOARD_FAB2(SCH_1):GND
  K33  GND            VSS<1084>  @BASEBOARD_FAB2_LIB.BASEBOARD_FAB2(SCH_1):GND
  K39  GND            VSS<1083>  @BASEBOARD_FAB2_LIB.BASEBOARD_FAB2(SCH_1):GND
  K65  GND            VSS<1082>  @BASEBOARD_FAB2_LIB.BASEBOARD_FAB2(SCH_1):GND
  K67  GND            VSS<1081>  @BASEBOARD_FAB2_LIB.BASEBOARD_FAB2(SCH_1):GND
  K69  GND            VSS<1080>  @BASEBOARD_FAB2_LIB.BASEBOARD_FAB2(SCH_1):GND
  K71  GND            VSS<1079>  @BASEBOARD_FAB2_LIB.BASEBOARD_FAB2(SCH_1):GND
  K73  GND            VSS<1078>  @BASEBOARD_FAB2_LIB.BASEBOARD_FAB2(SCH_1):GND
  K77  GND            VSS<1077>  @BASEBOARD_FAB2_LIB.BASEBOARD_FAB2(SCH_1):GND
  K81  GND            VSS<1076>  @BASEBOARD_FAB2_LIB.BASEBOARD_FAB2(SCH_1):GND
  K83  GND            VSS<1075>  @BASEBOARD_FAB2_LIB.BASEBOARD_FAB2(SCH_1):GND
  K85  GND            VSS<1074>  @BASEBOARD_FAB2_LIB.BASEBOARD_FAB2(SCH_1):GND
  L10  GND            VSS<1073>  @BASEBOARD_FAB2_LIB.BASEBOARD_FAB2(SCH_1):GND
   L2  GND            VSS<1072>  @BASEBOARD_FAB2_LIB.BASEBOARD_FAB2(SCH_1):GND
   L6  GND            VSS<1071>  @BASEBOARD_FAB2_LIB.BASEBOARD_FAB2(SCH_1):GND
  L20  GND            VSS<1070>  @BASEBOARD_FAB2_LIB.BASEBOARD_FAB2(SCH_1):GND
  L22  GND            VSS<1069>  @BASEBOARD_FAB2_LIB.BASEBOARD_FAB2(SCH_1):GND
  L72  GND            VSS<1068>  @BASEBOARD_FAB2_LIB.BASEBOARD_FAB2(SCH_1):GND
  L78  GND            VSS<1067>  @BASEBOARD_FAB2_LIB.BASEBOARD_FAB2(SCH_1):GND
  L80  GND            VSS<1066>  @BASEBOARD_FAB2_LIB.BASEBOARD_FAB2(SCH_1):GND
  L82  GND            VSS<1065>  @BASEBOARD_FAB2_LIB.BASEBOARD_FAB2(SCH_1):GND
  BT9  GND            VSS<1064>  @BASEBOARD_FAB2_LIB.BASEBOARD_FAB2(SCH_1):GND
  CT7  GND            VSS<1063>  @BASEBOARD_FAB2_LIB.BASEBOARD_FAB2(SCH_1):GND
  M15  GND            VSS<1062>  @BASEBOARD_FAB2_LIB.BASEBOARD_FAB2(SCH_1):GND
  M17  GND            VSS<1061>  @BASEBOARD_FAB2_LIB.BASEBOARD_FAB2(SCH_1):GND
  M19  GND            VSS<1060>  @BASEBOARD_FAB2_LIB.BASEBOARD_FAB2(SCH_1):GND
  M23  GND            VSS<1059>  @BASEBOARD_FAB2_LIB.BASEBOARD_FAB2(SCH_1):GND
  M25  GND            VSS<1058>  @BASEBOARD_FAB2_LIB.BASEBOARD_FAB2(SCH_1):GND
  M27  GND            VSS<1057>  @BASEBOARD_FAB2_LIB.BASEBOARD_FAB2(SCH_1):GND
  M29  GND            VSS<1056>  @BASEBOARD_FAB2_LIB.BASEBOARD_FAB2(SCH_1):GND
  M31  GND            VSS<1055>  @BASEBOARD_FAB2_LIB.BASEBOARD_FAB2(SCH_1):GND
  M33  GND            VSS<1054>  @BASEBOARD_FAB2_LIB.BASEBOARD_FAB2(SCH_1):GND
  M35  GND            VSS<1053>  @BASEBOARD_FAB2_LIB.BASEBOARD_FAB2(SCH_1):GND
  M37  GND            VSS<1052>  @BASEBOARD_FAB2_LIB.BASEBOARD_FAB2(SCH_1):GND
  M39  GND            VSS<1051>  @BASEBOARD_FAB2_LIB.BASEBOARD_FAB2(SCH_1):GND
  M41  GND            VSS<1050>  @BASEBOARD_FAB2_LIB.BASEBOARD_FAB2(SCH_1):GND
  M43  GND            VSS<1049>  @BASEBOARD_FAB2_LIB.BASEBOARD_FAB2(SCH_1):GND
  M65  GND            VSS<1048>  @BASEBOARD_FAB2_LIB.BASEBOARD_FAB2(SCH_1):GND
  M71  GND            VSS<1047>  @BASEBOARD_FAB2_LIB.BASEBOARD_FAB2(SCH_1):GND
  M79  GND            VSS<1046>  @BASEBOARD_FAB2_LIB.BASEBOARD_FAB2(SCH_1):GND
  M83  GND            VSS<1045>  @BASEBOARD_FAB2_LIB.BASEBOARD_FAB2(SCH_1):GND
  M85  GND            VSS<1044>  @BASEBOARD_FAB2_LIB.BASEBOARD_FAB2(SCH_1):GND
  DM19  GND            VSS<1043>  @BASEBOARD_FAB2_LIB.BASEBOARD_FAB2(SCH_1):GND
  N20  GND            VSS<1042>  @BASEBOARD_FAB2_LIB.BASEBOARD_FAB2(SCH_1):GND
  N22  GND            VSS<1041>  @BASEBOARD_FAB2_LIB.BASEBOARD_FAB2(SCH_1):GND
   N6  GND            VSS<1040>  @BASEBOARD_FAB2_LIB.BASEBOARD_FAB2(SCH_1):GND
  N66  GND            VSS<1039>  @BASEBOARD_FAB2_LIB.BASEBOARD_FAB2(SCH_1):GND
  N70  GND            VSS<1038>  @BASEBOARD_FAB2_LIB.BASEBOARD_FAB2(SCH_1):GND
  N72  GND            VSS<1037>  @BASEBOARD_FAB2_LIB.BASEBOARD_FAB2(SCH_1):GND
  N74  GND            VSS<1036>  @BASEBOARD_FAB2_LIB.BASEBOARD_FAB2(SCH_1):GND
  N76  GND            VSS<1035>  @BASEBOARD_FAB2_LIB.BASEBOARD_FAB2(SCH_1):GND
  N78  GND            VSS<1034>  @BASEBOARD_FAB2_LIB.BASEBOARD_FAB2(SCH_1):GND
   N4  GND            VSS<1033>  @BASEBOARD_FAB2_LIB.BASEBOARD_FAB2(SCH_1):GND
   N8  GND            VSS<1032>  @BASEBOARD_FAB2_LIB.BASEBOARD_FAB2(SCH_1):GND
  P11  GND            VSS<1031>  @BASEBOARD_FAB2_LIB.BASEBOARD_FAB2(SCH_1):GND
  P15  GND            VSS<1030>  @BASEBOARD_FAB2_LIB.BASEBOARD_FAB2(SCH_1):GND
  P27  GND            VSS<1029>  @BASEBOARD_FAB2_LIB.BASEBOARD_FAB2(SCH_1):GND
  P33  GND            VSS<1028>  @BASEBOARD_FAB2_LIB.BASEBOARD_FAB2(SCH_1):GND
  P39  GND            VSS<1027>  @BASEBOARD_FAB2_LIB.BASEBOARD_FAB2(SCH_1):GND
  P67  GND            VSS<1026>  @BASEBOARD_FAB2_LIB.BASEBOARD_FAB2(SCH_1):GND
  P69  GND            VSS<1025>  @BASEBOARD_FAB2_LIB.BASEBOARD_FAB2(SCH_1):GND
  P71  GND            VSS<1024>  @BASEBOARD_FAB2_LIB.BASEBOARD_FAB2(SCH_1):GND
  P81  GND            VSS<1023>  @BASEBOARD_FAB2_LIB.BASEBOARD_FAB2(SCH_1):GND
  P83  GND            VSS<1022>  @BASEBOARD_FAB2_LIB.BASEBOARD_FAB2(SCH_1):GND
  R14  GND            VSS<1021>  @BASEBOARD_FAB2_LIB.BASEBOARD_FAB2(SCH_1):GND
  R18  GND            VSS<1020>  @BASEBOARD_FAB2_LIB.BASEBOARD_FAB2(SCH_1):GND
   R2  GND            VSS<1019>  @BASEBOARD_FAB2_LIB.BASEBOARD_FAB2(SCH_1):GND
   R4  GND            VSS<1018>  @BASEBOARD_FAB2_LIB.BASEBOARD_FAB2(SCH_1):GND
  R22  GND            VSS<1017>  @BASEBOARD_FAB2_LIB.BASEBOARD_FAB2(SCH_1):GND
  R26  GND            VSS<1016>  @BASEBOARD_FAB2_LIB.BASEBOARD_FAB2(SCH_1):GND
  R28  GND            VSS<1015>  @BASEBOARD_FAB2_LIB.BASEBOARD_FAB2(SCH_1):GND
  R32  GND            VSS<1014>  @BASEBOARD_FAB2_LIB.BASEBOARD_FAB2(SCH_1):GND
  R34  GND            VSS<1013>  @BASEBOARD_FAB2_LIB.BASEBOARD_FAB2(SCH_1):GND
  R38  GND            VSS<1012>  @BASEBOARD_FAB2_LIB.BASEBOARD_FAB2(SCH_1):GND
  R40  GND            VSS<1011>  @BASEBOARD_FAB2_LIB.BASEBOARD_FAB2(SCH_1):GND
  R68  GND            VSS<1010>  @BASEBOARD_FAB2_LIB.BASEBOARD_FAB2(SCH_1):GND
  R72  GND            VSS<1009>  @BASEBOARD_FAB2_LIB.BASEBOARD_FAB2(SCH_1):GND
  R78  GND            VSS<1008>  @BASEBOARD_FAB2_LIB.BASEBOARD_FAB2(SCH_1):GND
  R86  GND            VSS<1007>  @BASEBOARD_FAB2_LIB.BASEBOARD_FAB2(SCH_1):GND
  T13  GND            VSS<1006>  @BASEBOARD_FAB2_LIB.BASEBOARD_FAB2(SCH_1):GND
  T17  GND            VSS<1005>  @BASEBOARD_FAB2_LIB.BASEBOARD_FAB2(SCH_1):GND
  T25  GND            VSS<1004>  @BASEBOARD_FAB2_LIB.BASEBOARD_FAB2(SCH_1):GND
  T29  GND            VSS<1003>  @BASEBOARD_FAB2_LIB.BASEBOARD_FAB2(SCH_1):GND
  T31  GND            VSS<1002>  @BASEBOARD_FAB2_LIB.BASEBOARD_FAB2(SCH_1):GND
  T35  GND            VSS<1001>  @BASEBOARD_FAB2_LIB.BASEBOARD_FAB2(SCH_1):GND
  T37  GND            VSS<1000>  @BASEBOARD_FAB2_LIB.BASEBOARD_FAB2(SCH_1):GND
  T41  GND            VSS<999>  @BASEBOARD_FAB2_LIB.BASEBOARD_FAB2(SCH_1):GND
  T65  GND            VSS<998>  @BASEBOARD_FAB2_LIB.BASEBOARD_FAB2(SCH_1):GND
  T73  GND            VSS<997>  @BASEBOARD_FAB2_LIB.BASEBOARD_FAB2(SCH_1):GND
  T77  GND            VSS<996>  @BASEBOARD_FAB2_LIB.BASEBOARD_FAB2(SCH_1):GND
  T83  GND            VSS<995>  @BASEBOARD_FAB2_LIB.BASEBOARD_FAB2(SCH_1):GND
  T85  GND            VSS<994>  @BASEBOARD_FAB2_LIB.BASEBOARD_FAB2(SCH_1):GND
   U2  GND            VSS<993>  @BASEBOARD_FAB2_LIB.BASEBOARD_FAB2(SCH_1):GND
   U4  GND            VSS<992>  @BASEBOARD_FAB2_LIB.BASEBOARD_FAB2(SCH_1):GND
   U6  GND            VSS<991>  @BASEBOARD_FAB2_LIB.BASEBOARD_FAB2(SCH_1):GND
  U20  GND            VSS<990>  @BASEBOARD_FAB2_LIB.BASEBOARD_FAB2(SCH_1):GND
  U22  GND            VSS<989>  @BASEBOARD_FAB2_LIB.BASEBOARD_FAB2(SCH_1):GND
  U24  GND            VSS<988>  @BASEBOARD_FAB2_LIB.BASEBOARD_FAB2(SCH_1):GND
  U30  GND            VSS<987>  @BASEBOARD_FAB2_LIB.BASEBOARD_FAB2(SCH_1):GND
  U36  GND            VSS<986>  @BASEBOARD_FAB2_LIB.BASEBOARD_FAB2(SCH_1):GND
  U42  GND            VSS<985>  @BASEBOARD_FAB2_LIB.BASEBOARD_FAB2(SCH_1):GND
  U68  GND            VSS<984>  @BASEBOARD_FAB2_LIB.BASEBOARD_FAB2(SCH_1):GND
  U70  GND            VSS<983>  @BASEBOARD_FAB2_LIB.BASEBOARD_FAB2(SCH_1):GND
  U74  GND            VSS<982>  @BASEBOARD_FAB2_LIB.BASEBOARD_FAB2(SCH_1):GND
  U76  GND            VSS<981>  @BASEBOARD_FAB2_LIB.BASEBOARD_FAB2(SCH_1):GND
  U78  GND            VSS<980>  @BASEBOARD_FAB2_LIB.BASEBOARD_FAB2(SCH_1):GND
  U80  GND            VSS<979>  @BASEBOARD_FAB2_LIB.BASEBOARD_FAB2(SCH_1):GND
  U86  GND            VSS<978>  @BASEBOARD_FAB2_LIB.BASEBOARD_FAB2(SCH_1):GND
   V1  GND            VSS<977>  @BASEBOARD_FAB2_LIB.BASEBOARD_FAB2(SCH_1):GND
   V5  GND            VSS<976>  @BASEBOARD_FAB2_LIB.BASEBOARD_FAB2(SCH_1):GND
   V9  GND            VSS<975>  @BASEBOARD_FAB2_LIB.BASEBOARD_FAB2(SCH_1):GND
  V13  GND            VSS<974>  @BASEBOARD_FAB2_LIB.BASEBOARD_FAB2(SCH_1):GND
  V15  GND            VSS<973>  @BASEBOARD_FAB2_LIB.BASEBOARD_FAB2(SCH_1):GND
  V21  GND            VSS<972>  @BASEBOARD_FAB2_LIB.BASEBOARD_FAB2(SCH_1):GND
  V23  GND            VSS<971>  @BASEBOARD_FAB2_LIB.BASEBOARD_FAB2(SCH_1):GND
  V43  GND            VSS<970>  @BASEBOARD_FAB2_LIB.BASEBOARD_FAB2(SCH_1):GND
  V73  GND            VSS<969>  @BASEBOARD_FAB2_LIB.BASEBOARD_FAB2(SCH_1):GND
  V75  GND            VSS<968>  @BASEBOARD_FAB2_LIB.BASEBOARD_FAB2(SCH_1):GND
  V77  GND            VSS<967>  @BASEBOARD_FAB2_LIB.BASEBOARD_FAB2(SCH_1):GND
  V83  GND            VSS<966>  @BASEBOARD_FAB2_LIB.BASEBOARD_FAB2(SCH_1):GND
   W8  GND            VSS<965>  @BASEBOARD_FAB2_LIB.BASEBOARD_FAB2(SCH_1):GND
  AC56  GND            VSS<964>  @BASEBOARD_FAB2_LIB.BASEBOARD_FAB2(SCH_1):GND
  W12  GND            VSS<963>  @BASEBOARD_FAB2_LIB.BASEBOARD_FAB2(SCH_1):GND
  W22  GND            VSS<962>  @BASEBOARD_FAB2_LIB.BASEBOARD_FAB2(SCH_1):GND
  W24  GND            VSS<961>  @BASEBOARD_FAB2_LIB.BASEBOARD_FAB2(SCH_1):GND
  W26  GND            VSS<960>  @BASEBOARD_FAB2_LIB.BASEBOARD_FAB2(SCH_1):GND
  W28  GND            VSS<959>  @BASEBOARD_FAB2_LIB.BASEBOARD_FAB2(SCH_1):GND
  W30  GND            VSS<958>  @BASEBOARD_FAB2_LIB.BASEBOARD_FAB2(SCH_1):GND
  W32  GND            VSS<957>  @BASEBOARD_FAB2_LIB.BASEBOARD_FAB2(SCH_1):GND
  W34  GND            VSS<956>  @BASEBOARD_FAB2_LIB.BASEBOARD_FAB2(SCH_1):GND
  W36  GND            VSS<955>  @BASEBOARD_FAB2_LIB.BASEBOARD_FAB2(SCH_1):GND
  W38  GND            VSS<954>  @BASEBOARD_FAB2_LIB.BASEBOARD_FAB2(SCH_1):GND
  W40  GND            VSS<953>  @BASEBOARD_FAB2_LIB.BASEBOARD_FAB2(SCH_1):GND
  W42  GND            VSS<952>  @BASEBOARD_FAB2_LIB.BASEBOARD_FAB2(SCH_1):GND
  W68  GND            VSS<951>  @BASEBOARD_FAB2_LIB.BASEBOARD_FAB2(SCH_1):GND
  W74  GND            VSS<950>  @BASEBOARD_FAB2_LIB.BASEBOARD_FAB2(SCH_1):GND
  W78  GND            VSS<949>  @BASEBOARD_FAB2_LIB.BASEBOARD_FAB2(SCH_1):GND
  W82  GND            VSS<948>  @BASEBOARD_FAB2_LIB.BASEBOARD_FAB2(SCH_1):GND
  Y15  GND            VSS<947>  @BASEBOARD_FAB2_LIB.BASEBOARD_FAB2(SCH_1):GND
  Y17  GND            VSS<946>  @BASEBOARD_FAB2_LIB.BASEBOARD_FAB2(SCH_1):GND
   Y5  GND            VSS<945>  @BASEBOARD_FAB2_LIB.BASEBOARD_FAB2(SCH_1):GND
  Y67  GND            VSS<944>  @BASEBOARD_FAB2_LIB.BASEBOARD_FAB2(SCH_1):GND
   Y7  GND            VSS<943>  @BASEBOARD_FAB2_LIB.BASEBOARD_FAB2(SCH_1):GND
   Y9  GND            VSS<942>  @BASEBOARD_FAB2_LIB.BASEBOARD_FAB2(SCH_1):GND
  Y71  GND            VSS<941>  @BASEBOARD_FAB2_LIB.BASEBOARD_FAB2(SCH_1):GND
  Y73  GND            VSS<940>  @BASEBOARD_FAB2_LIB.BASEBOARD_FAB2(SCH_1):GND
  Y79  GND            VSS<939>  @BASEBOARD_FAB2_LIB.BASEBOARD_FAB2(SCH_1):GND
  Y81  GND            VSS<938>  @BASEBOARD_FAB2_LIB.BASEBOARD_FAB2(SCH_1):GND
  Y83  GND            VSS<937>  @BASEBOARD_FAB2_LIB.BASEBOARD_FAB2(SCH_1):GND
  Y85  GND            VSS<936>  @BASEBOARD_FAB2_LIB.BASEBOARD_FAB2(SCH_1):GND
  AA4  GND            VSS<935>  @BASEBOARD_FAB2_LIB.BASEBOARD_FAB2(SCH_1):GND
  AA16  GND            VSS<934>  @BASEBOARD_FAB2_LIB.BASEBOARD_FAB2(SCH_1):GND

SKX_EXT_B_BGA1  I20  U5D1   [SKX_EXT_B_BGA1-IC,TBD]
   B9  GND            VSS<1253>  @BASEBOARD_FAB2_LIB.BASEBOARD_FAB2(SCH_1):GND
  A42  GND            VSS<1252>  @BASEBOARD_FAB2_LIB.BASEBOARD_FAB2(SCH_1):GND
  B43  GND            VSS<1251>  @BASEBOARD_FAB2_LIB.BASEBOARD_FAB2(SCH_1):GND
   B5  GND            VSS<1250>  @BASEBOARD_FAB2_LIB.BASEBOARD_FAB2(SCH_1):GND
  B79  GND            VSS<1249>  @BASEBOARD_FAB2_LIB.BASEBOARD_FAB2(SCH_1):GND
   C4  GND            VSS<1248>  @BASEBOARD_FAB2_LIB.BASEBOARD_FAB2(SCH_1):GND
  C80  GND            VSS<1247>  @BASEBOARD_FAB2_LIB.BASEBOARD_FAB2(SCH_1):GND
   D3  GND            VSS<1246>  @BASEBOARD_FAB2_LIB.BASEBOARD_FAB2(SCH_1):GND
  D81  GND            VSS<1245>  @BASEBOARD_FAB2_LIB.BASEBOARD_FAB2(SCH_1):GND
  E82  GND            VSS<1244>  @BASEBOARD_FAB2_LIB.BASEBOARD_FAB2(SCH_1):GND
  J86  GND            VSS<1243>  @BASEBOARD_FAB2_LIB.BASEBOARD_FAB2(SCH_1):GND
  DY85  GND            VSS<1242>  @BASEBOARD_FAB2_LIB.BASEBOARD_FAB2(SCH_1):GND
  EA84  GND            VSS<1241>  @BASEBOARD_FAB2_LIB.BASEBOARD_FAB2(SCH_1):GND
  EB83  GND            VSS<1240>  @BASEBOARD_FAB2_LIB.BASEBOARD_FAB2(SCH_1):GND
  DW2  GND            VSS<1239>  @BASEBOARD_FAB2_LIB.BASEBOARD_FAB2(SCH_1):GND
  EC42  GND            VSS<1238>  @BASEBOARD_FAB2_LIB.BASEBOARD_FAB2(SCH_1):GND
  EC6  GND            VSS<1237>  @BASEBOARD_FAB2_LIB.BASEBOARD_FAB2(SCH_1):GND
  EC82  GND            VSS<1236>  @BASEBOARD_FAB2_LIB.BASEBOARD_FAB2(SCH_1):GND
  ED41  GND            VSS<1235>  @BASEBOARD_FAB2_LIB.BASEBOARD_FAB2(SCH_1):GND
  ED7  GND            VSS<1234>  @BASEBOARD_FAB2_LIB.BASEBOARD_FAB2(SCH_1):GND
  ED81  GND            VSS<1233>  @BASEBOARD_FAB2_LIB.BASEBOARD_FAB2(SCH_1):GND
  EE40  GND            VSS<1232>  @BASEBOARD_FAB2_LIB.BASEBOARD_FAB2(SCH_1):GND
  EE8  GND            VSS<1231>  @BASEBOARD_FAB2_LIB.BASEBOARD_FAB2(SCH_1):GND
  EE80  GND            VSS<1230>  @BASEBOARD_FAB2_LIB.BASEBOARD_FAB2(SCH_1):GND
  ED69  GND            VSS<1229>  @BASEBOARD_FAB2_LIB.BASEBOARD_FAB2(SCH_1):GND
  E66  GND            VSS<1228>  @BASEBOARD_FAB2_LIB.BASEBOARD_FAB2(SCH_1):GND
  V11  GND            VSS<1227>  @BASEBOARD_FAB2_LIB.BASEBOARD_FAB2(SCH_1):GND
   L8  GND            VSS<1226>  @BASEBOARD_FAB2_LIB.BASEBOARD_FAB2(SCH_1):GND
  EA14  GND            VSS<1225>  @BASEBOARD_FAB2_LIB.BASEBOARD_FAB2(SCH_1):GND
  DY63  GND            VSS<1224>  @BASEBOARD_FAB2_LIB.BASEBOARD_FAB2(SCH_1):GND
  DY61  GND            VSS<1223>  @BASEBOARD_FAB2_LIB.BASEBOARD_FAB2(SCH_1):GND
  DY59  GND            VSS<1222>  @BASEBOARD_FAB2_LIB.BASEBOARD_FAB2(SCH_1):GND
  DY57  GND            VSS<1221>  @BASEBOARD_FAB2_LIB.BASEBOARD_FAB2(SCH_1):GND
  DY55  GND            VSS<1220>  @BASEBOARD_FAB2_LIB.BASEBOARD_FAB2(SCH_1):GND
  DY53  GND            VSS<1219>  @BASEBOARD_FAB2_LIB.BASEBOARD_FAB2(SCH_1):GND
  DY51  GND            VSS<1218>  @BASEBOARD_FAB2_LIB.BASEBOARD_FAB2(SCH_1):GND
  DY49  GND            VSS<1217>  @BASEBOARD_FAB2_LIB.BASEBOARD_FAB2(SCH_1):GND
  DY47  GND            VSS<1216>  @BASEBOARD_FAB2_LIB.BASEBOARD_FAB2(SCH_1):GND
  DY45  GND            VSS<1215>  @BASEBOARD_FAB2_LIB.BASEBOARD_FAB2(SCH_1):GND
  DV19  GND            VSS<1214>  @BASEBOARD_FAB2_LIB.BASEBOARD_FAB2(SCH_1):GND
  DP9  GND            VSS<1213>  @BASEBOARD_FAB2_LIB.BASEBOARD_FAB2(SCH_1):GND
  DP63  GND            VSS<1212>  @BASEBOARD_FAB2_LIB.BASEBOARD_FAB2(SCH_1):GND
  DP61  GND            VSS<1211>  @BASEBOARD_FAB2_LIB.BASEBOARD_FAB2(SCH_1):GND
  DP59  GND            VSS<1210>  @BASEBOARD_FAB2_LIB.BASEBOARD_FAB2(SCH_1):GND
  DP57  GND            VSS<1209>  @BASEBOARD_FAB2_LIB.BASEBOARD_FAB2(SCH_1):GND
  DP55  GND            VSS<1208>  @BASEBOARD_FAB2_LIB.BASEBOARD_FAB2(SCH_1):GND
  DP53  GND            VSS<1207>  @BASEBOARD_FAB2_LIB.BASEBOARD_FAB2(SCH_1):GND
  DP51  GND            VSS<1206>  @BASEBOARD_FAB2_LIB.BASEBOARD_FAB2(SCH_1):GND
  DP49  GND            VSS<1205>  @BASEBOARD_FAB2_LIB.BASEBOARD_FAB2(SCH_1):GND
  DP47  GND            VSS<1204>  @BASEBOARD_FAB2_LIB.BASEBOARD_FAB2(SCH_1):GND
  DP45  GND            VSS<1203>  @BASEBOARD_FAB2_LIB.BASEBOARD_FAB2(SCH_1):GND
  DN18  GND            VSS<1202>  @BASEBOARD_FAB2_LIB.BASEBOARD_FAB2(SCH_1):GND
  DL8  GND            VSS<1201>  @BASEBOARD_FAB2_LIB.BASEBOARD_FAB2(SCH_1):GND
  DE62  GND            VSS<1200>  @BASEBOARD_FAB2_LIB.BASEBOARD_FAB2(SCH_1):GND
  DE60  GND            VSS<1199>  @BASEBOARD_FAB2_LIB.BASEBOARD_FAB2(SCH_1):GND
  DE58  GND            VSS<1198>  @BASEBOARD_FAB2_LIB.BASEBOARD_FAB2(SCH_1):GND
  DE56  GND            VSS<1197>  @BASEBOARD_FAB2_LIB.BASEBOARD_FAB2(SCH_1):GND
  DE54  GND            VSS<1196>  @BASEBOARD_FAB2_LIB.BASEBOARD_FAB2(SCH_1):GND
  DE52  GND            VSS<1195>  @BASEBOARD_FAB2_LIB.BASEBOARD_FAB2(SCH_1):GND
  DE50  GND            VSS<1194>  @BASEBOARD_FAB2_LIB.BASEBOARD_FAB2(SCH_1):GND
  DE48  GND            VSS<1193>  @BASEBOARD_FAB2_LIB.BASEBOARD_FAB2(SCH_1):GND
  CW6  GND            VSS<1192>  @BASEBOARD_FAB2_LIB.BASEBOARD_FAB2(SCH_1):GND
  CG6  GND            VSS<1191>  @BASEBOARD_FAB2_LIB.BASEBOARD_FAB2(SCH_1):GND
  AR6  GND            VSS<1190>  @BASEBOARD_FAB2_LIB.BASEBOARD_FAB2(SCH_1):GND
  AJ4  GND            VSS<1189>  @BASEBOARD_FAB2_LIB.BASEBOARD_FAB2(SCH_1):GND
  AC62  GND            VSS<1188>  @BASEBOARD_FAB2_LIB.BASEBOARD_FAB2(SCH_1):GND
  AC60  GND            VSS<1187>  @BASEBOARD_FAB2_LIB.BASEBOARD_FAB2(SCH_1):GND
  AC58  GND            VSS<1186>  @BASEBOARD_FAB2_LIB.BASEBOARD_FAB2(SCH_1):GND
  A26  GND            VSS<1185>  @BASEBOARD_FAB2_LIB.BASEBOARD_FAB2(SCH_1):GND
  A30  GND            VSS<1184>  @BASEBOARD_FAB2_LIB.BASEBOARD_FAB2(SCH_1):GND
  A32  GND            VSS<1183>  @BASEBOARD_FAB2_LIB.BASEBOARD_FAB2(SCH_1):GND
  A36  GND            VSS<1182>  @BASEBOARD_FAB2_LIB.BASEBOARD_FAB2(SCH_1):GND
  A38  GND            VSS<1181>  @BASEBOARD_FAB2_LIB.BASEBOARD_FAB2(SCH_1):GND
  B25  GND            VSS<1180>  @BASEBOARD_FAB2_LIB.BASEBOARD_FAB2(SCH_1):GND
  B31  GND            VSS<1179>  @BASEBOARD_FAB2_LIB.BASEBOARD_FAB2(SCH_1):GND
  B37  GND            VSS<1178>  @BASEBOARD_FAB2_LIB.BASEBOARD_FAB2(SCH_1):GND
  B71  GND            VSS<1177>  @BASEBOARD_FAB2_LIB.BASEBOARD_FAB2(SCH_1):GND
  B75  GND            VSS<1176>  @BASEBOARD_FAB2_LIB.BASEBOARD_FAB2(SCH_1):GND
   C8  GND            VSS<1175>  @BASEBOARD_FAB2_LIB.BASEBOARD_FAB2(SCH_1):GND
  C10  GND            VSS<1174>  @BASEBOARD_FAB2_LIB.BASEBOARD_FAB2(SCH_1):GND
  C12  GND            VSS<1173>  @BASEBOARD_FAB2_LIB.BASEBOARD_FAB2(SCH_1):GND
  C14  GND            VSS<1172>  @BASEBOARD_FAB2_LIB.BASEBOARD_FAB2(SCH_1):GND
  C16  GND            VSS<1171>  @BASEBOARD_FAB2_LIB.BASEBOARD_FAB2(SCH_1):GND
  C76  GND            VSS<1170>  @BASEBOARD_FAB2_LIB.BASEBOARD_FAB2(SCH_1):GND
  C78  GND            VSS<1169>  @BASEBOARD_FAB2_LIB.BASEBOARD_FAB2(SCH_1):GND
  CM27  GND            VSS<1168>  @BASEBOARD_FAB2_LIB.BASEBOARD_FAB2(SCH_1):GND
  D11  GND            VSS<1167>  @BASEBOARD_FAB2_LIB.BASEBOARD_FAB2(SCH_1):GND
  D13  GND            VSS<1166>  @BASEBOARD_FAB2_LIB.BASEBOARD_FAB2(SCH_1):GND
  D25  GND            VSS<1165>  @BASEBOARD_FAB2_LIB.BASEBOARD_FAB2(SCH_1):GND
  D27  GND            VSS<1164>  @BASEBOARD_FAB2_LIB.BASEBOARD_FAB2(SCH_1):GND
  D29  GND            VSS<1163>  @BASEBOARD_FAB2_LIB.BASEBOARD_FAB2(SCH_1):GND
  D31  GND            VSS<1162>  @BASEBOARD_FAB2_LIB.BASEBOARD_FAB2(SCH_1):GND
  D33  GND            VSS<1161>  @BASEBOARD_FAB2_LIB.BASEBOARD_FAB2(SCH_1):GND
  D35  GND            VSS<1160>  @BASEBOARD_FAB2_LIB.BASEBOARD_FAB2(SCH_1):GND
  D37  GND            VSS<1159>  @BASEBOARD_FAB2_LIB.BASEBOARD_FAB2(SCH_1):GND
  D39  GND            VSS<1158>  @BASEBOARD_FAB2_LIB.BASEBOARD_FAB2(SCH_1):GND
  D41  GND            VSS<1157>  @BASEBOARD_FAB2_LIB.BASEBOARD_FAB2(SCH_1):GND
  D43  GND            VSS<1156>  @BASEBOARD_FAB2_LIB.BASEBOARD_FAB2(SCH_1):GND
  D77  GND            VSS<1155>  @BASEBOARD_FAB2_LIB.BASEBOARD_FAB2(SCH_1):GND
   E6  GND            VSS<1154>  @BASEBOARD_FAB2_LIB.BASEBOARD_FAB2(SCH_1):GND
   E8  GND            VSS<1153>  @BASEBOARD_FAB2_LIB.BASEBOARD_FAB2(SCH_1):GND
  E16  GND            VSS<1152>  @BASEBOARD_FAB2_LIB.BASEBOARD_FAB2(SCH_1):GND
  E18  GND            VSS<1151>  @BASEBOARD_FAB2_LIB.BASEBOARD_FAB2(SCH_1):GND
  E20  GND            VSS<1150>  @BASEBOARD_FAB2_LIB.BASEBOARD_FAB2(SCH_1):GND
  E22  GND            VSS<1149>  @BASEBOARD_FAB2_LIB.BASEBOARD_FAB2(SCH_1):GND
  E72  GND            VSS<1148>  @BASEBOARD_FAB2_LIB.BASEBOARD_FAB2(SCH_1):GND
  E74  GND            VSS<1147>  @BASEBOARD_FAB2_LIB.BASEBOARD_FAB2(SCH_1):GND
  E76  GND            VSS<1146>  @BASEBOARD_FAB2_LIB.BASEBOARD_FAB2(SCH_1):GND
   F5  GND            VSS<1145>  @BASEBOARD_FAB2_LIB.BASEBOARD_FAB2(SCH_1):GND
  F17  GND            VSS<1144>  @BASEBOARD_FAB2_LIB.BASEBOARD_FAB2(SCH_1):GND
  F19  GND            VSS<1143>  @BASEBOARD_FAB2_LIB.BASEBOARD_FAB2(SCH_1):GND
  F25  GND            VSS<1142>  @BASEBOARD_FAB2_LIB.BASEBOARD_FAB2(SCH_1):GND
  F31  GND            VSS<1141>  @BASEBOARD_FAB2_LIB.BASEBOARD_FAB2(SCH_1):GND
  F37  GND            VSS<1140>  @BASEBOARD_FAB2_LIB.BASEBOARD_FAB2(SCH_1):GND
  F43  GND            VSS<1139>  @BASEBOARD_FAB2_LIB.BASEBOARD_FAB2(SCH_1):GND
  F67  GND            VSS<1138>  @BASEBOARD_FAB2_LIB.BASEBOARD_FAB2(SCH_1):GND
  F69  GND            VSS<1137>  @BASEBOARD_FAB2_LIB.BASEBOARD_FAB2(SCH_1):GND
   G4  GND            VSS<1136>  @BASEBOARD_FAB2_LIB.BASEBOARD_FAB2(SCH_1):GND
   G8  GND            VSS<1135>  @BASEBOARD_FAB2_LIB.BASEBOARD_FAB2(SCH_1):GND
  G22  GND            VSS<1134>  @BASEBOARD_FAB2_LIB.BASEBOARD_FAB2(SCH_1):GND
  G24  GND            VSS<1133>  @BASEBOARD_FAB2_LIB.BASEBOARD_FAB2(SCH_1):GND
  G26  GND            VSS<1132>  @BASEBOARD_FAB2_LIB.BASEBOARD_FAB2(SCH_1):GND
  G30  GND            VSS<1131>  @BASEBOARD_FAB2_LIB.BASEBOARD_FAB2(SCH_1):GND
  G32  GND            VSS<1130>  @BASEBOARD_FAB2_LIB.BASEBOARD_FAB2(SCH_1):GND
  G36  GND            VSS<1129>  @BASEBOARD_FAB2_LIB.BASEBOARD_FAB2(SCH_1):GND
  G38  GND            VSS<1128>  @BASEBOARD_FAB2_LIB.BASEBOARD_FAB2(SCH_1):GND
  G42  GND            VSS<1127>  @BASEBOARD_FAB2_LIB.BASEBOARD_FAB2(SCH_1):GND
  G66  GND            VSS<1126>  @BASEBOARD_FAB2_LIB.BASEBOARD_FAB2(SCH_1):GND
  G70  GND            VSS<1125>  @BASEBOARD_FAB2_LIB.BASEBOARD_FAB2(SCH_1):GND
  G76  GND            VSS<1124>  @BASEBOARD_FAB2_LIB.BASEBOARD_FAB2(SCH_1):GND
  G78  GND            VSS<1123>  @BASEBOARD_FAB2_LIB.BASEBOARD_FAB2(SCH_1):GND
  G80  GND            VSS<1122>  @BASEBOARD_FAB2_LIB.BASEBOARD_FAB2(SCH_1):GND
  G82  GND            VSS<1121>  @BASEBOARD_FAB2_LIB.BASEBOARD_FAB2(SCH_1):GND
   H3  GND            VSS<1120>  @BASEBOARD_FAB2_LIB.BASEBOARD_FAB2(SCH_1):GND
  H11  GND            VSS<1119>  @BASEBOARD_FAB2_LIB.BASEBOARD_FAB2(SCH_1):GND
  H25  GND            VSS<1118>  @BASEBOARD_FAB2_LIB.BASEBOARD_FAB2(SCH_1):GND
  H27  GND            VSS<1117>  @BASEBOARD_FAB2_LIB.BASEBOARD_FAB2(SCH_1):GND
  H29  GND            VSS<1116>  @BASEBOARD_FAB2_LIB.BASEBOARD_FAB2(SCH_1):GND
  H31  GND            VSS<1115>  @BASEBOARD_FAB2_LIB.BASEBOARD_FAB2(SCH_1):GND
  H33  GND            VSS<1114>  @BASEBOARD_FAB2_LIB.BASEBOARD_FAB2(SCH_1):GND
  H35  GND            VSS<1113>  @BASEBOARD_FAB2_LIB.BASEBOARD_FAB2(SCH_1):GND
  H37  GND            VSS<1112>  @BASEBOARD_FAB2_LIB.BASEBOARD_FAB2(SCH_1):GND
  H39  GND            VSS<1111>  @BASEBOARD_FAB2_LIB.BASEBOARD_FAB2(SCH_1):GND
  H41  GND            VSS<1110>  @BASEBOARD_FAB2_LIB.BASEBOARD_FAB2(SCH_1):GND
  H65  GND            VSS<1109>  @BASEBOARD_FAB2_LIB.BASEBOARD_FAB2(SCH_1):GND
  H71  GND            VSS<1108>  @BASEBOARD_FAB2_LIB.BASEBOARD_FAB2(SCH_1):GND
  H75  GND            VSS<1107>  @BASEBOARD_FAB2_LIB.BASEBOARD_FAB2(SCH_1):GND
  DN44  GND            VSS<1106>  @BASEBOARD_FAB2_LIB.BASEBOARD_FAB2(SCH_1):GND
   J4  GND            VSS<1105>  @BASEBOARD_FAB2_LIB.BASEBOARD_FAB2(SCH_1):GND
  J12  GND            VSS<1104>  @BASEBOARD_FAB2_LIB.BASEBOARD_FAB2(SCH_1):GND
  J14  GND            VSS<1103>  @BASEBOARD_FAB2_LIB.BASEBOARD_FAB2(SCH_1):GND
  J22  GND            VSS<1102>  @BASEBOARD_FAB2_LIB.BASEBOARD_FAB2(SCH_1):GND
  J26  GND            VSS<1101>  @BASEBOARD_FAB2_LIB.BASEBOARD_FAB2(SCH_1):GND
  J28  GND            VSS<1100>  @BASEBOARD_FAB2_LIB.BASEBOARD_FAB2(SCH_1):GND
  J32  GND            VSS<1099>  @BASEBOARD_FAB2_LIB.BASEBOARD_FAB2(SCH_1):GND
  J34  GND            VSS<1098>  @BASEBOARD_FAB2_LIB.BASEBOARD_FAB2(SCH_1):GND
  J38  GND            VSS<1097>  @BASEBOARD_FAB2_LIB.BASEBOARD_FAB2(SCH_1):GND
  J40  GND            VSS<1096>  @BASEBOARD_FAB2_LIB.BASEBOARD_FAB2(SCH_1):GND
  J72  GND            VSS<1095>  @BASEBOARD_FAB2_LIB.BASEBOARD_FAB2(SCH_1):GND
  J74  GND            VSS<1094>  @BASEBOARD_FAB2_LIB.BASEBOARD_FAB2(SCH_1):GND

SKX_EXT_B_BGA1  I127  U5D1   [SKX_EXT_B_BGA1-IC,TBD]
  CE76  VSENSE_PVSA_CPU0_SKT_VSEN  VCCSA_SENSE  @BASEBOARD_FAB2_LIB.BASEBOARD_FAB2(SCH_1):VSENSE_PVSA_CPU0_SKT_VSEN
  CG76  VSENSE_PVSA_CPU0_SKT_VRTN  VSS_VCCSA_SENSE  @BASEBOARD_FAB2_LIB.BASEBOARD_FAB2(SCH_1):VSENSE_PVSA_CPU0_SKT_VRTN
  BN16  VSENSE_PVCCMCP_CPU0_SKT_VSEN  CD_VCC_CORE_SENSE  @BASEBOARD_FAB2_LIB.BASEBOARD_FAB2(SCH_1):VSENSE_PVCCMCP_CPU0_SKT_VSEN
  BL16  VSENSE_PVCCMCP_CPU0_SKT_VRTN  CD_VSS_VCC_CORE_SENSE  @BASEBOARD_FAB2_LIB.BASEBOARD_FAB2(SCH_1):VSENSE_PVCCMCP_CPU0_SKT_VRTN
  BH5  VSENSE_PVCCIO_CPU0_SKT_VSEN  VCCIO_SENSE  @BASEBOARD_FAB2_LIB.BASEBOARD_FAB2(SCH_1):VSENSE_PVCCIO_CPU0_SKT_VSEN
  BF5  VSENSE_PVCCIO_CPU0_SKT_VRTN  VSS_VCCIO_SENSE  @BASEBOARD_FAB2_LIB.BASEBOARD_FAB2(SCH_1):VSENSE_PVCCIO_CPU0_SKT_VRTN
  BT17  VSENSE_PVCCIOMCP_CPU0_SKT_VSEN  CD_VCCP_SENSE<1>  @BASEBOARD_FAB2_LIB.BASEBOARD_FAB2(SCH_1):VSENSE_PVCCIOMCP_CPU0_SKT_VSEN
  BU16  VSENSE_PVCCIOMCP_CPU0_SKT_VRTN  CD_VCCP_SENSE<0>  @BASEBOARD_FAB2_LIB.BASEBOARD_FAB2(SCH_1):VSENSE_PVCCIOMCP_CPU0_SKT_VRTN
  ED83  TP_CPU0_RSVD_9  RSVD<9>  @BASEBOARD_FAB2_LIB.BASEBOARD_FAB2(SCH_1):TP_CPU0_RSVD_9
  EE16  TP_CPU0_RSVD_8  RSVD<8>  @BASEBOARD_FAB2_LIB.BASEBOARD_FAB2(SCH_1):TP_CPU0_RSVD_8
  CP31  TP_CPU0_RSVD_73  RSVD<73>  @BASEBOARD_FAB2_LIB.BASEBOARD_FAB2(SCH_1):TP_CPU0_RSVD_73
  CR60  TP_CPU0_RSVD_72  RSVD<72>  @BASEBOARD_FAB2_LIB.BASEBOARD_FAB2(SCH_1):TP_CPU0_RSVD_72
  CT5  TP_CPU0_RSVD_70  RSVD<70>  @BASEBOARD_FAB2_LIB.BASEBOARD_FAB2(SCH_1):TP_CPU0_RSVD_70
  EE46  TP_CPU0_RSVD_7  RSVD<7>  @BASEBOARD_FAB2_LIB.BASEBOARD_FAB2(SCH_1):TP_CPU0_RSVD_7
  CT69  TP_CPU0_RSVD_69  RSVD<69>  @BASEBOARD_FAB2_LIB.BASEBOARD_FAB2(SCH_1):TP_CPU0_RSVD_69
  CU6  TP_CPU0_RSVD_67  RSVD<67>  @BASEBOARD_FAB2_LIB.BASEBOARD_FAB2(SCH_1):TP_CPU0_RSVD_67
  CU60  TP_CPU0_RSVD_66  RSVD<66>  @BASEBOARD_FAB2_LIB.BASEBOARD_FAB2(SCH_1):TP_CPU0_RSVD_66
  CV69  TP_CPU0_RSVD_64  RSVD<64>  @BASEBOARD_FAB2_LIB.BASEBOARD_FAB2(SCH_1):TP_CPU0_RSVD_64
  CW60  TP_CPU0_RSVD_61  RSVD<61>  @BASEBOARD_FAB2_LIB.BASEBOARD_FAB2(SCH_1):TP_CPU0_RSVD_61
  CW62  TP_CPU0_RSVD_60  RSVD<60>  @BASEBOARD_FAB2_LIB.BASEBOARD_FAB2(SCH_1):TP_CPU0_RSVD_60
  EE6  TP_CPU0_RSVD_6  RSVD<6>  @BASEBOARD_FAB2_LIB.BASEBOARD_FAB2(SCH_1):TP_CPU0_RSVD_6
  CY23  TP_CPU0_RSVD_59  RSVD<59>  @BASEBOARD_FAB2_LIB.BASEBOARD_FAB2(SCH_1):TP_CPU0_RSVD_59
  CY39  TP_CPU0_RSVD_57  RSVD<57>  @BASEBOARD_FAB2_LIB.BASEBOARD_FAB2(SCH_1):TP_CPU0_RSVD_57
  CY53  TP_CPU0_RSVD_56  RSVD<56>  @BASEBOARD_FAB2_LIB.BASEBOARD_FAB2(SCH_1):TP_CPU0_RSVD_56
  CY57  TP_CPU0_RSVD_55  RSVD<55>  @BASEBOARD_FAB2_LIB.BASEBOARD_FAB2(SCH_1):TP_CPU0_RSVD_55
  CY63  TP_CPU0_RSVD_54  RSVD<54>  @BASEBOARD_FAB2_LIB.BASEBOARD_FAB2(SCH_1):TP_CPU0_RSVD_54
  CY73  TP_CPU0_RSVD_53  RSVD<53>  @BASEBOARD_FAB2_LIB.BASEBOARD_FAB2(SCH_1):TP_CPU0_RSVD_53
  DA40  TP_CPU0_RSVD_51  RSVD<51>  @BASEBOARD_FAB2_LIB.BASEBOARD_FAB2(SCH_1):TP_CPU0_RSVD_51
  DA52  TP_CPU0_RSVD_50  RSVD<50>  @BASEBOARD_FAB2_LIB.BASEBOARD_FAB2(SCH_1):TP_CPU0_RSVD_50
  EE82  TP_CPU0_RSVD_5  RSVD<5>  @BASEBOARD_FAB2_LIB.BASEBOARD_FAB2(SCH_1):TP_CPU0_RSVD_5
  DA54  TP_CPU0_RSVD_49  RSVD<49>  @BASEBOARD_FAB2_LIB.BASEBOARD_FAB2(SCH_1):TP_CPU0_RSVD_49
  DA56  TP_CPU0_RSVD_48  RSVD<48>  @BASEBOARD_FAB2_LIB.BASEBOARD_FAB2(SCH_1):TP_CPU0_RSVD_48
  DC46  TP_CPU0_RSVD_47  RSVD<47>  @BASEBOARD_FAB2_LIB.BASEBOARD_FAB2(SCH_1):TP_CPU0_RSVD_47
  DC52  TP_CPU0_RSVD_46  RSVD<46>  @BASEBOARD_FAB2_LIB.BASEBOARD_FAB2(SCH_1):TP_CPU0_RSVD_46
  DD51  TP_CPU0_RSVD_45  RSVD<45>  @BASEBOARD_FAB2_LIB.BASEBOARD_FAB2(SCH_1):TP_CPU0_RSVD_45
  DG36  TP_CPU0_RSVD_44  RSVD<44>  @BASEBOARD_FAB2_LIB.BASEBOARD_FAB2(SCH_1):TP_CPU0_RSVD_44
  DG64  TP_CPU0_RSVD_43  RSVD<43>  @BASEBOARD_FAB2_LIB.BASEBOARD_FAB2(SCH_1):TP_CPU0_RSVD_43
  DH65  TP_CPU0_RSVD_42  RSVD<42>  @BASEBOARD_FAB2_LIB.BASEBOARD_FAB2(SCH_1):TP_CPU0_RSVD_42
  DJ36  TP_CPU0_RSVD_41  RSVD<41>  @BASEBOARD_FAB2_LIB.BASEBOARD_FAB2(SCH_1):TP_CPU0_RSVD_41
  DJ66  TP_CPU0_RSVD_40  RSVD<40>  @BASEBOARD_FAB2_LIB.BASEBOARD_FAB2(SCH_1):TP_CPU0_RSVD_40
  EE84  TP_CPU0_RSVD_4  RSVD<4>  @BASEBOARD_FAB2_LIB.BASEBOARD_FAB2(SCH_1):TP_CPU0_RSVD_4
  DK15  TP_CPU0_RSVD_39  RSVD<39>  @BASEBOARD_FAB2_LIB.BASEBOARD_FAB2(SCH_1):TP_CPU0_RSVD_39
  DK37  TP_CPU0_RSVD_38  RSVD<38>  @BASEBOARD_FAB2_LIB.BASEBOARD_FAB2(SCH_1):TP_CPU0_RSVD_38
  DK65  TP_CPU0_RSVD_37  RSVD<37>  @BASEBOARD_FAB2_LIB.BASEBOARD_FAB2(SCH_1):TP_CPU0_RSVD_37
  DK67  TP_CPU0_RSVD_36  RSVD<36>  @BASEBOARD_FAB2_LIB.BASEBOARD_FAB2(SCH_1):TP_CPU0_RSVD_36
  DL38  TP_CPU0_RSVD_35  RSVD<35>  @BASEBOARD_FAB2_LIB.BASEBOARD_FAB2(SCH_1):TP_CPU0_RSVD_35
  DL66  TP_CPU0_RSVD_34  RSVD<34>  @BASEBOARD_FAB2_LIB.BASEBOARD_FAB2(SCH_1):TP_CPU0_RSVD_34
  DM67  TP_CPU0_RSVD_33  RSVD<33>  @BASEBOARD_FAB2_LIB.BASEBOARD_FAB2(SCH_1):TP_CPU0_RSVD_33
  DN62  TP_CPU0_RSVD_32  RSVD<32>  @BASEBOARD_FAB2_LIB.BASEBOARD_FAB2(SCH_1):TP_CPU0_RSVD_32
  DN66  TP_CPU0_RSVD_31  RSVD<31>  @BASEBOARD_FAB2_LIB.BASEBOARD_FAB2(SCH_1):TP_CPU0_RSVD_31
  DP17  TP_CPU0_RSVD_30  RSVD<30>  @BASEBOARD_FAB2_LIB.BASEBOARD_FAB2(SCH_1):TP_CPU0_RSVD_30
  EF47  TP_CPU0_RSVD_3  RSVD<3>  @BASEBOARD_FAB2_LIB.BASEBOARD_FAB2(SCH_1):TP_CPU0_RSVD_3
  DP65  TP_CPU0_RSVD_29  RSVD<29>  @BASEBOARD_FAB2_LIB.BASEBOARD_FAB2(SCH_1):TP_CPU0_RSVD_29
  DR44  TP_CPU0_RSVD_28  RSVD<28>  @BASEBOARD_FAB2_LIB.BASEBOARD_FAB2(SCH_1):TP_CPU0_RSVD_28
  DT71  TP_CPU0_RSVD_27  RSVD<27>  @BASEBOARD_FAB2_LIB.BASEBOARD_FAB2(SCH_1):TP_CPU0_RSVD_27
  DU44  TP_CPU0_RSVD_26  RSVD<26>  @BASEBOARD_FAB2_LIB.BASEBOARD_FAB2(SCH_1):TP_CPU0_RSVD_26
  DV61  TP_CPU0_RSVD_25  RSVD<25>  @BASEBOARD_FAB2_LIB.BASEBOARD_FAB2(SCH_1):TP_CPU0_RSVD_25
  DV71  TP_CPU0_RSVD_24  RSVD<24>  @BASEBOARD_FAB2_LIB.BASEBOARD_FAB2(SCH_1):TP_CPU0_RSVD_24
  DW44  TP_CPU0_RSVD_23  RSVD<23>  @BASEBOARD_FAB2_LIB.BASEBOARD_FAB2(SCH_1):TP_CPU0_RSVD_23
  DW46  TP_CPU0_RSVD_22  RSVD<22>  @BASEBOARD_FAB2_LIB.BASEBOARD_FAB2(SCH_1):TP_CPU0_RSVD_22
  DY3  TP_CPU0_RSVD_21  RSVD<21>  @BASEBOARD_FAB2_LIB.BASEBOARD_FAB2(SCH_1):TP_CPU0_RSVD_21
  EA4  TP_CPU0_RSVD_20  RSVD<20>  @BASEBOARD_FAB2_LIB.BASEBOARD_FAB2(SCH_1):TP_CPU0_RSVD_20
  EF77  TP_CPU0_RSVD_2  RSVD<2>  @BASEBOARD_FAB2_LIB.BASEBOARD_FAB2(SCH_1):TP_CPU0_RSVD_2
  EA44  TP_CPU0_RSVD_19  RSVD<19>  @BASEBOARD_FAB2_LIB.BASEBOARD_FAB2(SCH_1):TP_CPU0_RSVD_19
  EB3  TP_CPU0_RSVD_18  RSVD<18>  @BASEBOARD_FAB2_LIB.BASEBOARD_FAB2(SCH_1):TP_CPU0_RSVD_18
  EB5  TP_CPU0_RSVD_17  RSVD<17>  @BASEBOARD_FAB2_LIB.BASEBOARD_FAB2(SCH_1):TP_CPU0_RSVD_17
  EB85  TP_CPU0_RSVD_16  RSVD<16>  @BASEBOARD_FAB2_LIB.BASEBOARD_FAB2(SCH_1):TP_CPU0_RSVD_16
  EC16  TP_CPU0_RSVD_15  RSVD<15>  @BASEBOARD_FAB2_LIB.BASEBOARD_FAB2(SCH_1):TP_CPU0_RSVD_15
  EC4  TP_CPU0_RSVD_14  RSVD<14>  @BASEBOARD_FAB2_LIB.BASEBOARD_FAB2(SCH_1):TP_CPU0_RSVD_14
  EC44  TP_CPU0_RSVD_13  RSVD<13>  @BASEBOARD_FAB2_LIB.BASEBOARD_FAB2(SCH_1):TP_CPU0_RSVD_13
  EC84  TP_CPU0_RSVD_12  RSVD<12>  @BASEBOARD_FAB2_LIB.BASEBOARD_FAB2(SCH_1):TP_CPU0_RSVD_12
  ED45  TP_CPU0_RSVD_11  RSVD<11>  @BASEBOARD_FAB2_LIB.BASEBOARD_FAB2(SCH_1):TP_CPU0_RSVD_11
  ED5  TP_CPU0_RSVD_10  RSVD<10>  @BASEBOARD_FAB2_LIB.BASEBOARD_FAB2(SCH_1):TP_CPU0_RSVD_10
  EF81  TP_CPU0_RSVD_1  RSVD<1>  @BASEBOARD_FAB2_LIB.BASEBOARD_FAB2(SCH_1):TP_CPU0_RSVD_1
  EF83  TP_CPU0_RSVD_0  RSVD<0>  @BASEBOARD_FAB2_LIB.BASEBOARD_FAB2(SCH_1):TP_CPU0_RSVD_0
  CW22  TP_CPU0_KTI2_DFX_DN  RSVD<63>  @BASEBOARD_FAB2_LIB.BASEBOARD_FAB2(SCH_1):TP_CPU0_KTI2_DFX_DN
  CN22  TP_CPU0_KTI2_AMONV  RSVD<77>  @BASEBOARD_FAB2_LIB.BASEBOARD_FAB2(SCH_1):TP_CPU0_KTI2_AMONV
  CL26  PVCCMCP_CPU0   RSVD<80>  @BASEBOARD_FAB2_LIB.BASEBOARD_FAB2(SCH_1):PVCCMCP_CPU0
  CM23  PVCCMCP_CPU0   RSVD<79>  @BASEBOARD_FAB2_LIB.BASEBOARD_FAB2(SCH_1):PVCCMCP_CPU0
  CM25  PVCCMCP_CPU0   RSVD<78>  @BASEBOARD_FAB2_LIB.BASEBOARD_FAB2(SCH_1):PVCCMCP_CPU0
  CN24  PVCCMCP_CPU0   RSVD<76>  @BASEBOARD_FAB2_LIB.BASEBOARD_FAB2(SCH_1):PVCCMCP_CPU0
  CP23  PVCCMCP_CPU0   RSVD<74>  @BASEBOARD_FAB2_LIB.BASEBOARD_FAB2(SCH_1):PVCCMCP_CPU0
  CT23  PVCCMCP_CPU0   RSVD<71>  @BASEBOARD_FAB2_LIB.BASEBOARD_FAB2(SCH_1):PVCCMCP_CPU0
  CU24  PVCCMCP_CPU0   RSVD<68>  @BASEBOARD_FAB2_LIB.BASEBOARD_FAB2(SCH_1):PVCCMCP_CPU0
  CV23  PVCCMCP_CPU0   RSVD<65>  @BASEBOARD_FAB2_LIB.BASEBOARD_FAB2(SCH_1):PVCCMCP_CPU0
  CW24  PVCCMCP_CPU0   RSVD<62>  @BASEBOARD_FAB2_LIB.BASEBOARD_FAB2(SCH_1):PVCCMCP_CPU0
  CY25  PVCCMCP_CPU0   RSVD<58>  @BASEBOARD_FAB2_LIB.BASEBOARD_FAB2(SCH_1):PVCCMCP_CPU0
  DA24  PVCCMCP_CPU0   RSVD<52>  @BASEBOARD_FAB2_LIB.BASEBOARD_FAB2(SCH_1):PVCCMCP_CPU0
  CN6  PVCCIO_CPU0    VCCIO<19>  @BASEBOARD_FAB2_LIB.BASEBOARD_FAB2(SCH_1):PVCCIO_CPU0
  CU12  PVCCIO_CPU0    VCCIO<18>  @BASEBOARD_FAB2_LIB.BASEBOARD_FAB2(SCH_1):PVCCIO_CPU0
  CV21  PVCCIO_CPU0    VCCIO<17>  @BASEBOARD_FAB2_LIB.BASEBOARD_FAB2(SCH_1):PVCCIO_CPU0
  CU18  PVCCIO_CPU0    VCCIO<16>  @BASEBOARD_FAB2_LIB.BASEBOARD_FAB2(SCH_1):PVCCIO_CPU0
  CY17  PVCCIO_CPU0    VCCIO<15>  @BASEBOARD_FAB2_LIB.BASEBOARD_FAB2(SCH_1):PVCCIO_CPU0
  DC18  PVCCIO_CPU0    VCCIO<14>  @BASEBOARD_FAB2_LIB.BASEBOARD_FAB2(SCH_1):PVCCIO_CPU0
  DE14  PVCCIO_CPU0    VCCIO<13>  @BASEBOARD_FAB2_LIB.BASEBOARD_FAB2(SCH_1):PVCCIO_CPU0
  CP13  PVCCIO_CPU0    VCCIO<12>  @BASEBOARD_FAB2_LIB.BASEBOARD_FAB2(SCH_1):PVCCIO_CPU0
  CL20  PVCCIO_CPU0    VCCIO<11>  @BASEBOARD_FAB2_LIB.BASEBOARD_FAB2(SCH_1):PVCCIO_CPU0
  CG14  PVCCIO_CPU0    VCCIO<10>  @BASEBOARD_FAB2_LIB.BASEBOARD_FAB2(SCH_1):PVCCIO_CPU0
  CF5  PVCCIO_CPU0    VCCIO<9>  @BASEBOARD_FAB2_LIB.BASEBOARD_FAB2(SCH_1):PVCCIO_CPU0
  DK21  PVCCIO_CPU0    VCCIO<8>  @BASEBOARD_FAB2_LIB.BASEBOARD_FAB2(SCH_1):PVCCIO_CPU0
  BE24  PVCCIO_CPU0    VCCIO<7>  @BASEBOARD_FAB2_LIB.BASEBOARD_FAB2(SCH_1):PVCCIO_CPU0
  AT7  PVCCIO_CPU0    VCCIO<6>  @BASEBOARD_FAB2_LIB.BASEBOARD_FAB2(SCH_1):PVCCIO_CPU0
  AT5  PVCCIO_CPU0    VCCIO<5>  @BASEBOARD_FAB2_LIB.BASEBOARD_FAB2(SCH_1):PVCCIO_CPU0
  AM5  PVCCIO_CPU0    VCCIO<4>  @BASEBOARD_FAB2_LIB.BASEBOARD_FAB2(SCH_1):PVCCIO_CPU0
  DV11  PVCCIO_CPU0    VCCIO<3>  @BASEBOARD_FAB2_LIB.BASEBOARD_FAB2(SCH_1):PVCCIO_CPU0
  AF5  PVCCIO_CPU0    VCCIO<2>  @BASEBOARD_FAB2_LIB.BASEBOARD_FAB2(SCH_1):PVCCIO_CPU0
  AE10  PVCCIO_CPU0    VCCIO<1>  @BASEBOARD_FAB2_LIB.BASEBOARD_FAB2(SCH_1):PVCCIO_CPU0
  EE10  PVCCIO_CPU0    VCCIO<0>  @BASEBOARD_FAB2_LIB.BASEBOARD_FAB2(SCH_1):PVCCIO_CPU0
  CN28  PD_CPU0_MCP01_DMON  RSVD<75>  @BASEBOARD_FAB2_LIB.BASEBOARD_FAB2(SCH_1):PD_CPU0_MCP01_DMON

SKX_EXT_B_BGA1  I34  U5D1   [SKX_EXT_B_BGA1-IC,TBD]
  CB65  PVSA_CPU0      VCCSA<25>  @BASEBOARD_FAB2_LIB.BASEBOARD_FAB2(SCH_1):PVSA_CPU0
  CB67  PVSA_CPU0      VCCSA<24>  @BASEBOARD_FAB2_LIB.BASEBOARD_FAB2(SCH_1):PVSA_CPU0
  CB69  PVSA_CPU0      VCCSA<23>  @BASEBOARD_FAB2_LIB.BASEBOARD_FAB2(SCH_1):PVSA_CPU0
  CC66  PVSA_CPU0      VCCSA<22>  @BASEBOARD_FAB2_LIB.BASEBOARD_FAB2(SCH_1):PVSA_CPU0
  CC68  PVSA_CPU0      VCCSA<21>  @BASEBOARD_FAB2_LIB.BASEBOARD_FAB2(SCH_1):PVSA_CPU0
  CC70  PVSA_CPU0      VCCSA<20>  @BASEBOARD_FAB2_LIB.BASEBOARD_FAB2(SCH_1):PVSA_CPU0
  CD65  PVSA_CPU0      VCCSA<19>  @BASEBOARD_FAB2_LIB.BASEBOARD_FAB2(SCH_1):PVSA_CPU0
  CD67  PVSA_CPU0      VCCSA<18>  @BASEBOARD_FAB2_LIB.BASEBOARD_FAB2(SCH_1):PVSA_CPU0
  CD69  PVSA_CPU0      VCCSA<17>  @BASEBOARD_FAB2_LIB.BASEBOARD_FAB2(SCH_1):PVSA_CPU0
  CD71  PVSA_CPU0      VCCSA<16>  @BASEBOARD_FAB2_LIB.BASEBOARD_FAB2(SCH_1):PVSA_CPU0
  CE64  PVSA_CPU0      VCCSA<15>  @BASEBOARD_FAB2_LIB.BASEBOARD_FAB2(SCH_1):PVSA_CPU0
  CE66  PVSA_CPU0      VCCSA<14>  @BASEBOARD_FAB2_LIB.BASEBOARD_FAB2(SCH_1):PVSA_CPU0
  CE68  PVSA_CPU0      VCCSA<13>  @BASEBOARD_FAB2_LIB.BASEBOARD_FAB2(SCH_1):PVSA_CPU0
  CE72  PVSA_CPU0      VCCSA<12>  @BASEBOARD_FAB2_LIB.BASEBOARD_FAB2(SCH_1):PVSA_CPU0
  CE74  PVSA_CPU0      VCCSA<11>  @BASEBOARD_FAB2_LIB.BASEBOARD_FAB2(SCH_1):PVSA_CPU0
  CF65  PVSA_CPU0      VCCSA<10>  @BASEBOARD_FAB2_LIB.BASEBOARD_FAB2(SCH_1):PVSA_CPU0
  CF67  PVSA_CPU0      VCCSA<9>  @BASEBOARD_FAB2_LIB.BASEBOARD_FAB2(SCH_1):PVSA_CPU0
  CF73  PVSA_CPU0      VCCSA<8>  @BASEBOARD_FAB2_LIB.BASEBOARD_FAB2(SCH_1):PVSA_CPU0
  CF75  PVSA_CPU0      VCCSA<7>  @BASEBOARD_FAB2_LIB.BASEBOARD_FAB2(SCH_1):PVSA_CPU0
  CG64  PVSA_CPU0      VCCSA<6>  @BASEBOARD_FAB2_LIB.BASEBOARD_FAB2(SCH_1):PVSA_CPU0
  CG66  PVSA_CPU0      VCCSA<5>  @BASEBOARD_FAB2_LIB.BASEBOARD_FAB2(SCH_1):PVSA_CPU0
  CG74  PVSA_CPU0      VCCSA<4>  @BASEBOARD_FAB2_LIB.BASEBOARD_FAB2(SCH_1):PVSA_CPU0
  CH65  PVSA_CPU0      VCCSA<3>  @BASEBOARD_FAB2_LIB.BASEBOARD_FAB2(SCH_1):PVSA_CPU0
  CH75  PVSA_CPU0      VCCSA<2>  @BASEBOARD_FAB2_LIB.BASEBOARD_FAB2(SCH_1):PVSA_CPU0
  CJ64  PVSA_CPU0      VCCSA<1>  @BASEBOARD_FAB2_LIB.BASEBOARD_FAB2(SCH_1):PVSA_CPU0
  CJ66  PVSA_CPU0      VCCSA<0>  @BASEBOARD_FAB2_LIB.BASEBOARD_FAB2(SCH_1):PVSA_CPU0
   A8  PVPP_ABC       CD_VPP<3>  @BASEBOARD_FAB2_LIB.BASEBOARD_FAB2(SCH_1):PVPP_ABC
  A10  PVPP_ABC       CD_VPP<2>  @BASEBOARD_FAB2_LIB.BASEBOARD_FAB2(SCH_1):PVPP_ABC
  A12  PVPP_ABC       CD_VPP<1>  @BASEBOARD_FAB2_LIB.BASEBOARD_FAB2(SCH_1):PVPP_ABC
  B11  PVPP_ABC       CD_VPP<0>  @BASEBOARD_FAB2_LIB.BASEBOARD_FAB2(SCH_1):PVPP_ABC
  BD13  PVCCMCP_CPU0   CD_VCC_CORE<12>  @BASEBOARD_FAB2_LIB.BASEBOARD_FAB2(SCH_1):PVCCMCP_CPU0
  BE12  PVCCMCP_CPU0   CD_VCC_CORE<11>  @BASEBOARD_FAB2_LIB.BASEBOARD_FAB2(SCH_1):PVCCMCP_CPU0
  BE14  PVCCMCP_CPU0   CD_VCC_CORE<10>  @BASEBOARD_FAB2_LIB.BASEBOARD_FAB2(SCH_1):PVCCMCP_CPU0
  BF11  PVCCMCP_CPU0   CD_VCC_CORE<9>  @BASEBOARD_FAB2_LIB.BASEBOARD_FAB2(SCH_1):PVCCMCP_CPU0
  BF13  PVCCMCP_CPU0   CD_VCC_CORE<8>  @BASEBOARD_FAB2_LIB.BASEBOARD_FAB2(SCH_1):PVCCMCP_CPU0
  BG12  PVCCMCP_CPU0   CD_VCC_CORE<7>  @BASEBOARD_FAB2_LIB.BASEBOARD_FAB2(SCH_1):PVCCMCP_CPU0
  BG14  PVCCMCP_CPU0   CD_VCC_CORE<6>  @BASEBOARD_FAB2_LIB.BASEBOARD_FAB2(SCH_1):PVCCMCP_CPU0
  BH13  PVCCMCP_CPU0   CD_VCC_CORE<5>  @BASEBOARD_FAB2_LIB.BASEBOARD_FAB2(SCH_1):PVCCMCP_CPU0
  BJ12  PVCCMCP_CPU0   CD_VCC_CORE<4>  @BASEBOARD_FAB2_LIB.BASEBOARD_FAB2(SCH_1):PVCCMCP_CPU0
  BJ14  PVCCMCP_CPU0   CD_VCC_CORE<3>  @BASEBOARD_FAB2_LIB.BASEBOARD_FAB2(SCH_1):PVCCMCP_CPU0
  BK13  PVCCMCP_CPU0   CD_VCC_CORE<2>  @BASEBOARD_FAB2_LIB.BASEBOARD_FAB2(SCH_1):PVCCMCP_CPU0
  BK15  PVCCMCP_CPU0   CD_VCC_CORE<1>  @BASEBOARD_FAB2_LIB.BASEBOARD_FAB2(SCH_1):PVCCMCP_CPU0
  BL14  PVCCMCP_CPU0   CD_VCC_CORE<0>  @BASEBOARD_FAB2_LIB.BASEBOARD_FAB2(SCH_1):PVCCMCP_CPU0
  AR28  PVCCIO_CPU0    VCCIO<104>  @BASEBOARD_FAB2_LIB.BASEBOARD_FAB2(SCH_1):PVCCIO_CPU0
  AL28  PVCCIO_CPU0    VCCIO<103>  @BASEBOARD_FAB2_LIB.BASEBOARD_FAB2(SCH_1):PVCCIO_CPU0
  AM29  PVCCIO_CPU0    VCCIO<102>  @BASEBOARD_FAB2_LIB.BASEBOARD_FAB2(SCH_1):PVCCIO_CPU0
  AG34  PVCCIO_CPU0    VCCIO<101>  @BASEBOARD_FAB2_LIB.BASEBOARD_FAB2(SCH_1):PVCCIO_CPU0
  AE34  PVCCIO_CPU0    VCCIO<100>  @BASEBOARD_FAB2_LIB.BASEBOARD_FAB2(SCH_1):PVCCIO_CPU0
  AD35  PVCCIO_CPU0    VCCIO<99>  @BASEBOARD_FAB2_LIB.BASEBOARD_FAB2(SCH_1):PVCCIO_CPU0
  AF35  PVCCIO_CPU0    VCCIO<98>  @BASEBOARD_FAB2_LIB.BASEBOARD_FAB2(SCH_1):PVCCIO_CPU0
  AC36  PVCCIO_CPU0    VCCIO<97>  @BASEBOARD_FAB2_LIB.BASEBOARD_FAB2(SCH_1):PVCCIO_CPU0
  AD37  PVCCIO_CPU0    VCCIO<96>  @BASEBOARD_FAB2_LIB.BASEBOARD_FAB2(SCH_1):PVCCIO_CPU0
  AE36  PVCCIO_CPU0    VCCIO<95>  @BASEBOARD_FAB2_LIB.BASEBOARD_FAB2(SCH_1):PVCCIO_CPU0
  BF27  PVCCIO_CPU0    VCCIO<94>  @BASEBOARD_FAB2_LIB.BASEBOARD_FAB2(SCH_1):PVCCIO_CPU0
  BG26  PVCCIO_CPU0    VCCIO<93>  @BASEBOARD_FAB2_LIB.BASEBOARD_FAB2(SCH_1):PVCCIO_CPU0
  BH25  PVCCIO_CPU0    VCCIO<92>  @BASEBOARD_FAB2_LIB.BASEBOARD_FAB2(SCH_1):PVCCIO_CPU0
  BH27  PVCCIO_CPU0    VCCIO<91>  @BASEBOARD_FAB2_LIB.BASEBOARD_FAB2(SCH_1):PVCCIO_CPU0
  BJ26  PVCCIO_CPU0    VCCIO<90>  @BASEBOARD_FAB2_LIB.BASEBOARD_FAB2(SCH_1):PVCCIO_CPU0
  BK25  PVCCIO_CPU0    VCCIO<89>  @BASEBOARD_FAB2_LIB.BASEBOARD_FAB2(SCH_1):PVCCIO_CPU0
  BK27  PVCCIO_CPU0    VCCIO<88>  @BASEBOARD_FAB2_LIB.BASEBOARD_FAB2(SCH_1):PVCCIO_CPU0
  BL26  PVCCIO_CPU0    VCCIO<87>  @BASEBOARD_FAB2_LIB.BASEBOARD_FAB2(SCH_1):PVCCIO_CPU0
  BM27  PVCCIO_CPU0    VCCIO<86>  @BASEBOARD_FAB2_LIB.BASEBOARD_FAB2(SCH_1):PVCCIO_CPU0
  CH27  PVCCIO_CPU0    VCCIO<85>  @BASEBOARD_FAB2_LIB.BASEBOARD_FAB2(SCH_1):PVCCIO_CPU0
  CJ28  PVCCIO_CPU0    VCCIO<84>  @BASEBOARD_FAB2_LIB.BASEBOARD_FAB2(SCH_1):PVCCIO_CPU0
  CC26  PVCCIO_CPU0    VCCIO<83>  @BASEBOARD_FAB2_LIB.BASEBOARD_FAB2(SCH_1):PVCCIO_CPU0
  CD27  PVCCIO_CPU0    VCCIO<82>  @BASEBOARD_FAB2_LIB.BASEBOARD_FAB2(SCH_1):PVCCIO_CPU0
  CF27  PVCCIO_CPU0    VCCIO<81>  @BASEBOARD_FAB2_LIB.BASEBOARD_FAB2(SCH_1):PVCCIO_CPU0
  AV27  PVCCIO_CPU0    VCCIO<80>  @BASEBOARD_FAB2_LIB.BASEBOARD_FAB2(SCH_1):PVCCIO_CPU0
  AW26  PVCCIO_CPU0    VCCIO<79>  @BASEBOARD_FAB2_LIB.BASEBOARD_FAB2(SCH_1):PVCCIO_CPU0
  AY27  PVCCIO_CPU0    VCCIO<78>  @BASEBOARD_FAB2_LIB.BASEBOARD_FAB2(SCH_1):PVCCIO_CPU0
  BA26  PVCCIO_CPU0    VCCIO<77>  @BASEBOARD_FAB2_LIB.BASEBOARD_FAB2(SCH_1):PVCCIO_CPU0
  BB27  PVCCIO_CPU0    VCCIO<76>  @BASEBOARD_FAB2_LIB.BASEBOARD_FAB2(SCH_1):PVCCIO_CPU0
  BC26  PVCCIO_CPU0    VCCIO<75>  @BASEBOARD_FAB2_LIB.BASEBOARD_FAB2(SCH_1):PVCCIO_CPU0
  W10  PVCCIO_CPU0    VCCIO<74>  @BASEBOARD_FAB2_LIB.BASEBOARD_FAB2(SCH_1):PVCCIO_CPU0
  N18  PVCCIO_CPU0    VCCIO<73>  @BASEBOARD_FAB2_LIB.BASEBOARD_FAB2(SCH_1):PVCCIO_CPU0
   M9  PVCCIO_CPU0    VCCIO<72>  @BASEBOARD_FAB2_LIB.BASEBOARD_FAB2(SCH_1):PVCCIO_CPU0
   M7  PVCCIO_CPU0    VCCIO<71>  @BASEBOARD_FAB2_LIB.BASEBOARD_FAB2(SCH_1):PVCCIO_CPU0
  K15  PVCCIO_CPU0    VCCIO<70>  @BASEBOARD_FAB2_LIB.BASEBOARD_FAB2(SCH_1):PVCCIO_CPU0
   J2  PVCCIO_CPU0    VCCIO<69>  @BASEBOARD_FAB2_LIB.BASEBOARD_FAB2(SCH_1):PVCCIO_CPU0
  EB15  PVCCIO_CPU0    VCCIO<68>  @BASEBOARD_FAB2_LIB.BASEBOARD_FAB2(SCH_1):PVCCIO_CPU0
  EA12  PVCCIO_CPU0    VCCIO<67>  @BASEBOARD_FAB2_LIB.BASEBOARD_FAB2(SCH_1):PVCCIO_CPU0
  DU20  PVCCIO_CPU0    VCCIO<66>  @BASEBOARD_FAB2_LIB.BASEBOARD_FAB2(SCH_1):PVCCIO_CPU0
  DR2  PVCCIO_CPU0    VCCIO<65>  @BASEBOARD_FAB2_LIB.BASEBOARD_FAB2(SCH_1):PVCCIO_CPU0
  DR10  PVCCIO_CPU0    VCCIO<64>  @BASEBOARD_FAB2_LIB.BASEBOARD_FAB2(SCH_1):PVCCIO_CPU0
  DP19  PVCCIO_CPU0    VCCIO<63>  @BASEBOARD_FAB2_LIB.BASEBOARD_FAB2(SCH_1):PVCCIO_CPU0
  DN8  PVCCIO_CPU0    VCCIO<62>  @BASEBOARD_FAB2_LIB.BASEBOARD_FAB2(SCH_1):PVCCIO_CPU0
  DM17  PVCCIO_CPU0    VCCIO<61>  @BASEBOARD_FAB2_LIB.BASEBOARD_FAB2(SCH_1):PVCCIO_CPU0
  DJ16  PVCCIO_CPU0    VCCIO<60>  @BASEBOARD_FAB2_LIB.BASEBOARD_FAB2(SCH_1):PVCCIO_CPU0
  H13  PVCCIO_CPU0    VCCIO<59>  @BASEBOARD_FAB2_LIB.BASEBOARD_FAB2(SCH_1):PVCCIO_CPU0
  J10  PVCCIO_CPU0    VCCIO<58>  @BASEBOARD_FAB2_LIB.BASEBOARD_FAB2(SCH_1):PVCCIO_CPU0
  L14  PVCCIO_CPU0    VCCIO<57>  @BASEBOARD_FAB2_LIB.BASEBOARD_FAB2(SCH_1):PVCCIO_CPU0
  L16  PVCCIO_CPU0    VCCIO<56>  @BASEBOARD_FAB2_LIB.BASEBOARD_FAB2(SCH_1):PVCCIO_CPU0
  DH7  PVCCIO_CPU0    VCCIO<55>  @BASEBOARD_FAB2_LIB.BASEBOARD_FAB2(SCH_1):PVCCIO_CPU0
  DG8  PVCCIO_CPU0    VCCIO<54>  @BASEBOARD_FAB2_LIB.BASEBOARD_FAB2(SCH_1):PVCCIO_CPU0
  M11  PVCCIO_CPU0    VCCIO<53>  @BASEBOARD_FAB2_LIB.BASEBOARD_FAB2(SCH_1):PVCCIO_CPU0
  M21  PVCCIO_CPU0    VCCIO<52>  @BASEBOARD_FAB2_LIB.BASEBOARD_FAB2(SCH_1):PVCCIO_CPU0
   P5  PVCCIO_CPU0    VCCIO<51>  @BASEBOARD_FAB2_LIB.BASEBOARD_FAB2(SCH_1):PVCCIO_CPU0
   T3  PVCCIO_CPU0    VCCIO<50>  @BASEBOARD_FAB2_LIB.BASEBOARD_FAB2(SCH_1):PVCCIO_CPU0
  U14  PVCCIO_CPU0    VCCIO<49>  @BASEBOARD_FAB2_LIB.BASEBOARD_FAB2(SCH_1):PVCCIO_CPU0
  DF21  PVCCIO_CPU0    VCCIO<48>  @BASEBOARD_FAB2_LIB.BASEBOARD_FAB2(SCH_1):PVCCIO_CPU0
   W4  PVCCIO_CPU0    VCCIO<47>  @BASEBOARD_FAB2_LIB.BASEBOARD_FAB2(SCH_1):PVCCIO_CPU0
   W6  PVCCIO_CPU0    VCCIO<46>  @BASEBOARD_FAB2_LIB.BASEBOARD_FAB2(SCH_1):PVCCIO_CPU0
  AA10  PVCCIO_CPU0    VCCIO<45>  @BASEBOARD_FAB2_LIB.BASEBOARD_FAB2(SCH_1):PVCCIO_CPU0
  AC20  PVCCIO_CPU0    VCCIO<44>  @BASEBOARD_FAB2_LIB.BASEBOARD_FAB2(SCH_1):PVCCIO_CPU0
  AC4  PVCCIO_CPU0    VCCIO<43>  @BASEBOARD_FAB2_LIB.BASEBOARD_FAB2(SCH_1):PVCCIO_CPU0
  AH9  PVCCIO_CPU0    VCCIO<42>  @BASEBOARD_FAB2_LIB.BASEBOARD_FAB2(SCH_1):PVCCIO_CPU0
  DF13  PVCCIO_CPU0    VCCIO<41>  @BASEBOARD_FAB2_LIB.BASEBOARD_FAB2(SCH_1):PVCCIO_CPU0
  AN10  PVCCIO_CPU0    VCCIO<40>  @BASEBOARD_FAB2_LIB.BASEBOARD_FAB2(SCH_1):PVCCIO_CPU0
  DD7  PVCCIO_CPU0    VCCIO<39>  @BASEBOARD_FAB2_LIB.BASEBOARD_FAB2(SCH_1):PVCCIO_CPU0
  AT11  PVCCIO_CPU0    VCCIO<38>  @BASEBOARD_FAB2_LIB.BASEBOARD_FAB2(SCH_1):PVCCIO_CPU0
  AW6  PVCCIO_CPU0    VCCIO<37>  @BASEBOARD_FAB2_LIB.BASEBOARD_FAB2(SCH_1):PVCCIO_CPU0
  AY11  PVCCIO_CPU0    VCCIO<36>  @BASEBOARD_FAB2_LIB.BASEBOARD_FAB2(SCH_1):PVCCIO_CPU0
  BA24  PVCCIO_CPU0    VCCIO<35>  @BASEBOARD_FAB2_LIB.BASEBOARD_FAB2(SCH_1):PVCCIO_CPU0
  BB5  PVCCIO_CPU0    VCCIO<34>  @BASEBOARD_FAB2_LIB.BASEBOARD_FAB2(SCH_1):PVCCIO_CPU0
  DA14  PVCCIO_CPU0    VCCIO<33>  @BASEBOARD_FAB2_LIB.BASEBOARD_FAB2(SCH_1):PVCCIO_CPU0
  BF23  PVCCIO_CPU0    VCCIO<32>  @BASEBOARD_FAB2_LIB.BASEBOARD_FAB2(SCH_1):PVCCIO_CPU0
  BJ24  PVCCIO_CPU0    VCCIO<31>  @BASEBOARD_FAB2_LIB.BASEBOARD_FAB2(SCH_1):PVCCIO_CPU0
  BP25  PVCCIO_CPU0    VCCIO<30>  @BASEBOARD_FAB2_LIB.BASEBOARD_FAB2(SCH_1):PVCCIO_CPU0
  CB13  PVCCIO_CPU0    VCCIO<29>  @BASEBOARD_FAB2_LIB.BASEBOARD_FAB2(SCH_1):PVCCIO_CPU0
  CB17  PVCCIO_CPU0    VCCIO<28>  @BASEBOARD_FAB2_LIB.BASEBOARD_FAB2(SCH_1):PVCCIO_CPU0
  CD9  PVCCIO_CPU0    VCCIO<27>  @BASEBOARD_FAB2_LIB.BASEBOARD_FAB2(SCH_1):PVCCIO_CPU0
  CE18  PVCCIO_CPU0    VCCIO<26>  @BASEBOARD_FAB2_LIB.BASEBOARD_FAB2(SCH_1):PVCCIO_CPU0
   D7  PVCCIO_CPU0    VCCIO<25>  @BASEBOARD_FAB2_LIB.BASEBOARD_FAB2(SCH_1):PVCCIO_CPU0
  CH9  PVCCIO_CPU0    VCCIO<24>  @BASEBOARD_FAB2_LIB.BASEBOARD_FAB2(SCH_1):PVCCIO_CPU0
  CV7  PVCCIO_CPU0    VCCIO<23>  @BASEBOARD_FAB2_LIB.BASEBOARD_FAB2(SCH_1):PVCCIO_CPU0
  CK5  PVCCIO_CPU0    VCCIO<22>  @BASEBOARD_FAB2_LIB.BASEBOARD_FAB2(SCH_1):PVCCIO_CPU0
  CL12  PVCCIO_CPU0    VCCIO<21>  @BASEBOARD_FAB2_LIB.BASEBOARD_FAB2(SCH_1):PVCCIO_CPU0
  CM15  PVCCIO_CPU0    VCCIO<20>  @BASEBOARD_FAB2_LIB.BASEBOARD_FAB2(SCH_1):PVCCIO_CPU0
  BM11  PVCCIOMCP_CPU0  CD_VCCP<15>  @BASEBOARD_FAB2_LIB.BASEBOARD_FAB2(SCH_1):PVCCIOMCP_CPU0
  BN12  PVCCIOMCP_CPU0  CD_VCCP<14>  @BASEBOARD_FAB2_LIB.BASEBOARD_FAB2(SCH_1):PVCCIOMCP_CPU0
  BN14  PVCCIOMCP_CPU0  CD_VCCP<13>  @BASEBOARD_FAB2_LIB.BASEBOARD_FAB2(SCH_1):PVCCIOMCP_CPU0
  BP11  PVCCIOMCP_CPU0  CD_VCCP<12>  @BASEBOARD_FAB2_LIB.BASEBOARD_FAB2(SCH_1):PVCCIOMCP_CPU0
  BP13  PVCCIOMCP_CPU0  CD_VCCP<11>  @BASEBOARD_FAB2_LIB.BASEBOARD_FAB2(SCH_1):PVCCIOMCP_CPU0
  BP15  PVCCIOMCP_CPU0  CD_VCCP<10>  @BASEBOARD_FAB2_LIB.BASEBOARD_FAB2(SCH_1):PVCCIOMCP_CPU0
  BR12  PVCCIOMCP_CPU0  CD_VCCP<9>  @BASEBOARD_FAB2_LIB.BASEBOARD_FAB2(SCH_1):PVCCIOMCP_CPU0
  BR14  PVCCIOMCP_CPU0  CD_VCCP<8>  @BASEBOARD_FAB2_LIB.BASEBOARD_FAB2(SCH_1):PVCCIOMCP_CPU0
  BT11  PVCCIOMCP_CPU0  CD_VCCP<7>  @BASEBOARD_FAB2_LIB.BASEBOARD_FAB2(SCH_1):PVCCIOMCP_CPU0
  BT13  PVCCIOMCP_CPU0  CD_VCCP<6>  @BASEBOARD_FAB2_LIB.BASEBOARD_FAB2(SCH_1):PVCCIOMCP_CPU0
  BT15  PVCCIOMCP_CPU0  CD_VCCP<5>  @BASEBOARD_FAB2_LIB.BASEBOARD_FAB2(SCH_1):PVCCIOMCP_CPU0
  BU12  PVCCIOMCP_CPU0  CD_VCCP<4>  @BASEBOARD_FAB2_LIB.BASEBOARD_FAB2(SCH_1):PVCCIOMCP_CPU0
  BU14  PVCCIOMCP_CPU0  CD_VCCP<3>  @BASEBOARD_FAB2_LIB.BASEBOARD_FAB2(SCH_1):PVCCIOMCP_CPU0
  BV11  PVCCIOMCP_CPU0  CD_VCCP<2>  @BASEBOARD_FAB2_LIB.BASEBOARD_FAB2(SCH_1):PVCCIOMCP_CPU0
  BV13  PVCCIOMCP_CPU0  CD_VCCP<1>  @BASEBOARD_FAB2_LIB.BASEBOARD_FAB2(SCH_1):PVCCIOMCP_CPU0
  BV15  PVCCIOMCP_CPU0  CD_VCCP<0>  @BASEBOARD_FAB2_LIB.BASEBOARD_FAB2(SCH_1):PVCCIOMCP_CPU0
  CY55  P3V3_STBY      VCC33  @BASEBOARD_FAB2_LIB.BASEBOARD_FAB2(SCH_1):P3V3_STBY
  BY27  P1V8_MCP_CPU0  CD_VCCIN<3>  @BASEBOARD_FAB2_LIB.BASEBOARD_FAB2(SCH_1):P1V8_MCP_CPU0
  BV27  P1V8_MCP_CPU0  CD_VCCIN<2>  @BASEBOARD_FAB2_LIB.BASEBOARD_FAB2(SCH_1):P1V8_MCP_CPU0
  BU26  P1V8_MCP_CPU0  CD_VCCIN<1>  @BASEBOARD_FAB2_LIB.BASEBOARD_FAB2(SCH_1):P1V8_MCP_CPU0
  BT27  P1V8_MCP_CPU0  CD_VCCIN<0>  @BASEBOARD_FAB2_LIB.BASEBOARD_FAB2(SCH_1):P1V8_MCP_CPU0

SKX_EXT_B_BGA1  I33  U5D1   [SKX_EXT_B_BGA1-IC,TBD]
  EE44  PVDDQ_DEF      VCCD345<50>  @BASEBOARD_FAB2_LIB.BASEBOARD_FAB2(SCH_1):PVDDQ_DEF
  EF45  PVDDQ_DEF      VCCD345<49>  @BASEBOARD_FAB2_LIB.BASEBOARD_FAB2(SCH_1):PVDDQ_DEF
  DB53  PVDDQ_DEF      VCCD345<48>  @BASEBOARD_FAB2_LIB.BASEBOARD_FAB2(SCH_1):PVDDQ_DEF
  DB55  PVDDQ_DEF      VCCD345<47>  @BASEBOARD_FAB2_LIB.BASEBOARD_FAB2(SCH_1):PVDDQ_DEF
  DB57  PVDDQ_DEF      VCCD345<46>  @BASEBOARD_FAB2_LIB.BASEBOARD_FAB2(SCH_1):PVDDQ_DEF
  DB59  PVDDQ_DEF      VCCD345<45>  @BASEBOARD_FAB2_LIB.BASEBOARD_FAB2(SCH_1):PVDDQ_DEF
  DB61  PVDDQ_DEF      VCCD345<44>  @BASEBOARD_FAB2_LIB.BASEBOARD_FAB2(SCH_1):PVDDQ_DEF
  DB63  PVDDQ_DEF      VCCD345<43>  @BASEBOARD_FAB2_LIB.BASEBOARD_FAB2(SCH_1):PVDDQ_DEF
  DD45  PVDDQ_DEF      VCCD345<42>  @BASEBOARD_FAB2_LIB.BASEBOARD_FAB2(SCH_1):PVDDQ_DEF
  DH45  PVDDQ_DEF      VCCD345<41>  @BASEBOARD_FAB2_LIB.BASEBOARD_FAB2(SCH_1):PVDDQ_DEF
  DH47  PVDDQ_DEF      VCCD345<40>  @BASEBOARD_FAB2_LIB.BASEBOARD_FAB2(SCH_1):PVDDQ_DEF
  DH49  PVDDQ_DEF      VCCD345<39>  @BASEBOARD_FAB2_LIB.BASEBOARD_FAB2(SCH_1):PVDDQ_DEF
  DH51  PVDDQ_DEF      VCCD345<38>  @BASEBOARD_FAB2_LIB.BASEBOARD_FAB2(SCH_1):PVDDQ_DEF
  DH53  PVDDQ_DEF      VCCD345<37>  @BASEBOARD_FAB2_LIB.BASEBOARD_FAB2(SCH_1):PVDDQ_DEF
  DH55  PVDDQ_DEF      VCCD345<36>  @BASEBOARD_FAB2_LIB.BASEBOARD_FAB2(SCH_1):PVDDQ_DEF
  DH57  PVDDQ_DEF      VCCD345<35>  @BASEBOARD_FAB2_LIB.BASEBOARD_FAB2(SCH_1):PVDDQ_DEF
  DH59  PVDDQ_DEF      VCCD345<34>  @BASEBOARD_FAB2_LIB.BASEBOARD_FAB2(SCH_1):PVDDQ_DEF
  DH61  PVDDQ_DEF      VCCD345<33>  @BASEBOARD_FAB2_LIB.BASEBOARD_FAB2(SCH_1):PVDDQ_DEF
  DH63  PVDDQ_DEF      VCCD345<32>  @BASEBOARD_FAB2_LIB.BASEBOARD_FAB2(SCH_1):PVDDQ_DEF
  DJ64  PVDDQ_DEF      VCCD345<31>  @BASEBOARD_FAB2_LIB.BASEBOARD_FAB2(SCH_1):PVDDQ_DEF
  DL46  PVDDQ_DEF      VCCD345<30>  @BASEBOARD_FAB2_LIB.BASEBOARD_FAB2(SCH_1):PVDDQ_DEF
  DL48  PVDDQ_DEF      VCCD345<29>  @BASEBOARD_FAB2_LIB.BASEBOARD_FAB2(SCH_1):PVDDQ_DEF
  DL50  PVDDQ_DEF      VCCD345<28>  @BASEBOARD_FAB2_LIB.BASEBOARD_FAB2(SCH_1):PVDDQ_DEF
  DL52  PVDDQ_DEF      VCCD345<27>  @BASEBOARD_FAB2_LIB.BASEBOARD_FAB2(SCH_1):PVDDQ_DEF
  DL54  PVDDQ_DEF      VCCD345<26>  @BASEBOARD_FAB2_LIB.BASEBOARD_FAB2(SCH_1):PVDDQ_DEF
  DL56  PVDDQ_DEF      VCCD345<25>  @BASEBOARD_FAB2_LIB.BASEBOARD_FAB2(SCH_1):PVDDQ_DEF
  DL58  PVDDQ_DEF      VCCD345<24>  @BASEBOARD_FAB2_LIB.BASEBOARD_FAB2(SCH_1):PVDDQ_DEF
  DL60  PVDDQ_DEF      VCCD345<23>  @BASEBOARD_FAB2_LIB.BASEBOARD_FAB2(SCH_1):PVDDQ_DEF
  DL62  PVDDQ_DEF      VCCD345<22>  @BASEBOARD_FAB2_LIB.BASEBOARD_FAB2(SCH_1):PVDDQ_DEF
  DU46  PVDDQ_DEF      VCCD345<21>  @BASEBOARD_FAB2_LIB.BASEBOARD_FAB2(SCH_1):PVDDQ_DEF
  DU48  PVDDQ_DEF      VCCD345<20>  @BASEBOARD_FAB2_LIB.BASEBOARD_FAB2(SCH_1):PVDDQ_DEF
  DU50  PVDDQ_DEF      VCCD345<19>  @BASEBOARD_FAB2_LIB.BASEBOARD_FAB2(SCH_1):PVDDQ_DEF
  DU52  PVDDQ_DEF      VCCD345<18>  @BASEBOARD_FAB2_LIB.BASEBOARD_FAB2(SCH_1):PVDDQ_DEF
  DU54  PVDDQ_DEF      VCCD345<17>  @BASEBOARD_FAB2_LIB.BASEBOARD_FAB2(SCH_1):PVDDQ_DEF
  DU56  PVDDQ_DEF      VCCD345<16>  @BASEBOARD_FAB2_LIB.BASEBOARD_FAB2(SCH_1):PVDDQ_DEF
  DU58  PVDDQ_DEF      VCCD345<15>  @BASEBOARD_FAB2_LIB.BASEBOARD_FAB2(SCH_1):PVDDQ_DEF
  DU60  PVDDQ_DEF      VCCD345<14>  @BASEBOARD_FAB2_LIB.BASEBOARD_FAB2(SCH_1):PVDDQ_DEF
  DU62  PVDDQ_DEF      VCCD345<13>  @BASEBOARD_FAB2_LIB.BASEBOARD_FAB2(SCH_1):PVDDQ_DEF
  DU64  PVDDQ_DEF      VCCD345<12>  @BASEBOARD_FAB2_LIB.BASEBOARD_FAB2(SCH_1):PVDDQ_DEF
  EC46  PVDDQ_DEF      VCCD345<11>  @BASEBOARD_FAB2_LIB.BASEBOARD_FAB2(SCH_1):PVDDQ_DEF
  EC48  PVDDQ_DEF      VCCD345<10>  @BASEBOARD_FAB2_LIB.BASEBOARD_FAB2(SCH_1):PVDDQ_DEF
  EC50  PVDDQ_DEF      VCCD345<9>  @BASEBOARD_FAB2_LIB.BASEBOARD_FAB2(SCH_1):PVDDQ_DEF
  EC52  PVDDQ_DEF      VCCD345<8>  @BASEBOARD_FAB2_LIB.BASEBOARD_FAB2(SCH_1):PVDDQ_DEF
  EC54  PVDDQ_DEF      VCCD345<7>  @BASEBOARD_FAB2_LIB.BASEBOARD_FAB2(SCH_1):PVDDQ_DEF
  EC56  PVDDQ_DEF      VCCD345<6>  @BASEBOARD_FAB2_LIB.BASEBOARD_FAB2(SCH_1):PVDDQ_DEF
  EC58  PVDDQ_DEF      VCCD345<5>  @BASEBOARD_FAB2_LIB.BASEBOARD_FAB2(SCH_1):PVDDQ_DEF
  EC60  PVDDQ_DEF      VCCD345<4>  @BASEBOARD_FAB2_LIB.BASEBOARD_FAB2(SCH_1):PVDDQ_DEF
  EC62  PVDDQ_DEF      VCCD345<3>  @BASEBOARD_FAB2_LIB.BASEBOARD_FAB2(SCH_1):PVDDQ_DEF
  EF49  PVDDQ_DEF      VCCD345<2>  @BASEBOARD_FAB2_LIB.BASEBOARD_FAB2(SCH_1):PVDDQ_DEF
  EF53  PVDDQ_DEF      VCCD345<1>  @BASEBOARD_FAB2_LIB.BASEBOARD_FAB2(SCH_1):PVDDQ_DEF
  EF59  PVDDQ_DEF      VCCD345<0>  @BASEBOARD_FAB2_LIB.BASEBOARD_FAB2(SCH_1):PVDDQ_DEF
  B47  PVDDQ_ABC      VCCD012<51>  @BASEBOARD_FAB2_LIB.BASEBOARD_FAB2(SCH_1):PVDDQ_ABC
  C46  PVDDQ_ABC      VCCD012<50>  @BASEBOARD_FAB2_LIB.BASEBOARD_FAB2(SCH_1):PVDDQ_ABC
  D45  PVDDQ_ABC      VCCD012<49>  @BASEBOARD_FAB2_LIB.BASEBOARD_FAB2(SCH_1):PVDDQ_ABC
  AF63  PVDDQ_ABC      VCCD012<48>  @BASEBOARD_FAB2_LIB.BASEBOARD_FAB2(SCH_1):PVDDQ_ABC
  AF61  PVDDQ_ABC      VCCD012<47>  @BASEBOARD_FAB2_LIB.BASEBOARD_FAB2(SCH_1):PVDDQ_ABC
  AF59  PVDDQ_ABC      VCCD012<46>  @BASEBOARD_FAB2_LIB.BASEBOARD_FAB2(SCH_1):PVDDQ_ABC
  AF57  PVDDQ_ABC      VCCD012<45>  @BASEBOARD_FAB2_LIB.BASEBOARD_FAB2(SCH_1):PVDDQ_ABC
  AF55  PVDDQ_ABC      VCCD012<44>  @BASEBOARD_FAB2_LIB.BASEBOARD_FAB2(SCH_1):PVDDQ_ABC
  AD45  PVDDQ_ABC      VCCD012<43>  @BASEBOARD_FAB2_LIB.BASEBOARD_FAB2(SCH_1):PVDDQ_ABC
  Y63  PVDDQ_ABC      VCCD012<42>  @BASEBOARD_FAB2_LIB.BASEBOARD_FAB2(SCH_1):PVDDQ_ABC
  Y61  PVDDQ_ABC      VCCD012<41>  @BASEBOARD_FAB2_LIB.BASEBOARD_FAB2(SCH_1):PVDDQ_ABC
  Y59  PVDDQ_ABC      VCCD012<40>  @BASEBOARD_FAB2_LIB.BASEBOARD_FAB2(SCH_1):PVDDQ_ABC
  Y57  PVDDQ_ABC      VCCD012<39>  @BASEBOARD_FAB2_LIB.BASEBOARD_FAB2(SCH_1):PVDDQ_ABC
  Y55  PVDDQ_ABC      VCCD012<38>  @BASEBOARD_FAB2_LIB.BASEBOARD_FAB2(SCH_1):PVDDQ_ABC
  Y53  PVDDQ_ABC      VCCD012<37>  @BASEBOARD_FAB2_LIB.BASEBOARD_FAB2(SCH_1):PVDDQ_ABC
  Y51  PVDDQ_ABC      VCCD012<36>  @BASEBOARD_FAB2_LIB.BASEBOARD_FAB2(SCH_1):PVDDQ_ABC
  Y49  PVDDQ_ABC      VCCD012<35>  @BASEBOARD_FAB2_LIB.BASEBOARD_FAB2(SCH_1):PVDDQ_ABC
  Y47  PVDDQ_ABC      VCCD012<34>  @BASEBOARD_FAB2_LIB.BASEBOARD_FAB2(SCH_1):PVDDQ_ABC
  Y45  PVDDQ_ABC      VCCD012<33>  @BASEBOARD_FAB2_LIB.BASEBOARD_FAB2(SCH_1):PVDDQ_ABC
  W64  PVDDQ_ABC      VCCD012<32>  @BASEBOARD_FAB2_LIB.BASEBOARD_FAB2(SCH_1):PVDDQ_ABC
  U62  PVDDQ_ABC      VCCD012<31>  @BASEBOARD_FAB2_LIB.BASEBOARD_FAB2(SCH_1):PVDDQ_ABC
  U60  PVDDQ_ABC      VCCD012<30>  @BASEBOARD_FAB2_LIB.BASEBOARD_FAB2(SCH_1):PVDDQ_ABC
  U58  PVDDQ_ABC      VCCD012<29>  @BASEBOARD_FAB2_LIB.BASEBOARD_FAB2(SCH_1):PVDDQ_ABC
  U56  PVDDQ_ABC      VCCD012<28>  @BASEBOARD_FAB2_LIB.BASEBOARD_FAB2(SCH_1):PVDDQ_ABC
  U54  PVDDQ_ABC      VCCD012<27>  @BASEBOARD_FAB2_LIB.BASEBOARD_FAB2(SCH_1):PVDDQ_ABC
  U52  PVDDQ_ABC      VCCD012<26>  @BASEBOARD_FAB2_LIB.BASEBOARD_FAB2(SCH_1):PVDDQ_ABC
  U50  PVDDQ_ABC      VCCD012<25>  @BASEBOARD_FAB2_LIB.BASEBOARD_FAB2(SCH_1):PVDDQ_ABC
  U48  PVDDQ_ABC      VCCD012<24>  @BASEBOARD_FAB2_LIB.BASEBOARD_FAB2(SCH_1):PVDDQ_ABC
  U46  PVDDQ_ABC      VCCD012<23>  @BASEBOARD_FAB2_LIB.BASEBOARD_FAB2(SCH_1):PVDDQ_ABC
  N64  PVDDQ_ABC      VCCD012<22>  @BASEBOARD_FAB2_LIB.BASEBOARD_FAB2(SCH_1):PVDDQ_ABC
  L62  PVDDQ_ABC      VCCD012<21>  @BASEBOARD_FAB2_LIB.BASEBOARD_FAB2(SCH_1):PVDDQ_ABC
  L60  PVDDQ_ABC      VCCD012<20>  @BASEBOARD_FAB2_LIB.BASEBOARD_FAB2(SCH_1):PVDDQ_ABC
  L58  PVDDQ_ABC      VCCD012<19>  @BASEBOARD_FAB2_LIB.BASEBOARD_FAB2(SCH_1):PVDDQ_ABC
  L56  PVDDQ_ABC      VCCD012<18>  @BASEBOARD_FAB2_LIB.BASEBOARD_FAB2(SCH_1):PVDDQ_ABC
  L54  PVDDQ_ABC      VCCD012<17>  @BASEBOARD_FAB2_LIB.BASEBOARD_FAB2(SCH_1):PVDDQ_ABC
  L52  PVDDQ_ABC      VCCD012<16>  @BASEBOARD_FAB2_LIB.BASEBOARD_FAB2(SCH_1):PVDDQ_ABC
  L50  PVDDQ_ABC      VCCD012<15>  @BASEBOARD_FAB2_LIB.BASEBOARD_FAB2(SCH_1):PVDDQ_ABC
  L48  PVDDQ_ABC      VCCD012<14>  @BASEBOARD_FAB2_LIB.BASEBOARD_FAB2(SCH_1):PVDDQ_ABC
  L46  PVDDQ_ABC      VCCD012<13>  @BASEBOARD_FAB2_LIB.BASEBOARD_FAB2(SCH_1):PVDDQ_ABC
  E64  PVDDQ_ABC      VCCD012<12>  @BASEBOARD_FAB2_LIB.BASEBOARD_FAB2(SCH_1):PVDDQ_ABC
  E62  PVDDQ_ABC      VCCD012<11>  @BASEBOARD_FAB2_LIB.BASEBOARD_FAB2(SCH_1):PVDDQ_ABC
  E60  PVDDQ_ABC      VCCD012<10>  @BASEBOARD_FAB2_LIB.BASEBOARD_FAB2(SCH_1):PVDDQ_ABC
  E58  PVDDQ_ABC      VCCD012<9>  @BASEBOARD_FAB2_LIB.BASEBOARD_FAB2(SCH_1):PVDDQ_ABC
  E56  PVDDQ_ABC      VCCD012<8>  @BASEBOARD_FAB2_LIB.BASEBOARD_FAB2(SCH_1):PVDDQ_ABC
  E54  PVDDQ_ABC      VCCD012<7>  @BASEBOARD_FAB2_LIB.BASEBOARD_FAB2(SCH_1):PVDDQ_ABC
  E52  PVDDQ_ABC      VCCD012<6>  @BASEBOARD_FAB2_LIB.BASEBOARD_FAB2(SCH_1):PVDDQ_ABC
  E50  PVDDQ_ABC      VCCD012<5>  @BASEBOARD_FAB2_LIB.BASEBOARD_FAB2(SCH_1):PVDDQ_ABC
  E48  PVDDQ_ABC      VCCD012<4>  @BASEBOARD_FAB2_LIB.BASEBOARD_FAB2(SCH_1):PVDDQ_ABC
  E46  PVDDQ_ABC      VCCD012<3>  @BASEBOARD_FAB2_LIB.BASEBOARD_FAB2(SCH_1):PVDDQ_ABC
  B59  PVDDQ_ABC      VCCD012<2>  @BASEBOARD_FAB2_LIB.BASEBOARD_FAB2(SCH_1):PVDDQ_ABC
  B53  PVDDQ_ABC      VCCD012<1>  @BASEBOARD_FAB2_LIB.BASEBOARD_FAB2(SCH_1):PVDDQ_ABC
  B49  PVDDQ_ABC      VCCD012<0>  @BASEBOARD_FAB2_LIB.BASEBOARD_FAB2(SCH_1):PVDDQ_ABC

SKX_EXT_B_BGA1  I311  U5D1   [SKX_EXT_B_BGA1-IC,TBD]
  AV85  VSENSE_VCCINR2PMAX_CPU0  VCCINPMAX<1>  @BASEBOARD_FAB2_LIB.BASEBOARD_FAB2(SCH_1):VSENSE_VCCINR2PMAX_CPU0
  AW86  VSENSE_VCCINR2PMAX_CPU0  VCCINPMAX<0>  @BASEBOARD_FAB2_LIB.BASEBOARD_FAB2(SCH_1):VSENSE_VCCINR2PMAX_CPU0
  BA86  VSENSE_PVCCIN_CPU0_SKT_VSEN  VCCIN_SENSE  @BASEBOARD_FAB2_LIB.BASEBOARD_FAB2(SCH_1):VSENSE_PVCCIN_CPU0_SKT_VSEN
  AY85  VSENSE_PVCCIN_CPU0_SKT_VRTN  VSS_VCCIN_SENSE  @BASEBOARD_FAB2_LIB.BASEBOARD_FAB2(SCH_1):VSENSE_PVCCIN_CPU0_SKT_VRTN
  AD41  VSENSE_PMAX_CPU0  VSENSEPMAX  @BASEBOARD_FAB2_LIB.BASEBOARD_FAB2(SCH_1):VSENSE_PMAX_CPU0
  BN80  PVCCIN_CPU0    VCCIN<129>  @BASEBOARD_FAB2_LIB.BASEBOARD_FAB2(SCH_1):PVCCIN_CPU0
  BN82  PVCCIN_CPU0    VCCIN<128>  @BASEBOARD_FAB2_LIB.BASEBOARD_FAB2(SCH_1):PVCCIN_CPU0
  BN84  PVCCIN_CPU0    VCCIN<127>  @BASEBOARD_FAB2_LIB.BASEBOARD_FAB2(SCH_1):PVCCIN_CPU0
  BP61  PVCCIN_CPU0    VCCIN<126>  @BASEBOARD_FAB2_LIB.BASEBOARD_FAB2(SCH_1):PVCCIN_CPU0
  BP63  PVCCIN_CPU0    VCCIN<125>  @BASEBOARD_FAB2_LIB.BASEBOARD_FAB2(SCH_1):PVCCIN_CPU0
  BP65  PVCCIN_CPU0    VCCIN<124>  @BASEBOARD_FAB2_LIB.BASEBOARD_FAB2(SCH_1):PVCCIN_CPU0
  BP67  PVCCIN_CPU0    VCCIN<123>  @BASEBOARD_FAB2_LIB.BASEBOARD_FAB2(SCH_1):PVCCIN_CPU0
  BP69  PVCCIN_CPU0    VCCIN<122>  @BASEBOARD_FAB2_LIB.BASEBOARD_FAB2(SCH_1):PVCCIN_CPU0
  BP71  PVCCIN_CPU0    VCCIN<121>  @BASEBOARD_FAB2_LIB.BASEBOARD_FAB2(SCH_1):PVCCIN_CPU0
  BP73  PVCCIN_CPU0    VCCIN<120>  @BASEBOARD_FAB2_LIB.BASEBOARD_FAB2(SCH_1):PVCCIN_CPU0
  BP75  PVCCIN_CPU0    VCCIN<119>  @BASEBOARD_FAB2_LIB.BASEBOARD_FAB2(SCH_1):PVCCIN_CPU0
  BP77  PVCCIN_CPU0    VCCIN<118>  @BASEBOARD_FAB2_LIB.BASEBOARD_FAB2(SCH_1):PVCCIN_CPU0
  BP79  PVCCIN_CPU0    VCCIN<117>  @BASEBOARD_FAB2_LIB.BASEBOARD_FAB2(SCH_1):PVCCIN_CPU0
  BP81  PVCCIN_CPU0    VCCIN<116>  @BASEBOARD_FAB2_LIB.BASEBOARD_FAB2(SCH_1):PVCCIN_CPU0
  BP83  PVCCIN_CPU0    VCCIN<115>  @BASEBOARD_FAB2_LIB.BASEBOARD_FAB2(SCH_1):PVCCIN_CPU0
  BR60  PVCCIN_CPU0    VCCIN<114>  @BASEBOARD_FAB2_LIB.BASEBOARD_FAB2(SCH_1):PVCCIN_CPU0
  BR62  PVCCIN_CPU0    VCCIN<113>  @BASEBOARD_FAB2_LIB.BASEBOARD_FAB2(SCH_1):PVCCIN_CPU0
  BR84  PVCCIN_CPU0    VCCIN<112>  @BASEBOARD_FAB2_LIB.BASEBOARD_FAB2(SCH_1):PVCCIN_CPU0
  BT61  PVCCIN_CPU0    VCCIN<111>  @BASEBOARD_FAB2_LIB.BASEBOARD_FAB2(SCH_1):PVCCIN_CPU0
  BT63  PVCCIN_CPU0    VCCIN<110>  @BASEBOARD_FAB2_LIB.BASEBOARD_FAB2(SCH_1):PVCCIN_CPU0
  BT65  PVCCIN_CPU0    VCCIN<109>  @BASEBOARD_FAB2_LIB.BASEBOARD_FAB2(SCH_1):PVCCIN_CPU0
  BT67  PVCCIN_CPU0    VCCIN<108>  @BASEBOARD_FAB2_LIB.BASEBOARD_FAB2(SCH_1):PVCCIN_CPU0
  BT69  PVCCIN_CPU0    VCCIN<107>  @BASEBOARD_FAB2_LIB.BASEBOARD_FAB2(SCH_1):PVCCIN_CPU0
  BT71  PVCCIN_CPU0    VCCIN<106>  @BASEBOARD_FAB2_LIB.BASEBOARD_FAB2(SCH_1):PVCCIN_CPU0
  BT73  PVCCIN_CPU0    VCCIN<105>  @BASEBOARD_FAB2_LIB.BASEBOARD_FAB2(SCH_1):PVCCIN_CPU0
  BT75  PVCCIN_CPU0    VCCIN<104>  @BASEBOARD_FAB2_LIB.BASEBOARD_FAB2(SCH_1):PVCCIN_CPU0
  BT77  PVCCIN_CPU0    VCCIN<103>  @BASEBOARD_FAB2_LIB.BASEBOARD_FAB2(SCH_1):PVCCIN_CPU0
  BT79  PVCCIN_CPU0    VCCIN<102>  @BASEBOARD_FAB2_LIB.BASEBOARD_FAB2(SCH_1):PVCCIN_CPU0
  BT81  PVCCIN_CPU0    VCCIN<101>  @BASEBOARD_FAB2_LIB.BASEBOARD_FAB2(SCH_1):PVCCIN_CPU0
  BT83  PVCCIN_CPU0    VCCIN<100>  @BASEBOARD_FAB2_LIB.BASEBOARD_FAB2(SCH_1):PVCCIN_CPU0
  BU60  PVCCIN_CPU0    VCCIN<99>  @BASEBOARD_FAB2_LIB.BASEBOARD_FAB2(SCH_1):PVCCIN_CPU0
  BU62  PVCCIN_CPU0    VCCIN<98>  @BASEBOARD_FAB2_LIB.BASEBOARD_FAB2(SCH_1):PVCCIN_CPU0
  BU64  PVCCIN_CPU0    VCCIN<97>  @BASEBOARD_FAB2_LIB.BASEBOARD_FAB2(SCH_1):PVCCIN_CPU0
  BU66  PVCCIN_CPU0    VCCIN<96>  @BASEBOARD_FAB2_LIB.BASEBOARD_FAB2(SCH_1):PVCCIN_CPU0
  BU68  PVCCIN_CPU0    VCCIN<95>  @BASEBOARD_FAB2_LIB.BASEBOARD_FAB2(SCH_1):PVCCIN_CPU0
  BU70  PVCCIN_CPU0    VCCIN<94>  @BASEBOARD_FAB2_LIB.BASEBOARD_FAB2(SCH_1):PVCCIN_CPU0
  BU72  PVCCIN_CPU0    VCCIN<93>  @BASEBOARD_FAB2_LIB.BASEBOARD_FAB2(SCH_1):PVCCIN_CPU0
  BU74  PVCCIN_CPU0    VCCIN<92>  @BASEBOARD_FAB2_LIB.BASEBOARD_FAB2(SCH_1):PVCCIN_CPU0
  BU76  PVCCIN_CPU0    VCCIN<91>  @BASEBOARD_FAB2_LIB.BASEBOARD_FAB2(SCH_1):PVCCIN_CPU0
  BU78  PVCCIN_CPU0    VCCIN<90>  @BASEBOARD_FAB2_LIB.BASEBOARD_FAB2(SCH_1):PVCCIN_CPU0
  BU80  PVCCIN_CPU0    VCCIN<89>  @BASEBOARD_FAB2_LIB.BASEBOARD_FAB2(SCH_1):PVCCIN_CPU0
  BU82  PVCCIN_CPU0    VCCIN<88>  @BASEBOARD_FAB2_LIB.BASEBOARD_FAB2(SCH_1):PVCCIN_CPU0
  BU84  PVCCIN_CPU0    VCCIN<87>  @BASEBOARD_FAB2_LIB.BASEBOARD_FAB2(SCH_1):PVCCIN_CPU0
  BV61  PVCCIN_CPU0    VCCIN<86>  @BASEBOARD_FAB2_LIB.BASEBOARD_FAB2(SCH_1):PVCCIN_CPU0
  BV63  PVCCIN_CPU0    VCCIN<85>  @BASEBOARD_FAB2_LIB.BASEBOARD_FAB2(SCH_1):PVCCIN_CPU0
  BV65  PVCCIN_CPU0    VCCIN<84>  @BASEBOARD_FAB2_LIB.BASEBOARD_FAB2(SCH_1):PVCCIN_CPU0
  BV67  PVCCIN_CPU0    VCCIN<83>  @BASEBOARD_FAB2_LIB.BASEBOARD_FAB2(SCH_1):PVCCIN_CPU0
  BV69  PVCCIN_CPU0    VCCIN<82>  @BASEBOARD_FAB2_LIB.BASEBOARD_FAB2(SCH_1):PVCCIN_CPU0
  BV71  PVCCIN_CPU0    VCCIN<81>  @BASEBOARD_FAB2_LIB.BASEBOARD_FAB2(SCH_1):PVCCIN_CPU0
  BV73  PVCCIN_CPU0    VCCIN<80>  @BASEBOARD_FAB2_LIB.BASEBOARD_FAB2(SCH_1):PVCCIN_CPU0
  BV75  PVCCIN_CPU0    VCCIN<79>  @BASEBOARD_FAB2_LIB.BASEBOARD_FAB2(SCH_1):PVCCIN_CPU0
  BV77  PVCCIN_CPU0    VCCIN<78>  @BASEBOARD_FAB2_LIB.BASEBOARD_FAB2(SCH_1):PVCCIN_CPU0
  BV79  PVCCIN_CPU0    VCCIN<77>  @BASEBOARD_FAB2_LIB.BASEBOARD_FAB2(SCH_1):PVCCIN_CPU0
  BV81  PVCCIN_CPU0    VCCIN<76>  @BASEBOARD_FAB2_LIB.BASEBOARD_FAB2(SCH_1):PVCCIN_CPU0
  BV83  PVCCIN_CPU0    VCCIN<75>  @BASEBOARD_FAB2_LIB.BASEBOARD_FAB2(SCH_1):PVCCIN_CPU0
  BW60  PVCCIN_CPU0    VCCIN<74>  @BASEBOARD_FAB2_LIB.BASEBOARD_FAB2(SCH_1):PVCCIN_CPU0
  BW62  PVCCIN_CPU0    VCCIN<73>  @BASEBOARD_FAB2_LIB.BASEBOARD_FAB2(SCH_1):PVCCIN_CPU0
  BW64  PVCCIN_CPU0    VCCIN<72>  @BASEBOARD_FAB2_LIB.BASEBOARD_FAB2(SCH_1):PVCCIN_CPU0
  BW66  PVCCIN_CPU0    VCCIN<71>  @BASEBOARD_FAB2_LIB.BASEBOARD_FAB2(SCH_1):PVCCIN_CPU0
  BW68  PVCCIN_CPU0    VCCIN<70>  @BASEBOARD_FAB2_LIB.BASEBOARD_FAB2(SCH_1):PVCCIN_CPU0
  BW70  PVCCIN_CPU0    VCCIN<69>  @BASEBOARD_FAB2_LIB.BASEBOARD_FAB2(SCH_1):PVCCIN_CPU0
  BW84  PVCCIN_CPU0    VCCIN<68>  @BASEBOARD_FAB2_LIB.BASEBOARD_FAB2(SCH_1):PVCCIN_CPU0
  BY61  PVCCIN_CPU0    VCCIN<67>  @BASEBOARD_FAB2_LIB.BASEBOARD_FAB2(SCH_1):PVCCIN_CPU0
  BY73  PVCCIN_CPU0    VCCIN<66>  @BASEBOARD_FAB2_LIB.BASEBOARD_FAB2(SCH_1):PVCCIN_CPU0
  BY75  PVCCIN_CPU0    VCCIN<65>  @BASEBOARD_FAB2_LIB.BASEBOARD_FAB2(SCH_1):PVCCIN_CPU0
  BY77  PVCCIN_CPU0    VCCIN<64>  @BASEBOARD_FAB2_LIB.BASEBOARD_FAB2(SCH_1):PVCCIN_CPU0
  BY79  PVCCIN_CPU0    VCCIN<63>  @BASEBOARD_FAB2_LIB.BASEBOARD_FAB2(SCH_1):PVCCIN_CPU0
  BY81  PVCCIN_CPU0    VCCIN<62>  @BASEBOARD_FAB2_LIB.BASEBOARD_FAB2(SCH_1):PVCCIN_CPU0
  BY83  PVCCIN_CPU0    VCCIN<61>  @BASEBOARD_FAB2_LIB.BASEBOARD_FAB2(SCH_1):PVCCIN_CPU0
  CA60  PVCCIN_CPU0    VCCIN<60>  @BASEBOARD_FAB2_LIB.BASEBOARD_FAB2(SCH_1):PVCCIN_CPU0
  CA62  PVCCIN_CPU0    VCCIN<59>  @BASEBOARD_FAB2_LIB.BASEBOARD_FAB2(SCH_1):PVCCIN_CPU0
  CA72  PVCCIN_CPU0    VCCIN<58>  @BASEBOARD_FAB2_LIB.BASEBOARD_FAB2(SCH_1):PVCCIN_CPU0
  CA74  PVCCIN_CPU0    VCCIN<57>  @BASEBOARD_FAB2_LIB.BASEBOARD_FAB2(SCH_1):PVCCIN_CPU0
  CA76  PVCCIN_CPU0    VCCIN<56>  @BASEBOARD_FAB2_LIB.BASEBOARD_FAB2(SCH_1):PVCCIN_CPU0
  CA78  PVCCIN_CPU0    VCCIN<55>  @BASEBOARD_FAB2_LIB.BASEBOARD_FAB2(SCH_1):PVCCIN_CPU0
  CA80  PVCCIN_CPU0    VCCIN<54>  @BASEBOARD_FAB2_LIB.BASEBOARD_FAB2(SCH_1):PVCCIN_CPU0
  CA82  PVCCIN_CPU0    VCCIN<53>  @BASEBOARD_FAB2_LIB.BASEBOARD_FAB2(SCH_1):PVCCIN_CPU0
  CA84  PVCCIN_CPU0    VCCIN<52>  @BASEBOARD_FAB2_LIB.BASEBOARD_FAB2(SCH_1):PVCCIN_CPU0
  CB61  PVCCIN_CPU0    VCCIN<51>  @BASEBOARD_FAB2_LIB.BASEBOARD_FAB2(SCH_1):PVCCIN_CPU0
  CB73  PVCCIN_CPU0    VCCIN<50>  @BASEBOARD_FAB2_LIB.BASEBOARD_FAB2(SCH_1):PVCCIN_CPU0
  CB75  PVCCIN_CPU0    VCCIN<49>  @BASEBOARD_FAB2_LIB.BASEBOARD_FAB2(SCH_1):PVCCIN_CPU0
  CB77  PVCCIN_CPU0    VCCIN<48>  @BASEBOARD_FAB2_LIB.BASEBOARD_FAB2(SCH_1):PVCCIN_CPU0
  CB79  PVCCIN_CPU0    VCCIN<47>  @BASEBOARD_FAB2_LIB.BASEBOARD_FAB2(SCH_1):PVCCIN_CPU0
  CB81  PVCCIN_CPU0    VCCIN<46>  @BASEBOARD_FAB2_LIB.BASEBOARD_FAB2(SCH_1):PVCCIN_CPU0
  CB83  PVCCIN_CPU0    VCCIN<45>  @BASEBOARD_FAB2_LIB.BASEBOARD_FAB2(SCH_1):PVCCIN_CPU0
  CC60  PVCCIN_CPU0    VCCIN<44>  @BASEBOARD_FAB2_LIB.BASEBOARD_FAB2(SCH_1):PVCCIN_CPU0
  CC62  PVCCIN_CPU0    VCCIN<43>  @BASEBOARD_FAB2_LIB.BASEBOARD_FAB2(SCH_1):PVCCIN_CPU0
  CC84  PVCCIN_CPU0    VCCIN<42>  @BASEBOARD_FAB2_LIB.BASEBOARD_FAB2(SCH_1):PVCCIN_CPU0
  CD61  PVCCIN_CPU0    VCCIN<41>  @BASEBOARD_FAB2_LIB.BASEBOARD_FAB2(SCH_1):PVCCIN_CPU0
  CD83  PVCCIN_CPU0    VCCIN<40>  @BASEBOARD_FAB2_LIB.BASEBOARD_FAB2(SCH_1):PVCCIN_CPU0
  CD85  PVCCIN_CPU0    VCCIN<39>  @BASEBOARD_FAB2_LIB.BASEBOARD_FAB2(SCH_1):PVCCIN_CPU0
  CE60  PVCCIN_CPU0    VCCIN<38>  @BASEBOARD_FAB2_LIB.BASEBOARD_FAB2(SCH_1):PVCCIN_CPU0
  CE84  PVCCIN_CPU0    VCCIN<37>  @BASEBOARD_FAB2_LIB.BASEBOARD_FAB2(SCH_1):PVCCIN_CPU0
  CF61  PVCCIN_CPU0    VCCIN<36>  @BASEBOARD_FAB2_LIB.BASEBOARD_FAB2(SCH_1):PVCCIN_CPU0
  CF85  PVCCIN_CPU0    VCCIN<35>  @BASEBOARD_FAB2_LIB.BASEBOARD_FAB2(SCH_1):PVCCIN_CPU0
  CG60  PVCCIN_CPU0    VCCIN<34>  @BASEBOARD_FAB2_LIB.BASEBOARD_FAB2(SCH_1):PVCCIN_CPU0
  CG84  PVCCIN_CPU0    VCCIN<33>  @BASEBOARD_FAB2_LIB.BASEBOARD_FAB2(SCH_1):PVCCIN_CPU0
  CH61  PVCCIN_CPU0    VCCIN<32>  @BASEBOARD_FAB2_LIB.BASEBOARD_FAB2(SCH_1):PVCCIN_CPU0
  CH85  PVCCIN_CPU0    VCCIN<31>  @BASEBOARD_FAB2_LIB.BASEBOARD_FAB2(SCH_1):PVCCIN_CPU0
  CJ60  PVCCIN_CPU0    VCCIN<30>  @BASEBOARD_FAB2_LIB.BASEBOARD_FAB2(SCH_1):PVCCIN_CPU0
  CK59  PVCCIN_CPU0    VCCIN<29>  @BASEBOARD_FAB2_LIB.BASEBOARD_FAB2(SCH_1):PVCCIN_CPU0
  CK61  PVCCIN_CPU0    VCCIN<28>  @BASEBOARD_FAB2_LIB.BASEBOARD_FAB2(SCH_1):PVCCIN_CPU0
  CL58  PVCCIN_CPU0    VCCIN<27>  @BASEBOARD_FAB2_LIB.BASEBOARD_FAB2(SCH_1):PVCCIN_CPU0
  CL60  PVCCIN_CPU0    VCCIN<26>  @BASEBOARD_FAB2_LIB.BASEBOARD_FAB2(SCH_1):PVCCIN_CPU0
  CM57  PVCCIN_CPU0    VCCIN<25>  @BASEBOARD_FAB2_LIB.BASEBOARD_FAB2(SCH_1):PVCCIN_CPU0
  CM59  PVCCIN_CPU0    VCCIN<24>  @BASEBOARD_FAB2_LIB.BASEBOARD_FAB2(SCH_1):PVCCIN_CPU0
  CN56  PVCCIN_CPU0    VCCIN<23>  @BASEBOARD_FAB2_LIB.BASEBOARD_FAB2(SCH_1):PVCCIN_CPU0
  CN58  PVCCIN_CPU0    VCCIN<22>  @BASEBOARD_FAB2_LIB.BASEBOARD_FAB2(SCH_1):PVCCIN_CPU0
  CP33  PVCCIN_CPU0    VCCIN<21>  @BASEBOARD_FAB2_LIB.BASEBOARD_FAB2(SCH_1):PVCCIN_CPU0
  CP55  PVCCIN_CPU0    VCCIN<20>  @BASEBOARD_FAB2_LIB.BASEBOARD_FAB2(SCH_1):PVCCIN_CPU0
  CP57  PVCCIN_CPU0    VCCIN<19>  @BASEBOARD_FAB2_LIB.BASEBOARD_FAB2(SCH_1):PVCCIN_CPU0
  CR34  PVCCIN_CPU0    VCCIN<18>  @BASEBOARD_FAB2_LIB.BASEBOARD_FAB2(SCH_1):PVCCIN_CPU0
  CR54  PVCCIN_CPU0    VCCIN<17>  @BASEBOARD_FAB2_LIB.BASEBOARD_FAB2(SCH_1):PVCCIN_CPU0
  CR56  PVCCIN_CPU0    VCCIN<16>  @BASEBOARD_FAB2_LIB.BASEBOARD_FAB2(SCH_1):PVCCIN_CPU0
  CT37  PVCCIN_CPU0    VCCIN<15>  @BASEBOARD_FAB2_LIB.BASEBOARD_FAB2(SCH_1):PVCCIN_CPU0
  CT39  PVCCIN_CPU0    VCCIN<14>  @BASEBOARD_FAB2_LIB.BASEBOARD_FAB2(SCH_1):PVCCIN_CPU0
  CT41  PVCCIN_CPU0    VCCIN<13>  @BASEBOARD_FAB2_LIB.BASEBOARD_FAB2(SCH_1):PVCCIN_CPU0
  CT53  PVCCIN_CPU0    VCCIN<12>  @BASEBOARD_FAB2_LIB.BASEBOARD_FAB2(SCH_1):PVCCIN_CPU0
  CT55  PVCCIN_CPU0    VCCIN<11>  @BASEBOARD_FAB2_LIB.BASEBOARD_FAB2(SCH_1):PVCCIN_CPU0
  CU38  PVCCIN_CPU0    VCCIN<10>  @BASEBOARD_FAB2_LIB.BASEBOARD_FAB2(SCH_1):PVCCIN_CPU0
  CU40  PVCCIN_CPU0    VCCIN<9>  @BASEBOARD_FAB2_LIB.BASEBOARD_FAB2(SCH_1):PVCCIN_CPU0
  CU42  PVCCIN_CPU0    VCCIN<8>  @BASEBOARD_FAB2_LIB.BASEBOARD_FAB2(SCH_1):PVCCIN_CPU0
  CU52  PVCCIN_CPU0    VCCIN<7>  @BASEBOARD_FAB2_LIB.BASEBOARD_FAB2(SCH_1):PVCCIN_CPU0
  CU54  PVCCIN_CPU0    VCCIN<6>  @BASEBOARD_FAB2_LIB.BASEBOARD_FAB2(SCH_1):PVCCIN_CPU0
  CV51  PVCCIN_CPU0    VCCIN<5>  @BASEBOARD_FAB2_LIB.BASEBOARD_FAB2(SCH_1):PVCCIN_CPU0
  CW46  PVCCIN_CPU0    VCCIN<4>  @BASEBOARD_FAB2_LIB.BASEBOARD_FAB2(SCH_1):PVCCIN_CPU0
  CW48  PVCCIN_CPU0    VCCIN<3>  @BASEBOARD_FAB2_LIB.BASEBOARD_FAB2(SCH_1):PVCCIN_CPU0
  CW50  PVCCIN_CPU0    VCCIN<2>  @BASEBOARD_FAB2_LIB.BASEBOARD_FAB2(SCH_1):PVCCIN_CPU0
  CY47  PVCCIN_CPU0    VCCIN<1>  @BASEBOARD_FAB2_LIB.BASEBOARD_FAB2(SCH_1):PVCCIN_CPU0
  CY49  PVCCIN_CPU0    VCCIN<0>  @BASEBOARD_FAB2_LIB.BASEBOARD_FAB2(SCH_1):PVCCIN_CPU0

SKX_EXT_B_BGA1  I310  U5D1   [SKX_EXT_B_BGA1-IC,TBD]
  AF43  PVCCIN_CPU0    VCCIN<267>  @BASEBOARD_FAB2_LIB.BASEBOARD_FAB2(SCH_1):PVCCIN_CPU0
  AG38  PVCCIN_CPU0    VCCIN<266>  @BASEBOARD_FAB2_LIB.BASEBOARD_FAB2(SCH_1):PVCCIN_CPU0
  AG40  PVCCIN_CPU0    VCCIN<265>  @BASEBOARD_FAB2_LIB.BASEBOARD_FAB2(SCH_1):PVCCIN_CPU0
  AG42  PVCCIN_CPU0    VCCIN<264>  @BASEBOARD_FAB2_LIB.BASEBOARD_FAB2(SCH_1):PVCCIN_CPU0
  AH37  PVCCIN_CPU0    VCCIN<263>  @BASEBOARD_FAB2_LIB.BASEBOARD_FAB2(SCH_1):PVCCIN_CPU0
  AH39  PVCCIN_CPU0    VCCIN<262>  @BASEBOARD_FAB2_LIB.BASEBOARD_FAB2(SCH_1):PVCCIN_CPU0
  AH41  PVCCIN_CPU0    VCCIN<261>  @BASEBOARD_FAB2_LIB.BASEBOARD_FAB2(SCH_1):PVCCIN_CPU0
  AJ36  PVCCIN_CPU0    VCCIN<260>  @BASEBOARD_FAB2_LIB.BASEBOARD_FAB2(SCH_1):PVCCIN_CPU0
  AK35  PVCCIN_CPU0    VCCIN<259>  @BASEBOARD_FAB2_LIB.BASEBOARD_FAB2(SCH_1):PVCCIN_CPU0
  AK45  PVCCIN_CPU0    VCCIN<258>  @BASEBOARD_FAB2_LIB.BASEBOARD_FAB2(SCH_1):PVCCIN_CPU0
  AK47  PVCCIN_CPU0    VCCIN<257>  @BASEBOARD_FAB2_LIB.BASEBOARD_FAB2(SCH_1):PVCCIN_CPU0
  AK49  PVCCIN_CPU0    VCCIN<256>  @BASEBOARD_FAB2_LIB.BASEBOARD_FAB2(SCH_1):PVCCIN_CPU0
  AK51  PVCCIN_CPU0    VCCIN<255>  @BASEBOARD_FAB2_LIB.BASEBOARD_FAB2(SCH_1):PVCCIN_CPU0
  AK53  PVCCIN_CPU0    VCCIN<254>  @BASEBOARD_FAB2_LIB.BASEBOARD_FAB2(SCH_1):PVCCIN_CPU0
  AL34  PVCCIN_CPU0    VCCIN<253>  @BASEBOARD_FAB2_LIB.BASEBOARD_FAB2(SCH_1):PVCCIN_CPU0
  AL46  PVCCIN_CPU0    VCCIN<252>  @BASEBOARD_FAB2_LIB.BASEBOARD_FAB2(SCH_1):PVCCIN_CPU0
  AL48  PVCCIN_CPU0    VCCIN<251>  @BASEBOARD_FAB2_LIB.BASEBOARD_FAB2(SCH_1):PVCCIN_CPU0
  AL50  PVCCIN_CPU0    VCCIN<250>  @BASEBOARD_FAB2_LIB.BASEBOARD_FAB2(SCH_1):PVCCIN_CPU0
  AL52  PVCCIN_CPU0    VCCIN<249>  @BASEBOARD_FAB2_LIB.BASEBOARD_FAB2(SCH_1):PVCCIN_CPU0
  AL54  PVCCIN_CPU0    VCCIN<248>  @BASEBOARD_FAB2_LIB.BASEBOARD_FAB2(SCH_1):PVCCIN_CPU0
  AM33  PVCCIN_CPU0    VCCIN<247>  @BASEBOARD_FAB2_LIB.BASEBOARD_FAB2(SCH_1):PVCCIN_CPU0
  AM53  PVCCIN_CPU0    VCCIN<246>  @BASEBOARD_FAB2_LIB.BASEBOARD_FAB2(SCH_1):PVCCIN_CPU0
  AM55  PVCCIN_CPU0    VCCIN<245>  @BASEBOARD_FAB2_LIB.BASEBOARD_FAB2(SCH_1):PVCCIN_CPU0
  AN32  PVCCIN_CPU0    VCCIN<244>  @BASEBOARD_FAB2_LIB.BASEBOARD_FAB2(SCH_1):PVCCIN_CPU0
  AN54  PVCCIN_CPU0    VCCIN<243>  @BASEBOARD_FAB2_LIB.BASEBOARD_FAB2(SCH_1):PVCCIN_CPU0
  AN56  PVCCIN_CPU0    VCCIN<242>  @BASEBOARD_FAB2_LIB.BASEBOARD_FAB2(SCH_1):PVCCIN_CPU0
  AP55  PVCCIN_CPU0    VCCIN<241>  @BASEBOARD_FAB2_LIB.BASEBOARD_FAB2(SCH_1):PVCCIN_CPU0
  AP57  PVCCIN_CPU0    VCCIN<240>  @BASEBOARD_FAB2_LIB.BASEBOARD_FAB2(SCH_1):PVCCIN_CPU0
  AR56  PVCCIN_CPU0    VCCIN<239>  @BASEBOARD_FAB2_LIB.BASEBOARD_FAB2(SCH_1):PVCCIN_CPU0
  AR58  PVCCIN_CPU0    VCCIN<238>  @BASEBOARD_FAB2_LIB.BASEBOARD_FAB2(SCH_1):PVCCIN_CPU0
  AT57  PVCCIN_CPU0    VCCIN<237>  @BASEBOARD_FAB2_LIB.BASEBOARD_FAB2(SCH_1):PVCCIN_CPU0
  AT59  PVCCIN_CPU0    VCCIN<236>  @BASEBOARD_FAB2_LIB.BASEBOARD_FAB2(SCH_1):PVCCIN_CPU0
  AU58  PVCCIN_CPU0    VCCIN<235>  @BASEBOARD_FAB2_LIB.BASEBOARD_FAB2(SCH_1):PVCCIN_CPU0
  AU60  PVCCIN_CPU0    VCCIN<234>  @BASEBOARD_FAB2_LIB.BASEBOARD_FAB2(SCH_1):PVCCIN_CPU0
  AV59  PVCCIN_CPU0    VCCIN<233>  @BASEBOARD_FAB2_LIB.BASEBOARD_FAB2(SCH_1):PVCCIN_CPU0
  AV61  PVCCIN_CPU0    VCCIN<232>  @BASEBOARD_FAB2_LIB.BASEBOARD_FAB2(SCH_1):PVCCIN_CPU0
  AW60  PVCCIN_CPU0    VCCIN<231>  @BASEBOARD_FAB2_LIB.BASEBOARD_FAB2(SCH_1):PVCCIN_CPU0
  AY61  PVCCIN_CPU0    VCCIN<230>  @BASEBOARD_FAB2_LIB.BASEBOARD_FAB2(SCH_1):PVCCIN_CPU0
  BA60  PVCCIN_CPU0    VCCIN<229>  @BASEBOARD_FAB2_LIB.BASEBOARD_FAB2(SCH_1):PVCCIN_CPU0
  BB61  PVCCIN_CPU0    VCCIN<228>  @BASEBOARD_FAB2_LIB.BASEBOARD_FAB2(SCH_1):PVCCIN_CPU0
  BB85  PVCCIN_CPU0    VCCIN<227>  @BASEBOARD_FAB2_LIB.BASEBOARD_FAB2(SCH_1):PVCCIN_CPU0
  BC60  PVCCIN_CPU0    VCCIN<226>  @BASEBOARD_FAB2_LIB.BASEBOARD_FAB2(SCH_1):PVCCIN_CPU0
  BC62  PVCCIN_CPU0    VCCIN<225>  @BASEBOARD_FAB2_LIB.BASEBOARD_FAB2(SCH_1):PVCCIN_CPU0
  BC84  PVCCIN_CPU0    VCCIN<224>  @BASEBOARD_FAB2_LIB.BASEBOARD_FAB2(SCH_1):PVCCIN_CPU0
  BD61  PVCCIN_CPU0    VCCIN<223>  @BASEBOARD_FAB2_LIB.BASEBOARD_FAB2(SCH_1):PVCCIN_CPU0
  BD73  PVCCIN_CPU0    VCCIN<222>  @BASEBOARD_FAB2_LIB.BASEBOARD_FAB2(SCH_1):PVCCIN_CPU0
  BD75  PVCCIN_CPU0    VCCIN<221>  @BASEBOARD_FAB2_LIB.BASEBOARD_FAB2(SCH_1):PVCCIN_CPU0
  BD77  PVCCIN_CPU0    VCCIN<220>  @BASEBOARD_FAB2_LIB.BASEBOARD_FAB2(SCH_1):PVCCIN_CPU0
  BD79  PVCCIN_CPU0    VCCIN<219>  @BASEBOARD_FAB2_LIB.BASEBOARD_FAB2(SCH_1):PVCCIN_CPU0
  BD81  PVCCIN_CPU0    VCCIN<218>  @BASEBOARD_FAB2_LIB.BASEBOARD_FAB2(SCH_1):PVCCIN_CPU0
  BD83  PVCCIN_CPU0    VCCIN<217>  @BASEBOARD_FAB2_LIB.BASEBOARD_FAB2(SCH_1):PVCCIN_CPU0
  BD85  PVCCIN_CPU0    VCCIN<216>  @BASEBOARD_FAB2_LIB.BASEBOARD_FAB2(SCH_1):PVCCIN_CPU0
  BE60  PVCCIN_CPU0    VCCIN<215>  @BASEBOARD_FAB2_LIB.BASEBOARD_FAB2(SCH_1):PVCCIN_CPU0
  BE62  PVCCIN_CPU0    VCCIN<214>  @BASEBOARD_FAB2_LIB.BASEBOARD_FAB2(SCH_1):PVCCIN_CPU0
  BE72  PVCCIN_CPU0    VCCIN<213>  @BASEBOARD_FAB2_LIB.BASEBOARD_FAB2(SCH_1):PVCCIN_CPU0
  BE74  PVCCIN_CPU0    VCCIN<212>  @BASEBOARD_FAB2_LIB.BASEBOARD_FAB2(SCH_1):PVCCIN_CPU0
  BE76  PVCCIN_CPU0    VCCIN<211>  @BASEBOARD_FAB2_LIB.BASEBOARD_FAB2(SCH_1):PVCCIN_CPU0
  BE78  PVCCIN_CPU0    VCCIN<210>  @BASEBOARD_FAB2_LIB.BASEBOARD_FAB2(SCH_1):PVCCIN_CPU0
  BE80  PVCCIN_CPU0    VCCIN<209>  @BASEBOARD_FAB2_LIB.BASEBOARD_FAB2(SCH_1):PVCCIN_CPU0
  BE82  PVCCIN_CPU0    VCCIN<208>  @BASEBOARD_FAB2_LIB.BASEBOARD_FAB2(SCH_1):PVCCIN_CPU0
  BE84  PVCCIN_CPU0    VCCIN<207>  @BASEBOARD_FAB2_LIB.BASEBOARD_FAB2(SCH_1):PVCCIN_CPU0
  BF61  PVCCIN_CPU0    VCCIN<206>  @BASEBOARD_FAB2_LIB.BASEBOARD_FAB2(SCH_1):PVCCIN_CPU0
  BF73  PVCCIN_CPU0    VCCIN<205>  @BASEBOARD_FAB2_LIB.BASEBOARD_FAB2(SCH_1):PVCCIN_CPU0
  BF75  PVCCIN_CPU0    VCCIN<204>  @BASEBOARD_FAB2_LIB.BASEBOARD_FAB2(SCH_1):PVCCIN_CPU0
  BF77  PVCCIN_CPU0    VCCIN<203>  @BASEBOARD_FAB2_LIB.BASEBOARD_FAB2(SCH_1):PVCCIN_CPU0
  BF79  PVCCIN_CPU0    VCCIN<202>  @BASEBOARD_FAB2_LIB.BASEBOARD_FAB2(SCH_1):PVCCIN_CPU0
  BF81  PVCCIN_CPU0    VCCIN<201>  @BASEBOARD_FAB2_LIB.BASEBOARD_FAB2(SCH_1):PVCCIN_CPU0
  BF83  PVCCIN_CPU0    VCCIN<200>  @BASEBOARD_FAB2_LIB.BASEBOARD_FAB2(SCH_1):PVCCIN_CPU0
  BF85  PVCCIN_CPU0    VCCIN<199>  @BASEBOARD_FAB2_LIB.BASEBOARD_FAB2(SCH_1):PVCCIN_CPU0
  BG60  PVCCIN_CPU0    VCCIN<198>  @BASEBOARD_FAB2_LIB.BASEBOARD_FAB2(SCH_1):PVCCIN_CPU0
  BG62  PVCCIN_CPU0    VCCIN<197>  @BASEBOARD_FAB2_LIB.BASEBOARD_FAB2(SCH_1):PVCCIN_CPU0
  BG64  PVCCIN_CPU0    VCCIN<196>  @BASEBOARD_FAB2_LIB.BASEBOARD_FAB2(SCH_1):PVCCIN_CPU0
  BG66  PVCCIN_CPU0    VCCIN<195>  @BASEBOARD_FAB2_LIB.BASEBOARD_FAB2(SCH_1):PVCCIN_CPU0
  BG68  PVCCIN_CPU0    VCCIN<194>  @BASEBOARD_FAB2_LIB.BASEBOARD_FAB2(SCH_1):PVCCIN_CPU0
  BG70  PVCCIN_CPU0    VCCIN<193>  @BASEBOARD_FAB2_LIB.BASEBOARD_FAB2(SCH_1):PVCCIN_CPU0
  BG84  PVCCIN_CPU0    VCCIN<192>  @BASEBOARD_FAB2_LIB.BASEBOARD_FAB2(SCH_1):PVCCIN_CPU0
  BH61  PVCCIN_CPU0    VCCIN<191>  @BASEBOARD_FAB2_LIB.BASEBOARD_FAB2(SCH_1):PVCCIN_CPU0
  BH63  PVCCIN_CPU0    VCCIN<190>  @BASEBOARD_FAB2_LIB.BASEBOARD_FAB2(SCH_1):PVCCIN_CPU0
  BH65  PVCCIN_CPU0    VCCIN<189>  @BASEBOARD_FAB2_LIB.BASEBOARD_FAB2(SCH_1):PVCCIN_CPU0
  BH67  PVCCIN_CPU0    VCCIN<188>  @BASEBOARD_FAB2_LIB.BASEBOARD_FAB2(SCH_1):PVCCIN_CPU0
  BH69  PVCCIN_CPU0    VCCIN<187>  @BASEBOARD_FAB2_LIB.BASEBOARD_FAB2(SCH_1):PVCCIN_CPU0
  BH71  PVCCIN_CPU0    VCCIN<186>  @BASEBOARD_FAB2_LIB.BASEBOARD_FAB2(SCH_1):PVCCIN_CPU0
  BH73  PVCCIN_CPU0    VCCIN<185>  @BASEBOARD_FAB2_LIB.BASEBOARD_FAB2(SCH_1):PVCCIN_CPU0
  BH75  PVCCIN_CPU0    VCCIN<184>  @BASEBOARD_FAB2_LIB.BASEBOARD_FAB2(SCH_1):PVCCIN_CPU0
  BH77  PVCCIN_CPU0    VCCIN<183>  @BASEBOARD_FAB2_LIB.BASEBOARD_FAB2(SCH_1):PVCCIN_CPU0
  BH79  PVCCIN_CPU0    VCCIN<182>  @BASEBOARD_FAB2_LIB.BASEBOARD_FAB2(SCH_1):PVCCIN_CPU0
  BH81  PVCCIN_CPU0    VCCIN<181>  @BASEBOARD_FAB2_LIB.BASEBOARD_FAB2(SCH_1):PVCCIN_CPU0
  BH83  PVCCIN_CPU0    VCCIN<180>  @BASEBOARD_FAB2_LIB.BASEBOARD_FAB2(SCH_1):PVCCIN_CPU0
  BJ60  PVCCIN_CPU0    VCCIN<179>  @BASEBOARD_FAB2_LIB.BASEBOARD_FAB2(SCH_1):PVCCIN_CPU0
  BJ62  PVCCIN_CPU0    VCCIN<178>  @BASEBOARD_FAB2_LIB.BASEBOARD_FAB2(SCH_1):PVCCIN_CPU0
  BJ64  PVCCIN_CPU0    VCCIN<177>  @BASEBOARD_FAB2_LIB.BASEBOARD_FAB2(SCH_1):PVCCIN_CPU0
  BJ66  PVCCIN_CPU0    VCCIN<176>  @BASEBOARD_FAB2_LIB.BASEBOARD_FAB2(SCH_1):PVCCIN_CPU0
  BJ68  PVCCIN_CPU0    VCCIN<175>  @BASEBOARD_FAB2_LIB.BASEBOARD_FAB2(SCH_1):PVCCIN_CPU0
  BJ70  PVCCIN_CPU0    VCCIN<174>  @BASEBOARD_FAB2_LIB.BASEBOARD_FAB2(SCH_1):PVCCIN_CPU0
  BJ72  PVCCIN_CPU0    VCCIN<173>  @BASEBOARD_FAB2_LIB.BASEBOARD_FAB2(SCH_1):PVCCIN_CPU0
  BJ74  PVCCIN_CPU0    VCCIN<172>  @BASEBOARD_FAB2_LIB.BASEBOARD_FAB2(SCH_1):PVCCIN_CPU0
  BJ76  PVCCIN_CPU0    VCCIN<171>  @BASEBOARD_FAB2_LIB.BASEBOARD_FAB2(SCH_1):PVCCIN_CPU0
  BJ78  PVCCIN_CPU0    VCCIN<170>  @BASEBOARD_FAB2_LIB.BASEBOARD_FAB2(SCH_1):PVCCIN_CPU0
  BJ80  PVCCIN_CPU0    VCCIN<169>  @BASEBOARD_FAB2_LIB.BASEBOARD_FAB2(SCH_1):PVCCIN_CPU0
  BJ82  PVCCIN_CPU0    VCCIN<168>  @BASEBOARD_FAB2_LIB.BASEBOARD_FAB2(SCH_1):PVCCIN_CPU0
  BJ84  PVCCIN_CPU0    VCCIN<167>  @BASEBOARD_FAB2_LIB.BASEBOARD_FAB2(SCH_1):PVCCIN_CPU0
  BK61  PVCCIN_CPU0    VCCIN<166>  @BASEBOARD_FAB2_LIB.BASEBOARD_FAB2(SCH_1):PVCCIN_CPU0
  BK63  PVCCIN_CPU0    VCCIN<165>  @BASEBOARD_FAB2_LIB.BASEBOARD_FAB2(SCH_1):PVCCIN_CPU0
  BK65  PVCCIN_CPU0    VCCIN<164>  @BASEBOARD_FAB2_LIB.BASEBOARD_FAB2(SCH_1):PVCCIN_CPU0
  BK67  PVCCIN_CPU0    VCCIN<163>  @BASEBOARD_FAB2_LIB.BASEBOARD_FAB2(SCH_1):PVCCIN_CPU0
  BK69  PVCCIN_CPU0    VCCIN<162>  @BASEBOARD_FAB2_LIB.BASEBOARD_FAB2(SCH_1):PVCCIN_CPU0
  BK71  PVCCIN_CPU0    VCCIN<161>  @BASEBOARD_FAB2_LIB.BASEBOARD_FAB2(SCH_1):PVCCIN_CPU0
  BK73  PVCCIN_CPU0    VCCIN<160>  @BASEBOARD_FAB2_LIB.BASEBOARD_FAB2(SCH_1):PVCCIN_CPU0
  BK75  PVCCIN_CPU0    VCCIN<159>  @BASEBOARD_FAB2_LIB.BASEBOARD_FAB2(SCH_1):PVCCIN_CPU0
  BK77  PVCCIN_CPU0    VCCIN<158>  @BASEBOARD_FAB2_LIB.BASEBOARD_FAB2(SCH_1):PVCCIN_CPU0
  BK79  PVCCIN_CPU0    VCCIN<157>  @BASEBOARD_FAB2_LIB.BASEBOARD_FAB2(SCH_1):PVCCIN_CPU0
  BK81  PVCCIN_CPU0    VCCIN<156>  @BASEBOARD_FAB2_LIB.BASEBOARD_FAB2(SCH_1):PVCCIN_CPU0
  BK83  PVCCIN_CPU0    VCCIN<155>  @BASEBOARD_FAB2_LIB.BASEBOARD_FAB2(SCH_1):PVCCIN_CPU0
  BL60  PVCCIN_CPU0    VCCIN<154>  @BASEBOARD_FAB2_LIB.BASEBOARD_FAB2(SCH_1):PVCCIN_CPU0
  BL62  PVCCIN_CPU0    VCCIN<153>  @BASEBOARD_FAB2_LIB.BASEBOARD_FAB2(SCH_1):PVCCIN_CPU0
  BL84  PVCCIN_CPU0    VCCIN<152>  @BASEBOARD_FAB2_LIB.BASEBOARD_FAB2(SCH_1):PVCCIN_CPU0
  BM61  PVCCIN_CPU0    VCCIN<151>  @BASEBOARD_FAB2_LIB.BASEBOARD_FAB2(SCH_1):PVCCIN_CPU0
  BM63  PVCCIN_CPU0    VCCIN<150>  @BASEBOARD_FAB2_LIB.BASEBOARD_FAB2(SCH_1):PVCCIN_CPU0
  BM65  PVCCIN_CPU0    VCCIN<149>  @BASEBOARD_FAB2_LIB.BASEBOARD_FAB2(SCH_1):PVCCIN_CPU0
  BM67  PVCCIN_CPU0    VCCIN<148>  @BASEBOARD_FAB2_LIB.BASEBOARD_FAB2(SCH_1):PVCCIN_CPU0
  BM69  PVCCIN_CPU0    VCCIN<147>  @BASEBOARD_FAB2_LIB.BASEBOARD_FAB2(SCH_1):PVCCIN_CPU0
  BM71  PVCCIN_CPU0    VCCIN<146>  @BASEBOARD_FAB2_LIB.BASEBOARD_FAB2(SCH_1):PVCCIN_CPU0
  BM73  PVCCIN_CPU0    VCCIN<145>  @BASEBOARD_FAB2_LIB.BASEBOARD_FAB2(SCH_1):PVCCIN_CPU0
  BM75  PVCCIN_CPU0    VCCIN<144>  @BASEBOARD_FAB2_LIB.BASEBOARD_FAB2(SCH_1):PVCCIN_CPU0
  BM77  PVCCIN_CPU0    VCCIN<143>  @BASEBOARD_FAB2_LIB.BASEBOARD_FAB2(SCH_1):PVCCIN_CPU0
  BM79  PVCCIN_CPU0    VCCIN<142>  @BASEBOARD_FAB2_LIB.BASEBOARD_FAB2(SCH_1):PVCCIN_CPU0
  BM81  PVCCIN_CPU0    VCCIN<141>  @BASEBOARD_FAB2_LIB.BASEBOARD_FAB2(SCH_1):PVCCIN_CPU0
  BM83  PVCCIN_CPU0    VCCIN<140>  @BASEBOARD_FAB2_LIB.BASEBOARD_FAB2(SCH_1):PVCCIN_CPU0
  BN60  PVCCIN_CPU0    VCCIN<139>  @BASEBOARD_FAB2_LIB.BASEBOARD_FAB2(SCH_1):PVCCIN_CPU0
  BN62  PVCCIN_CPU0    VCCIN<138>  @BASEBOARD_FAB2_LIB.BASEBOARD_FAB2(SCH_1):PVCCIN_CPU0
  BN64  PVCCIN_CPU0    VCCIN<137>  @BASEBOARD_FAB2_LIB.BASEBOARD_FAB2(SCH_1):PVCCIN_CPU0
  BN66  PVCCIN_CPU0    VCCIN<136>  @BASEBOARD_FAB2_LIB.BASEBOARD_FAB2(SCH_1):PVCCIN_CPU0
  BN68  PVCCIN_CPU0    VCCIN<135>  @BASEBOARD_FAB2_LIB.BASEBOARD_FAB2(SCH_1):PVCCIN_CPU0
  BN70  PVCCIN_CPU0    VCCIN<134>  @BASEBOARD_FAB2_LIB.BASEBOARD_FAB2(SCH_1):PVCCIN_CPU0
  BN72  PVCCIN_CPU0    VCCIN<133>  @BASEBOARD_FAB2_LIB.BASEBOARD_FAB2(SCH_1):PVCCIN_CPU0
  BN74  PVCCIN_CPU0    VCCIN<132>  @BASEBOARD_FAB2_LIB.BASEBOARD_FAB2(SCH_1):PVCCIN_CPU0
  BN76  PVCCIN_CPU0    VCCIN<131>  @BASEBOARD_FAB2_LIB.BASEBOARD_FAB2(SCH_1):PVCCIN_CPU0
  BN78  PVCCIN_CPU0    VCCIN<130>  @BASEBOARD_FAB2_LIB.BASEBOARD_FAB2(SCH_1):PVCCIN_CPU0

SKX_EXT_B_BGA1  I16  U5D1   [SKX_EXT_B_BGA1-IC,TBD]
  AW20  TP_CPU0_TEST_9  TEST_9  @BASEBOARD_FAB2_LIB.BASEBOARD_FAB2(SCH_1):TP_CPU0_TEST_9
  AW16  TP_CPU0_TEST_8  TEST_8  @BASEBOARD_FAB2_LIB.BASEBOARD_FAB2(SCH_1):TP_CPU0_TEST_8
  AU18  TP_CPU0_TEST_7  TEST_7  @BASEBOARD_FAB2_LIB.BASEBOARD_FAB2(SCH_1):TP_CPU0_TEST_7
  AR16  TP_CPU0_TEST_6  TEST_6  @BASEBOARD_FAB2_LIB.BASEBOARD_FAB2(SCH_1):TP_CPU0_TEST_6
  AW22  TP_CPU0_TEST_10  TEST_10  @BASEBOARD_FAB2_LIB.BASEBOARD_FAB2(SCH_1):TP_CPU0_TEST_10
  CH25  TP_CPU0_RSVD_91  RSVD<91>  @BASEBOARD_FAB2_LIB.BASEBOARD_FAB2(SCH_1):TP_CPU0_RSVD_91
  CH77  TP_CPU0_RSVD_90  RSVD<90>  @BASEBOARD_FAB2_LIB.BASEBOARD_FAB2(SCH_1):TP_CPU0_RSVD_90
  CK19  TP_CPU0_RSVD_85  RSVD<85>  @BASEBOARD_FAB2_LIB.BASEBOARD_FAB2(SCH_1):TP_CPU0_RSVD_85
  CK77  TP_CPU0_RSVD_82  RSVD<82>  @BASEBOARD_FAB2_LIB.BASEBOARD_FAB2(SCH_1):TP_CPU0_RSVD_82
  CJ20  PVCCMCP_CPU0   RSVD<89>  @BASEBOARD_FAB2_LIB.BASEBOARD_FAB2(SCH_1):PVCCMCP_CPU0
  CJ22  PVCCMCP_CPU0   RSVD<88>  @BASEBOARD_FAB2_LIB.BASEBOARD_FAB2(SCH_1):PVCCMCP_CPU0
  CJ24  PVCCMCP_CPU0   RSVD<87>  @BASEBOARD_FAB2_LIB.BASEBOARD_FAB2(SCH_1):PVCCMCP_CPU0
  CJ26  PVCCMCP_CPU0   RSVD<86>  @BASEBOARD_FAB2_LIB.BASEBOARD_FAB2(SCH_1):PVCCMCP_CPU0
  CK23  PVCCMCP_CPU0   RSVD<84>  @BASEBOARD_FAB2_LIB.BASEBOARD_FAB2(SCH_1):PVCCMCP_CPU0
  CK25  PVCCMCP_CPU0   RSVD<83>  @BASEBOARD_FAB2_LIB.BASEBOARD_FAB2(SCH_1):PVCCMCP_CPU0
  CL24  PVCCMCP_CPU0   RSVD<81>  @BASEBOARD_FAB2_LIB.BASEBOARD_FAB2(SCH_1):PVCCMCP_CPU0

SKX_EXT_B_BGA1  I15  U5D1   [SKX_EXT_B_BGA1-IC,TBD]
  CG10  TP_CPU0_RSVD_99  RSVD<99>  @BASEBOARD_FAB2_LIB.BASEBOARD_FAB2(SCH_1):TP_CPU0_RSVD_99
  CG24  TP_CPU0_RSVD_97  RSVD<97>  @BASEBOARD_FAB2_LIB.BASEBOARD_FAB2(SCH_1):TP_CPU0_RSVD_97
  CG78  TP_CPU0_RSVD_95  RSVD<95>  @BASEBOARD_FAB2_LIB.BASEBOARD_FAB2(SCH_1):TP_CPU0_RSVD_95
  CG82  TP_CPU0_RSVD_94  RSVD<94>  @BASEBOARD_FAB2_LIB.BASEBOARD_FAB2(SCH_1):TP_CPU0_RSVD_94
  AY83  TP_CPU0_RSVD_255  RSVD<255>  @BASEBOARD_FAB2_LIB.BASEBOARD_FAB2(SCH_1):TP_CPU0_RSVD_255
  BA78  TP_CPU0_RSVD_171  RSVD<171>  @BASEBOARD_FAB2_LIB.BASEBOARD_FAB2(SCH_1):TP_CPU0_RSVD_171
  BA82  TP_CPU0_RSVD_170  RSVD<170>  @BASEBOARD_FAB2_LIB.BASEBOARD_FAB2(SCH_1):TP_CPU0_RSVD_170
  BB13  TP_CPU0_RSVD_169  RSVD<169>  @BASEBOARD_FAB2_LIB.BASEBOARD_FAB2(SCH_1):TP_CPU0_RSVD_169
  BB15  TP_CPU0_RSVD_168  RSVD<168>  @BASEBOARD_FAB2_LIB.BASEBOARD_FAB2(SCH_1):TP_CPU0_RSVD_168
  BB17  TP_CPU0_RSVD_167  RSVD<167>  @BASEBOARD_FAB2_LIB.BASEBOARD_FAB2(SCH_1):TP_CPU0_RSVD_167
  BB21  TP_CPU0_RSVD_166  RSVD<166>  @BASEBOARD_FAB2_LIB.BASEBOARD_FAB2(SCH_1):TP_CPU0_RSVD_166
  BB65  TP_CPU0_RSVD_164  RSVD<164>  @BASEBOARD_FAB2_LIB.BASEBOARD_FAB2(SCH_1):TP_CPU0_RSVD_164
  BB67  TP_CPU0_RSVD_163  RSVD<163>  @BASEBOARD_FAB2_LIB.BASEBOARD_FAB2(SCH_1):TP_CPU0_RSVD_163
  BC14  TP_CPU0_RSVD_162  RSVD<162>  @BASEBOARD_FAB2_LIB.BASEBOARD_FAB2(SCH_1):TP_CPU0_RSVD_162
  BC18  TP_CPU0_RSVD_161  RSVD<161>  @BASEBOARD_FAB2_LIB.BASEBOARD_FAB2(SCH_1):TP_CPU0_RSVD_161
  BC20  TP_CPU0_RSVD_160  RSVD<160>  @BASEBOARD_FAB2_LIB.BASEBOARD_FAB2(SCH_1):TP_CPU0_RSVD_160
  BC22  TP_CPU0_RSVD_159  RSVD<159>  @BASEBOARD_FAB2_LIB.BASEBOARD_FAB2(SCH_1):TP_CPU0_RSVD_159
  BC64  TP_CPU0_RSVD_158  RSVD<158>  @BASEBOARD_FAB2_LIB.BASEBOARD_FAB2(SCH_1):TP_CPU0_RSVD_158
  BC66  TP_CPU0_RSVD_157  RSVD<157>  @BASEBOARD_FAB2_LIB.BASEBOARD_FAB2(SCH_1):TP_CPU0_RSVD_157
  BC68  TP_CPU0_RSVD_156  RSVD<156>  @BASEBOARD_FAB2_LIB.BASEBOARD_FAB2(SCH_1):TP_CPU0_RSVD_156
  BD17  TP_CPU0_RSVD_155  RSVD<155>  @BASEBOARD_FAB2_LIB.BASEBOARD_FAB2(SCH_1):TP_CPU0_RSVD_155
  BD19  TP_CPU0_RSVD_154  RSVD<154>  @BASEBOARD_FAB2_LIB.BASEBOARD_FAB2(SCH_1):TP_CPU0_RSVD_154
  BD65  TP_CPU0_RSVD_152  RSVD<152>  @BASEBOARD_FAB2_LIB.BASEBOARD_FAB2(SCH_1):TP_CPU0_RSVD_152
  BD67  TP_CPU0_RSVD_151  RSVD<151>  @BASEBOARD_FAB2_LIB.BASEBOARD_FAB2(SCH_1):TP_CPU0_RSVD_151
  BD69  TP_CPU0_RSVD_150  RSVD<150>  @BASEBOARD_FAB2_LIB.BASEBOARD_FAB2(SCH_1):TP_CPU0_RSVD_150
  BE18  TP_CPU0_RSVD_149  RSVD<149>  @BASEBOARD_FAB2_LIB.BASEBOARD_FAB2(SCH_1):TP_CPU0_RSVD_149
  BE20  TP_CPU0_RSVD_148  RSVD<148>  @BASEBOARD_FAB2_LIB.BASEBOARD_FAB2(SCH_1):TP_CPU0_RSVD_148
  BE22  TP_CPU0_RSVD_147  RSVD<147>  @BASEBOARD_FAB2_LIB.BASEBOARD_FAB2(SCH_1):TP_CPU0_RSVD_147
  BF21  TP_CPU0_RSVD_146  RSVD<146>  @BASEBOARD_FAB2_LIB.BASEBOARD_FAB2(SCH_1):TP_CPU0_RSVD_146
  BG18  TP_CPU0_RSVD_145  RSVD<145>  @BASEBOARD_FAB2_LIB.BASEBOARD_FAB2(SCH_1):TP_CPU0_RSVD_145
  BG20  TP_CPU0_RSVD_144  RSVD<144>  @BASEBOARD_FAB2_LIB.BASEBOARD_FAB2(SCH_1):TP_CPU0_RSVD_144
  BV23  TP_CPU0_RSVD_124  RSVD<124>  @BASEBOARD_FAB2_LIB.BASEBOARD_FAB2(SCH_1):TP_CPU0_RSVD_124
  BW10  TP_CPU0_RSVD_123  RSVD<123>  @BASEBOARD_FAB2_LIB.BASEBOARD_FAB2(SCH_1):TP_CPU0_RSVD_123
  BW22  TP_CPU0_RSVD_121  RSVD<121>  @BASEBOARD_FAB2_LIB.BASEBOARD_FAB2(SCH_1):TP_CPU0_RSVD_121
  BY25  TP_CPU0_RSVD_119  RSVD<119>  @BASEBOARD_FAB2_LIB.BASEBOARD_FAB2(SCH_1):TP_CPU0_RSVD_119
  CA24  TP_CPU0_RSVD_117  RSVD<117>  @BASEBOARD_FAB2_LIB.BASEBOARD_FAB2(SCH_1):TP_CPU0_RSVD_117
  CB25  TP_CPU0_RSVD_114  RSVD<114>  @BASEBOARD_FAB2_LIB.BASEBOARD_FAB2(SCH_1):TP_CPU0_RSVD_114
  CB5  TP_CPU0_RSVD_113  RSVD<113>  @BASEBOARD_FAB2_LIB.BASEBOARD_FAB2(SCH_1):TP_CPU0_RSVD_113
  CC6  TP_CPU0_RSVD_111  RSVD<111>  @BASEBOARD_FAB2_LIB.BASEBOARD_FAB2(SCH_1):TP_CPU0_RSVD_111
  CD25  TP_CPU0_RSVD_108  RSVD<108>  @BASEBOARD_FAB2_LIB.BASEBOARD_FAB2(SCH_1):TP_CPU0_RSVD_108
  CE78  TP_CPU0_RSVD_106  RSVD<106>  @BASEBOARD_FAB2_LIB.BASEBOARD_FAB2(SCH_1):TP_CPU0_RSVD_106
  CE80  TP_CPU0_RSVD_105  RSVD<105>  @BASEBOARD_FAB2_LIB.BASEBOARD_FAB2(SCH_1):TP_CPU0_RSVD_105
  CF79  TP_CPU0_RSVD_101  RSVD<101>  @BASEBOARD_FAB2_LIB.BASEBOARD_FAB2(SCH_1):TP_CPU0_RSVD_101
  CF81  TP_CPU0_RSVD_100  RSVD<100>  @BASEBOARD_FAB2_LIB.BASEBOARD_FAB2(SCH_1):TP_CPU0_RSVD_100
  BH19  PVCCMCP_CPU0   RSVD<143>  @BASEBOARD_FAB2_LIB.BASEBOARD_FAB2(SCH_1):PVCCMCP_CPU0
  BJ16  PVCCMCP_CPU0   RSVD<142>  @BASEBOARD_FAB2_LIB.BASEBOARD_FAB2(SCH_1):PVCCMCP_CPU0
  BJ18  PVCCMCP_CPU0   RSVD<141>  @BASEBOARD_FAB2_LIB.BASEBOARD_FAB2(SCH_1):PVCCMCP_CPU0
  BJ20  PVCCMCP_CPU0   RSVD<140>  @BASEBOARD_FAB2_LIB.BASEBOARD_FAB2(SCH_1):PVCCMCP_CPU0
  BK17  PVCCMCP_CPU0   RSVD<139>  @BASEBOARD_FAB2_LIB.BASEBOARD_FAB2(SCH_1):PVCCMCP_CPU0
  BL18  PVCCMCP_CPU0   RSVD<138>  @BASEBOARD_FAB2_LIB.BASEBOARD_FAB2(SCH_1):PVCCMCP_CPU0
  BL20  PVCCMCP_CPU0   RSVD<137>  @BASEBOARD_FAB2_LIB.BASEBOARD_FAB2(SCH_1):PVCCMCP_CPU0
  BM17  PVCCMCP_CPU0   RSVD<136>  @BASEBOARD_FAB2_LIB.BASEBOARD_FAB2(SCH_1):PVCCMCP_CPU0
  BM19  PVCCMCP_CPU0   RSVD<135>  @BASEBOARD_FAB2_LIB.BASEBOARD_FAB2(SCH_1):PVCCMCP_CPU0
  BN18  PVCCMCP_CPU0   RSVD<134>  @BASEBOARD_FAB2_LIB.BASEBOARD_FAB2(SCH_1):PVCCMCP_CPU0
  BP17  PVCCMCP_CPU0   RSVD<133>  @BASEBOARD_FAB2_LIB.BASEBOARD_FAB2(SCH_1):PVCCMCP_CPU0
  BP21  PVCCMCP_CPU0   RSVD<132>  @BASEBOARD_FAB2_LIB.BASEBOARD_FAB2(SCH_1):PVCCMCP_CPU0
  BR22  PVCCMCP_CPU0   RSVD<131>  @BASEBOARD_FAB2_LIB.BASEBOARD_FAB2(SCH_1):PVCCMCP_CPU0
  BR24  PVCCMCP_CPU0   RSVD<130>  @BASEBOARD_FAB2_LIB.BASEBOARD_FAB2(SCH_1):PVCCMCP_CPU0
  BU18  PVCCMCP_CPU0   RSVD<129>  @BASEBOARD_FAB2_LIB.BASEBOARD_FAB2(SCH_1):PVCCMCP_CPU0
  BU20  PVCCMCP_CPU0   RSVD<128>  @BASEBOARD_FAB2_LIB.BASEBOARD_FAB2(SCH_1):PVCCMCP_CPU0
  BU22  PVCCMCP_CPU0   RSVD<127>  @BASEBOARD_FAB2_LIB.BASEBOARD_FAB2(SCH_1):PVCCMCP_CPU0
  BV19  PVCCMCP_CPU0   RSVD<126>  @BASEBOARD_FAB2_LIB.BASEBOARD_FAB2(SCH_1):PVCCMCP_CPU0
  BV21  PVCCMCP_CPU0   RSVD<125>  @BASEBOARD_FAB2_LIB.BASEBOARD_FAB2(SCH_1):PVCCMCP_CPU0
  BW20  PVCCMCP_CPU0   RSVD<122>  @BASEBOARD_FAB2_LIB.BASEBOARD_FAB2(SCH_1):PVCCMCP_CPU0
  BY19  PVCCMCP_CPU0   RSVD<120>  @BASEBOARD_FAB2_LIB.BASEBOARD_FAB2(SCH_1):PVCCMCP_CPU0
  CA22  PVCCMCP_CPU0   RSVD<118>  @BASEBOARD_FAB2_LIB.BASEBOARD_FAB2(SCH_1):PVCCMCP_CPU0
  CB19  PVCCMCP_CPU0   RSVD<116>  @BASEBOARD_FAB2_LIB.BASEBOARD_FAB2(SCH_1):PVCCMCP_CPU0
  CB21  PVCCMCP_CPU0   RSVD<115>  @BASEBOARD_FAB2_LIB.BASEBOARD_FAB2(SCH_1):PVCCMCP_CPU0
  CC20  PVCCMCP_CPU0   RSVD<112>  @BASEBOARD_FAB2_LIB.BASEBOARD_FAB2(SCH_1):PVCCMCP_CPU0
  CD19  PVCCMCP_CPU0   RSVD<110>  @BASEBOARD_FAB2_LIB.BASEBOARD_FAB2(SCH_1):PVCCMCP_CPU0
  CD21  PVCCMCP_CPU0   RSVD<109>  @BASEBOARD_FAB2_LIB.BASEBOARD_FAB2(SCH_1):PVCCMCP_CPU0
  CE22  PVCCMCP_CPU0   RSVD<107>  @BASEBOARD_FAB2_LIB.BASEBOARD_FAB2(SCH_1):PVCCMCP_CPU0
  CF19  PVCCMCP_CPU0   RSVD<104>  @BASEBOARD_FAB2_LIB.BASEBOARD_FAB2(SCH_1):PVCCMCP_CPU0
  CF21  PVCCMCP_CPU0   RSVD<103>  @BASEBOARD_FAB2_LIB.BASEBOARD_FAB2(SCH_1):PVCCMCP_CPU0
  CF23  PVCCMCP_CPU0   RSVD<102>  @BASEBOARD_FAB2_LIB.BASEBOARD_FAB2(SCH_1):PVCCMCP_CPU0
  CG20  PVCCMCP_CPU0   RSVD<98>  @BASEBOARD_FAB2_LIB.BASEBOARD_FAB2(SCH_1):PVCCMCP_CPU0
  CG26  PVCCMCP_CPU0   RSVD<96>  @BASEBOARD_FAB2_LIB.BASEBOARD_FAB2(SCH_1):PVCCMCP_CPU0
  CH21  PVCCMCP_CPU0   RSVD<93>  @BASEBOARD_FAB2_LIB.BASEBOARD_FAB2(SCH_1):PVCCMCP_CPU0
  CH23  PVCCMCP_CPU0   RSVD<92>  @BASEBOARD_FAB2_LIB.BASEBOARD_FAB2(SCH_1):PVCCMCP_CPU0
  BD25  CLK_100M_CPU0_RC_REFCLK1_DP  RSVD<153>  @BASEBOARD_FAB2_LIB.BASEBOARD_FAB2(SCH_1):CLK_100M_CPU0_RC_REFCLK1_DP
  BB25  CLK_100M_CPU0_RC_REFCLK1_DN  RSVD<165>  @BASEBOARD_FAB2_LIB.BASEBOARD_FAB2(SCH_1):CLK_100M_CPU0_RC_REFCLK1_DN

SKX_EXT_B_BGA1  I3   U5D1   [SKX_EXT_B_BGA1-IC,TBD]
  CC12  TP_CPU0_UPI2_RSVD_DT21  UPI2_TX_DN<19>  @BASEBOARD_FAB2_LIB.BASEBOARD_FAB2(SCH_1):TP_CPU0_UPI2_RSVD_DT21
  CA12  TP_CPU0_UPI2_RSVD_DP21  UPI2_TX_DP<19>  @BASEBOARD_FAB2_LIB.BASEBOARD_FAB2(SCH_1):TP_CPU0_UPI2_RSVD_DP21
  CB11  TP_CPU0_UPI2_RSVD_DN20  UPI2_TX_DP<18>  @BASEBOARD_FAB2_LIB.BASEBOARD_FAB2(SCH_1):TP_CPU0_UPI2_RSVD_DN20
  CC10  TP_CPU0_UPI2_RSVD_DM21  UPI2_TX_DN<18>  @BASEBOARD_FAB2_LIB.BASEBOARD_FAB2(SCH_1):TP_CPU0_UPI2_RSVD_DM21
  CE12  TP_CPU0_UPI2_RSVD_DL20  UPI2_TX_DN<17>  @BASEBOARD_FAB2_LIB.BASEBOARD_FAB2(SCH_1):TP_CPU0_UPI2_RSVD_DL20
  CD11  TP_CPU0_UPI2_RSVD_DK19  UPI2_TX_DP<17>  @BASEBOARD_FAB2_LIB.BASEBOARD_FAB2(SCH_1):TP_CPU0_UPI2_RSVD_DK19
  CJ14  TP_CPU0_UPI2_RSVD_DK17  UPI2_TX_DN<14>  @BASEBOARD_FAB2_LIB.BASEBOARD_FAB2(SCH_1):TP_CPU0_UPI2_RSVD_DK17
  CF11  TP_CPU0_UPI2_RSVD_DJ20  UPI2_TX_DP<16>  @BASEBOARD_FAB2_LIB.BASEBOARD_FAB2(SCH_1):TP_CPU0_UPI2_RSVD_DJ20
  CG12  TP_CPU0_UPI2_RSVD_DJ18  UPI2_TX_DP<15>  @BASEBOARD_FAB2_LIB.BASEBOARD_FAB2(SCH_1):TP_CPU0_UPI2_RSVD_DJ18
  CF13  TP_CPU0_UPI2_RSVD_DH19  UPI2_TX_DN<15>  @BASEBOARD_FAB2_LIB.BASEBOARD_FAB2(SCH_1):TP_CPU0_UPI2_RSVD_DH19
  CH13  TP_CPU0_UPI2_RSVD_DH17  UPI2_TX_DP<14>  @BASEBOARD_FAB2_LIB.BASEBOARD_FAB2(SCH_1):TP_CPU0_UPI2_RSVD_DH17
  CH11  TP_CPU0_UPI2_RSVD_DG20  UPI2_TX_DN<16>  @BASEBOARD_FAB2_LIB.BASEBOARD_FAB2(SCH_1):TP_CPU0_UPI2_RSVD_DG20
  CM13  TP_CPU0_UPI2_RSVD_DG18  UPI2_TX_DN<13>  @BASEBOARD_FAB2_LIB.BASEBOARD_FAB2(SCH_1):TP_CPU0_UPI2_RSVD_DG18
  CK13  TP_CPU0_UPI2_RSVD_DF17  UPI2_TX_DP<13>  @BASEBOARD_FAB2_LIB.BASEBOARD_FAB2(SCH_1):TP_CPU0_UPI2_RSVD_DF17
  CW14  TP_CPU0_UPI2_RSVD_DF15  UPI2_TX_DN<11>  @BASEBOARD_FAB2_LIB.BASEBOARD_FAB2(SCH_1):TP_CPU0_UPI2_RSVD_DF15
  CR14  TP_CPU0_UPI2_RSVD_DE16  UPI2_TX_DP<12>  @BASEBOARD_FAB2_LIB.BASEBOARD_FAB2(SCH_1):TP_CPU0_UPI2_RSVD_DE16
  CU14  TP_CPU0_UPI2_RSVD_DD17  UPI2_TX_DN<12>  @BASEBOARD_FAB2_LIB.BASEBOARD_FAB2(SCH_1):TP_CPU0_UPI2_RSVD_DD17
  CV13  TP_CPU0_UPI2_RSVD_DD15  UPI2_TX_DP<11>  @BASEBOARD_FAB2_LIB.BASEBOARD_FAB2(SCH_1):TP_CPU0_UPI2_RSVD_DD15
  DA16  TP_CPU0_UPI2_RSVD_DC16  UPI2_TX_DN<10>  @BASEBOARD_FAB2_LIB.BASEBOARD_FAB2(SCH_1):TP_CPU0_UPI2_RSVD_DC16
  CW16  TP_CPU0_UPI2_RSVD_DB15  UPI2_TX_DP<10>  @BASEBOARD_FAB2_LIB.BASEBOARD_FAB2(SCH_1):TP_CPU0_UPI2_RSVD_DB15
  DC16  TP_CPU0_UPI2_RSVD_DA16  UPI2_TX_DN<9>  @BASEBOARD_FAB2_LIB.BASEBOARD_FAB2(SCH_1):TP_CPU0_UPI2_RSVD_DA16
  DB15  TP_CPU0_UPI2_RSVD_CW16  UPI2_TX_DP<9>  @BASEBOARD_FAB2_LIB.BASEBOARD_FAB2(SCH_1):TP_CPU0_UPI2_RSVD_CW16
  DF15  TP_CPU0_UPI2_RSVD_CW14  UPI2_TX_DN<8>  @BASEBOARD_FAB2_LIB.BASEBOARD_FAB2(SCH_1):TP_CPU0_UPI2_RSVD_CW14
  DD15  TP_CPU0_UPI2_RSVD_CV13  UPI2_TX_DP<8>  @BASEBOARD_FAB2_LIB.BASEBOARD_FAB2(SCH_1):TP_CPU0_UPI2_RSVD_CV13
  DD17  TP_CPU0_UPI2_RSVD_CU14  UPI2_TX_DN<7>  @BASEBOARD_FAB2_LIB.BASEBOARD_FAB2(SCH_1):TP_CPU0_UPI2_RSVD_CU14
  DE16  TP_CPU0_UPI2_RSVD_CR14  UPI2_TX_DP<7>  @BASEBOARD_FAB2_LIB.BASEBOARD_FAB2(SCH_1):TP_CPU0_UPI2_RSVD_CR14
  DG18  TP_CPU0_UPI2_RSVD_CM13  UPI2_TX_DN<6>  @BASEBOARD_FAB2_LIB.BASEBOARD_FAB2(SCH_1):TP_CPU0_UPI2_RSVD_CM13
  DF17  TP_CPU0_UPI2_RSVD_CK13  UPI2_TX_DP<6>  @BASEBOARD_FAB2_LIB.BASEBOARD_FAB2(SCH_1):TP_CPU0_UPI2_RSVD_CK13
  DK17  TP_CPU0_UPI2_RSVD_CJ14  UPI2_TX_DN<5>  @BASEBOARD_FAB2_LIB.BASEBOARD_FAB2(SCH_1):TP_CPU0_UPI2_RSVD_CJ14
  DH17  TP_CPU0_UPI2_RSVD_CH13  UPI2_TX_DP<5>  @BASEBOARD_FAB2_LIB.BASEBOARD_FAB2(SCH_1):TP_CPU0_UPI2_RSVD_CH13
  DG20  TP_CPU0_UPI2_RSVD_CH11  UPI2_TX_DN<3>  @BASEBOARD_FAB2_LIB.BASEBOARD_FAB2(SCH_1):TP_CPU0_UPI2_RSVD_CH11
  DJ18  TP_CPU0_UPI2_RSVD_CG12  UPI2_TX_DP<4>  @BASEBOARD_FAB2_LIB.BASEBOARD_FAB2(SCH_1):TP_CPU0_UPI2_RSVD_CG12
  DH19  TP_CPU0_UPI2_RSVD_CF13  UPI2_TX_DN<4>  @BASEBOARD_FAB2_LIB.BASEBOARD_FAB2(SCH_1):TP_CPU0_UPI2_RSVD_CF13
  DJ20  TP_CPU0_UPI2_RSVD_CF11  UPI2_TX_DP<3>  @BASEBOARD_FAB2_LIB.BASEBOARD_FAB2(SCH_1):TP_CPU0_UPI2_RSVD_CF11
  DL20  TP_CPU0_UPI2_RSVD_CE12  UPI2_TX_DN<2>  @BASEBOARD_FAB2_LIB.BASEBOARD_FAB2(SCH_1):TP_CPU0_UPI2_RSVD_CE12
  DK19  TP_CPU0_UPI2_RSVD_CD11  UPI2_TX_DP<2>  @BASEBOARD_FAB2_LIB.BASEBOARD_FAB2(SCH_1):TP_CPU0_UPI2_RSVD_CD11
  DT21  TP_CPU0_UPI2_RSVD_CC12  UPI2_TX_DN<0>  @BASEBOARD_FAB2_LIB.BASEBOARD_FAB2(SCH_1):TP_CPU0_UPI2_RSVD_CC12
  DM21  TP_CPU0_UPI2_RSVD_CC10  UPI2_TX_DN<1>  @BASEBOARD_FAB2_LIB.BASEBOARD_FAB2(SCH_1):TP_CPU0_UPI2_RSVD_CC10
  DN20  TP_CPU0_UPI2_RSVD_CB11  UPI2_TX_DP<1>  @BASEBOARD_FAB2_LIB.BASEBOARD_FAB2(SCH_1):TP_CPU0_UPI2_RSVD_CB11
  DP21  TP_CPU0_UPI2_RSVD_CA12  UPI2_TX_DP<0>  @BASEBOARD_FAB2_LIB.BASEBOARD_FAB2(SCH_1):TP_CPU0_UPI2_RSVD_CA12
  CA16  GND            UPI2_RX_DP<19>  @BASEBOARD_FAB2_LIB.BASEBOARD_FAB2(SCH_1):GND
  BY15  GND            UPI2_RX_DP<18>  @BASEBOARD_FAB2_LIB.BASEBOARD_FAB2(SCH_1):GND
  CD17  GND            UPI2_RX_DP<17>  @BASEBOARD_FAB2_LIB.BASEBOARD_FAB2(SCH_1):GND
  CC14  GND            UPI2_RX_DP<16>  @BASEBOARD_FAB2_LIB.BASEBOARD_FAB2(SCH_1):GND
  CF15  GND            UPI2_RX_DP<15>  @BASEBOARD_FAB2_LIB.BASEBOARD_FAB2(SCH_1):GND
  CG16  GND            UPI2_RX_DP<14>  @BASEBOARD_FAB2_LIB.BASEBOARD_FAB2(SCH_1):GND
  CK17  GND            UPI2_RX_DP<13>  @BASEBOARD_FAB2_LIB.BASEBOARD_FAB2(SCH_1):GND
  CJ16  GND            UPI2_RX_DP<12>  @BASEBOARD_FAB2_LIB.BASEBOARD_FAB2(SCH_1):GND
  CM21  GND            UPI2_RX_DP<11>  @BASEBOARD_FAB2_LIB.BASEBOARD_FAB2(SCH_1):GND
  CP19  GND            UPI2_RX_DP<10>  @BASEBOARD_FAB2_LIB.BASEBOARD_FAB2(SCH_1):GND
  CN18  GND            UPI2_RX_DP<9>  @BASEBOARD_FAB2_LIB.BASEBOARD_FAB2(SCH_1):GND
  CR20  GND            UPI2_RX_DP<8>  @BASEBOARD_FAB2_LIB.BASEBOARD_FAB2(SCH_1):GND
  CW18  GND            UPI2_RX_DP<7>  @BASEBOARD_FAB2_LIB.BASEBOARD_FAB2(SCH_1):GND
  CU20  GND            UPI2_RX_DP<6>  @BASEBOARD_FAB2_LIB.BASEBOARD_FAB2(SCH_1):GND
  CY19  GND            UPI2_RX_DP<5>  @BASEBOARD_FAB2_LIB.BASEBOARD_FAB2(SCH_1):GND
  DB19  GND            UPI2_RX_DP<4>  @BASEBOARD_FAB2_LIB.BASEBOARD_FAB2(SCH_1):GND
  DC20  GND            UPI2_RX_DP<3>  @BASEBOARD_FAB2_LIB.BASEBOARD_FAB2(SCH_1):GND
  DA22  GND            UPI2_RX_DP<2>  @BASEBOARD_FAB2_LIB.BASEBOARD_FAB2(SCH_1):GND
  DD21  GND            UPI2_RX_DP<1>  @BASEBOARD_FAB2_LIB.BASEBOARD_FAB2(SCH_1):GND
  DG22  GND            UPI2_RX_DP<0>  @BASEBOARD_FAB2_LIB.BASEBOARD_FAB2(SCH_1):GND
  BY17  GND            UPI2_RX_DN<19>  @BASEBOARD_FAB2_LIB.BASEBOARD_FAB2(SCH_1):GND
  CB15  GND            UPI2_RX_DN<18>  @BASEBOARD_FAB2_LIB.BASEBOARD_FAB2(SCH_1):GND
  CF17  GND            UPI2_RX_DN<17>  @BASEBOARD_FAB2_LIB.BASEBOARD_FAB2(SCH_1):GND
  CD15  GND            UPI2_RX_DN<16>  @BASEBOARD_FAB2_LIB.BASEBOARD_FAB2(SCH_1):GND
  CE16  GND            UPI2_RX_DN<15>  @BASEBOARD_FAB2_LIB.BASEBOARD_FAB2(SCH_1):GND
  CH17  GND            UPI2_RX_DN<14>  @BASEBOARD_FAB2_LIB.BASEBOARD_FAB2(SCH_1):GND
  CJ18  GND            UPI2_RX_DN<13>  @BASEBOARD_FAB2_LIB.BASEBOARD_FAB2(SCH_1):GND
  CL16  GND            UPI2_RX_DN<12>  @BASEBOARD_FAB2_LIB.BASEBOARD_FAB2(SCH_1):GND
  CP21  GND            UPI2_RX_DN<11>  @BASEBOARD_FAB2_LIB.BASEBOARD_FAB2(SCH_1):GND
  CN20  GND            UPI2_RX_DN<10>  @BASEBOARD_FAB2_LIB.BASEBOARD_FAB2(SCH_1):GND
  CR18  GND            UPI2_RX_DN<9>  @BASEBOARD_FAB2_LIB.BASEBOARD_FAB2(SCH_1):GND
  CT21  GND            UPI2_RX_DN<8>  @BASEBOARD_FAB2_LIB.BASEBOARD_FAB2(SCH_1):GND
  CV19  GND            UPI2_RX_DN<7>  @BASEBOARD_FAB2_LIB.BASEBOARD_FAB2(SCH_1):GND
  CW20  GND            UPI2_RX_DN<6>  @BASEBOARD_FAB2_LIB.BASEBOARD_FAB2(SCH_1):GND
  DA20  GND            UPI2_RX_DN<5>  @BASEBOARD_FAB2_LIB.BASEBOARD_FAB2(SCH_1):GND
  DD19  GND            UPI2_RX_DN<4>  @BASEBOARD_FAB2_LIB.BASEBOARD_FAB2(SCH_1):GND
  DB21  GND            UPI2_RX_DN<3>  @BASEBOARD_FAB2_LIB.BASEBOARD_FAB2(SCH_1):GND
  DC22  GND            UPI2_RX_DN<2>  @BASEBOARD_FAB2_LIB.BASEBOARD_FAB2(SCH_1):GND
  DE22  GND            UPI2_RX_DN<1>  @BASEBOARD_FAB2_LIB.BASEBOARD_FAB2(SCH_1):GND
  DF23  GND            UPI2_RX_DN<0>  @BASEBOARD_FAB2_LIB.BASEBOARD_FAB2(SCH_1):GND

SKX_EXT_B_BGA1  I86  U5D1   [SKX_EXT_B_BGA1-IC,TBD]
  T15  UPI_CPU1_CPU0_P1P1_DP<9>  UPI1_RX_DP<10>  @BASEBOARD_FAB2_LIB.BASEBOARD_FAB2(SCH_1):UPI_CPU1_CPU0_P1P1_DP<9>
  N16  UPI_CPU1_CPU0_P1P1_DP<8>  UPI1_RX_DP<11>  @BASEBOARD_FAB2_LIB.BASEBOARD_FAB2(SCH_1):UPI_CPU1_CPU0_P1P1_DP<8>
  W16  UPI_CPU1_CPU0_P1P1_DP<7>  UPI1_RX_DP<12>  @BASEBOARD_FAB2_LIB.BASEBOARD_FAB2(SCH_1):UPI_CPU1_CPU0_P1P1_DP<7>
  V17  UPI_CPU1_CPU0_P1P1_DP<6>  UPI1_RX_DP<13>  @BASEBOARD_FAB2_LIB.BASEBOARD_FAB2(SCH_1):UPI_CPU1_CPU0_P1P1_DP<6>
  P19  UPI_CPU1_CPU0_P1P1_DP<5>  UPI1_RX_DP<14>  @BASEBOARD_FAB2_LIB.BASEBOARD_FAB2(SCH_1):UPI_CPU1_CPU0_P1P1_DP<5>
  T19  UPI_CPU1_CPU0_P1P1_DP<4>  UPI1_RX_DP<15>  @BASEBOARD_FAB2_LIB.BASEBOARD_FAB2(SCH_1):UPI_CPU1_CPU0_P1P1_DP<4>
  T21  UPI_CPU1_CPU0_P1P1_DP<3>  UPI1_RX_DP<16>  @BASEBOARD_FAB2_LIB.BASEBOARD_FAB2(SCH_1):UPI_CPU1_CPU0_P1P1_DP<3>
  Y19  UPI_CPU1_CPU0_P1P1_DP<2>  UPI1_RX_DP<17>  @BASEBOARD_FAB2_LIB.BASEBOARD_FAB2(SCH_1):UPI_CPU1_CPU0_P1P1_DP<2>
  W20  UPI_CPU1_CPU0_P1P1_DP<1>  UPI1_RX_DP<18>  @BASEBOARD_FAB2_LIB.BASEBOARD_FAB2(SCH_1):UPI_CPU1_CPU0_P1P1_DP<1>
   R6  UPI_CPU1_CPU0_P1P1_DP<19>  UPI1_RX_DP<0>  @BASEBOARD_FAB2_LIB.BASEBOARD_FAB2(SCH_1):UPI_CPU1_CPU0_P1P1_DP<19>
   T7  UPI_CPU1_CPU0_P1P1_DP<18>  UPI1_RX_DP<1>  @BASEBOARD_FAB2_LIB.BASEBOARD_FAB2(SCH_1):UPI_CPU1_CPU0_P1P1_DP<18>
   U8  UPI_CPU1_CPU0_P1P1_DP<17>  UPI1_RX_DP<2>  @BASEBOARD_FAB2_LIB.BASEBOARD_FAB2(SCH_1):UPI_CPU1_CPU0_P1P1_DP<17>
   R8  UPI_CPU1_CPU0_P1P1_DP<16>  UPI1_RX_DP<3>  @BASEBOARD_FAB2_LIB.BASEBOARD_FAB2(SCH_1):UPI_CPU1_CPU0_P1P1_DP<16>
  N10  UPI_CPU1_CPU0_P1P1_DP<15>  UPI1_RX_DP<4>  @BASEBOARD_FAB2_LIB.BASEBOARD_FAB2(SCH_1):UPI_CPU1_CPU0_P1P1_DP<15>
  U10  UPI_CPU1_CPU0_P1P1_DP<14>  UPI1_RX_DP<5>  @BASEBOARD_FAB2_LIB.BASEBOARD_FAB2(SCH_1):UPI_CPU1_CPU0_P1P1_DP<14>
  T11  UPI_CPU1_CPU0_P1P1_DP<13>  UPI1_RX_DP<6>  @BASEBOARD_FAB2_LIB.BASEBOARD_FAB2(SCH_1):UPI_CPU1_CPU0_P1P1_DP<13>
  N12  UPI_CPU1_CPU0_P1P1_DP<12>  UPI1_RX_DP<7>  @BASEBOARD_FAB2_LIB.BASEBOARD_FAB2(SCH_1):UPI_CPU1_CPU0_P1P1_DP<12>
  M13  UPI_CPU1_CPU0_P1P1_DP<11>  UPI1_RX_DP<8>  @BASEBOARD_FAB2_LIB.BASEBOARD_FAB2(SCH_1):UPI_CPU1_CPU0_P1P1_DP<11>
  P13  UPI_CPU1_CPU0_P1P1_DP<10>  UPI1_RX_DP<9>  @BASEBOARD_FAB2_LIB.BASEBOARD_FAB2(SCH_1):UPI_CPU1_CPU0_P1P1_DP<10>
  AA20  UPI_CPU1_CPU0_P1P1_DP<0>  UPI1_RX_DP<19>  @BASEBOARD_FAB2_LIB.BASEBOARD_FAB2(SCH_1):UPI_CPU1_CPU0_P1P1_DP<0>
  R16  UPI_CPU1_CPU0_P1P1_DN<9>  UPI1_RX_DN<10>  @BASEBOARD_FAB2_LIB.BASEBOARD_FAB2(SCH_1):UPI_CPU1_CPU0_P1P1_DN<9>
  P17  UPI_CPU1_CPU0_P1P1_DN<8>  UPI1_RX_DN<11>  @BASEBOARD_FAB2_LIB.BASEBOARD_FAB2(SCH_1):UPI_CPU1_CPU0_P1P1_DN<8>
  U16  UPI_CPU1_CPU0_P1P1_DN<7>  UPI1_RX_DN<12>  @BASEBOARD_FAB2_LIB.BASEBOARD_FAB2(SCH_1):UPI_CPU1_CPU0_P1P1_DN<7>
  W18  UPI_CPU1_CPU0_P1P1_DN<6>  UPI1_RX_DN<13>  @BASEBOARD_FAB2_LIB.BASEBOARD_FAB2(SCH_1):UPI_CPU1_CPU0_P1P1_DN<6>
  R20  UPI_CPU1_CPU0_P1P1_DN<5>  UPI1_RX_DN<14>  @BASEBOARD_FAB2_LIB.BASEBOARD_FAB2(SCH_1):UPI_CPU1_CPU0_P1P1_DN<5>
  U18  UPI_CPU1_CPU0_P1P1_DN<4>  UPI1_RX_DN<15>  @BASEBOARD_FAB2_LIB.BASEBOARD_FAB2(SCH_1):UPI_CPU1_CPU0_P1P1_DN<4>
  P21  UPI_CPU1_CPU0_P1P1_DN<3>  UPI1_RX_DN<16>  @BASEBOARD_FAB2_LIB.BASEBOARD_FAB2(SCH_1):UPI_CPU1_CPU0_P1P1_DN<3>
  V19  UPI_CPU1_CPU0_P1P1_DN<2>  UPI1_RX_DN<17>  @BASEBOARD_FAB2_LIB.BASEBOARD_FAB2(SCH_1):UPI_CPU1_CPU0_P1P1_DN<2>
  Y21  UPI_CPU1_CPU0_P1P1_DN<1>  UPI1_RX_DN<18>  @BASEBOARD_FAB2_LIB.BASEBOARD_FAB2(SCH_1):UPI_CPU1_CPU0_P1P1_DN<1>
   T5  UPI_CPU1_CPU0_P1P1_DN<19>  UPI1_RX_DN<0>  @BASEBOARD_FAB2_LIB.BASEBOARD_FAB2(SCH_1):UPI_CPU1_CPU0_P1P1_DN<19>
   P7  UPI_CPU1_CPU0_P1P1_DN<18>  UPI1_RX_DN<1>  @BASEBOARD_FAB2_LIB.BASEBOARD_FAB2(SCH_1):UPI_CPU1_CPU0_P1P1_DN<18>
   V7  UPI_CPU1_CPU0_P1P1_DN<17>  UPI1_RX_DN<2>  @BASEBOARD_FAB2_LIB.BASEBOARD_FAB2(SCH_1):UPI_CPU1_CPU0_P1P1_DN<17>
   T9  UPI_CPU1_CPU0_P1P1_DN<16>  UPI1_RX_DN<3>  @BASEBOARD_FAB2_LIB.BASEBOARD_FAB2(SCH_1):UPI_CPU1_CPU0_P1P1_DN<16>
   P9  UPI_CPU1_CPU0_P1P1_DN<15>  UPI1_RX_DN<4>  @BASEBOARD_FAB2_LIB.BASEBOARD_FAB2(SCH_1):UPI_CPU1_CPU0_P1P1_DN<15>
  R10  UPI_CPU1_CPU0_P1P1_DN<14>  UPI1_RX_DN<5>  @BASEBOARD_FAB2_LIB.BASEBOARD_FAB2(SCH_1):UPI_CPU1_CPU0_P1P1_DN<14>
  U12  UPI_CPU1_CPU0_P1P1_DN<13>  UPI1_RX_DN<6>  @BASEBOARD_FAB2_LIB.BASEBOARD_FAB2(SCH_1):UPI_CPU1_CPU0_P1P1_DN<13>
  L12  UPI_CPU1_CPU0_P1P1_DN<12>  UPI1_RX_DN<7>  @BASEBOARD_FAB2_LIB.BASEBOARD_FAB2(SCH_1):UPI_CPU1_CPU0_P1P1_DN<12>
  N14  UPI_CPU1_CPU0_P1P1_DN<11>  UPI1_RX_DN<8>  @BASEBOARD_FAB2_LIB.BASEBOARD_FAB2(SCH_1):UPI_CPU1_CPU0_P1P1_DN<11>
  R12  UPI_CPU1_CPU0_P1P1_DN<10>  UPI1_RX_DN<9>  @BASEBOARD_FAB2_LIB.BASEBOARD_FAB2(SCH_1):UPI_CPU1_CPU0_P1P1_DN<10>
  AB19  UPI_CPU1_CPU0_P1P1_DN<0>  UPI1_RX_DN<19>  @BASEBOARD_FAB2_LIB.BASEBOARD_FAB2(SCH_1):UPI_CPU1_CPU0_P1P1_DN<0>
  G12  UPI_CPU0_CPU1_P1P1_DP<9>  UPI1_TX_DP<10>  @BASEBOARD_FAB2_LIB.BASEBOARD_FAB2(SCH_1):UPI_CPU0_CPU1_P1P1_DP<9>
  F13  UPI_CPU0_CPU1_P1P1_DP<8>  UPI1_TX_DP<11>  @BASEBOARD_FAB2_LIB.BASEBOARD_FAB2(SCH_1):UPI_CPU0_CPU1_P1P1_DP<8>
  E14  UPI_CPU0_CPU1_P1P1_DP<7>  UPI1_TX_DP<12>  @BASEBOARD_FAB2_LIB.BASEBOARD_FAB2(SCH_1):UPI_CPU0_CPU1_P1P1_DP<7>
  H15  UPI_CPU0_CPU1_P1P1_DP<6>  UPI1_TX_DP<13>  @BASEBOARD_FAB2_LIB.BASEBOARD_FAB2(SCH_1):UPI_CPU0_CPU1_P1P1_DP<6>
  G16  UPI_CPU0_CPU1_P1P1_DP<5>  UPI1_TX_DP<14>  @BASEBOARD_FAB2_LIB.BASEBOARD_FAB2(SCH_1):UPI_CPU0_CPU1_P1P1_DP<5>
  L18  UPI_CPU0_CPU1_P1P1_DP<4>  UPI1_TX_DP<15>  @BASEBOARD_FAB2_LIB.BASEBOARD_FAB2(SCH_1):UPI_CPU0_CPU1_P1P1_DP<4>
  J18  UPI_CPU0_CPU1_P1P1_DP<3>  UPI1_TX_DP<16>  @BASEBOARD_FAB2_LIB.BASEBOARD_FAB2(SCH_1):UPI_CPU0_CPU1_P1P1_DP<3>
  H19  UPI_CPU0_CPU1_P1P1_DP<2>  UPI1_TX_DP<17>  @BASEBOARD_FAB2_LIB.BASEBOARD_FAB2(SCH_1):UPI_CPU0_CPU1_P1P1_DP<2>
  G20  UPI_CPU0_CPU1_P1P1_DP<1>  UPI1_TX_DP<18>  @BASEBOARD_FAB2_LIB.BASEBOARD_FAB2(SCH_1):UPI_CPU0_CPU1_P1P1_DP<1>
   P3  UPI_CPU0_CPU1_P1P1_DP<19>  UPI1_TX_DP<0>  @BASEBOARD_FAB2_LIB.BASEBOARD_FAB2(SCH_1):UPI_CPU0_CPU1_P1P1_DP<19>
   K3  UPI_CPU0_CPU1_P1P1_DP<18>  UPI1_TX_DP<1>  @BASEBOARD_FAB2_LIB.BASEBOARD_FAB2(SCH_1):UPI_CPU0_CPU1_P1P1_DP<18>
   M5  UPI_CPU0_CPU1_P1P1_DP<17>  UPI1_TX_DP<2>  @BASEBOARD_FAB2_LIB.BASEBOARD_FAB2(SCH_1):UPI_CPU0_CPU1_P1P1_DP<17>
   H5  UPI_CPU0_CPU1_P1P1_DP<16>  UPI1_TX_DP<3>  @BASEBOARD_FAB2_LIB.BASEBOARD_FAB2(SCH_1):UPI_CPU0_CPU1_P1P1_DP<16>
   F7  UPI_CPU0_CPU1_P1P1_DP<15>  UPI1_TX_DP<4>  @BASEBOARD_FAB2_LIB.BASEBOARD_FAB2(SCH_1):UPI_CPU0_CPU1_P1P1_DP<15>
   K7  UPI_CPU0_CPU1_P1P1_DP<14>  UPI1_TX_DP<5>  @BASEBOARD_FAB2_LIB.BASEBOARD_FAB2(SCH_1):UPI_CPU0_CPU1_P1P1_DP<14>
   J8  UPI_CPU0_CPU1_P1P1_DP<13>  UPI1_TX_DP<6>  @BASEBOARD_FAB2_LIB.BASEBOARD_FAB2(SCH_1):UPI_CPU0_CPU1_P1P1_DP<13>
   F9  UPI_CPU0_CPU1_P1P1_DP<12>  UPI1_TX_DP<7>  @BASEBOARD_FAB2_LIB.BASEBOARD_FAB2(SCH_1):UPI_CPU0_CPU1_P1P1_DP<12>
  E10  UPI_CPU0_CPU1_P1P1_DP<11>  UPI1_TX_DP<8>  @BASEBOARD_FAB2_LIB.BASEBOARD_FAB2(SCH_1):UPI_CPU0_CPU1_P1P1_DP<11>
   H9  UPI_CPU0_CPU1_P1P1_DP<10>  UPI1_TX_DP<9>  @BASEBOARD_FAB2_LIB.BASEBOARD_FAB2(SCH_1):UPI_CPU0_CPU1_P1P1_DP<10>
  K21  UPI_CPU0_CPU1_P1P1_DP<0>  UPI1_TX_DP<19>  @BASEBOARD_FAB2_LIB.BASEBOARD_FAB2(SCH_1):UPI_CPU0_CPU1_P1P1_DP<0>
  E12  UPI_CPU0_CPU1_P1P1_DN<9>  UPI1_TX_DN<10>  @BASEBOARD_FAB2_LIB.BASEBOARD_FAB2(SCH_1):UPI_CPU0_CPU1_P1P1_DN<9>
  G14  UPI_CPU0_CPU1_P1P1_DN<8>  UPI1_TX_DN<11>  @BASEBOARD_FAB2_LIB.BASEBOARD_FAB2(SCH_1):UPI_CPU0_CPU1_P1P1_DN<8>
  D15  UPI_CPU0_CPU1_P1P1_DN<7>  UPI1_TX_DN<12>  @BASEBOARD_FAB2_LIB.BASEBOARD_FAB2(SCH_1):UPI_CPU0_CPU1_P1P1_DN<7>
  F15  UPI_CPU0_CPU1_P1P1_DN<6>  UPI1_TX_DN<13>  @BASEBOARD_FAB2_LIB.BASEBOARD_FAB2(SCH_1):UPI_CPU0_CPU1_P1P1_DN<6>
  H17  UPI_CPU0_CPU1_P1P1_DN<5>  UPI1_TX_DN<14>  @BASEBOARD_FAB2_LIB.BASEBOARD_FAB2(SCH_1):UPI_CPU0_CPU1_P1P1_DN<5>
  K19  UPI_CPU0_CPU1_P1P1_DN<4>  UPI1_TX_DN<15>  @BASEBOARD_FAB2_LIB.BASEBOARD_FAB2(SCH_1):UPI_CPU0_CPU1_P1P1_DN<4>
  G18  UPI_CPU0_CPU1_P1P1_DN<3>  UPI1_TX_DN<16>  @BASEBOARD_FAB2_LIB.BASEBOARD_FAB2(SCH_1):UPI_CPU0_CPU1_P1P1_DN<3>
  J20  UPI_CPU0_CPU1_P1P1_DN<2>  UPI1_TX_DN<17>  @BASEBOARD_FAB2_LIB.BASEBOARD_FAB2(SCH_1):UPI_CPU0_CPU1_P1P1_DN<2>
  F21  UPI_CPU0_CPU1_P1P1_DN<1>  UPI1_TX_DN<18>  @BASEBOARD_FAB2_LIB.BASEBOARD_FAB2(SCH_1):UPI_CPU0_CPU1_P1P1_DN<1>
   M3  UPI_CPU0_CPU1_P1P1_DN<19>  UPI1_TX_DN<0>  @BASEBOARD_FAB2_LIB.BASEBOARD_FAB2(SCH_1):UPI_CPU0_CPU1_P1P1_DN<19>
   L4  UPI_CPU0_CPU1_P1P1_DN<18>  UPI1_TX_DN<1>  @BASEBOARD_FAB2_LIB.BASEBOARD_FAB2(SCH_1):UPI_CPU0_CPU1_P1P1_DN<18>
   K5  UPI_CPU0_CPU1_P1P1_DN<17>  UPI1_TX_DN<2>  @BASEBOARD_FAB2_LIB.BASEBOARD_FAB2(SCH_1):UPI_CPU0_CPU1_P1P1_DN<17>
   J6  UPI_CPU0_CPU1_P1P1_DN<16>  UPI1_TX_DN<3>  @BASEBOARD_FAB2_LIB.BASEBOARD_FAB2(SCH_1):UPI_CPU0_CPU1_P1P1_DN<16>
   G6  UPI_CPU0_CPU1_P1P1_DN<15>  UPI1_TX_DN<4>  @BASEBOARD_FAB2_LIB.BASEBOARD_FAB2(SCH_1):UPI_CPU0_CPU1_P1P1_DN<15>
   H7  UPI_CPU0_CPU1_P1P1_DN<14>  UPI1_TX_DN<5>  @BASEBOARD_FAB2_LIB.BASEBOARD_FAB2(SCH_1):UPI_CPU0_CPU1_P1P1_DN<14>
   K9  UPI_CPU0_CPU1_P1P1_DN<13>  UPI1_TX_DN<6>  @BASEBOARD_FAB2_LIB.BASEBOARD_FAB2(SCH_1):UPI_CPU0_CPU1_P1P1_DN<13>
   D9  UPI_CPU0_CPU1_P1P1_DN<12>  UPI1_TX_DN<7>  @BASEBOARD_FAB2_LIB.BASEBOARD_FAB2(SCH_1):UPI_CPU0_CPU1_P1P1_DN<12>
  F11  UPI_CPU0_CPU1_P1P1_DN<11>  UPI1_TX_DN<8>  @BASEBOARD_FAB2_LIB.BASEBOARD_FAB2(SCH_1):UPI_CPU0_CPU1_P1P1_DN<11>
  G10  UPI_CPU0_CPU1_P1P1_DN<10>  UPI1_TX_DN<9>  @BASEBOARD_FAB2_LIB.BASEBOARD_FAB2(SCH_1):UPI_CPU0_CPU1_P1P1_DN<10>
  H21  UPI_CPU0_CPU1_P1P1_DN<0>  UPI1_TX_DN<19>  @BASEBOARD_FAB2_LIB.BASEBOARD_FAB2(SCH_1):UPI_CPU0_CPU1_P1P1_DN<0>

SKX_EXT_B_BGA1  I86  U5D1   [SKX_EXT_B_BGA1-IC,TBD]
  AN8  UPI_CPU1_CPU0_P0P0_DP<9>  UPI0_RX_DP<10>  @BASEBOARD_FAB2_LIB.BASEBOARD_FAB2(SCH_1):UPI_CPU1_CPU0_P0P0_DP<9>
  AU8  UPI_CPU1_CPU0_P0P0_DP<8>  UPI0_RX_DP<11>  @BASEBOARD_FAB2_LIB.BASEBOARD_FAB2(SCH_1):UPI_CPU1_CPU0_P0P0_DP<8>
  AT9  UPI_CPU1_CPU0_P0P0_DP<7>  UPI0_RX_DP<12>  @BASEBOARD_FAB2_LIB.BASEBOARD_FAB2(SCH_1):UPI_CPU1_CPU0_P0P0_DP<7>
  AY7  UPI_CPU1_CPU0_P0P0_DP<6>  UPI0_RX_DP<13>  @BASEBOARD_FAB2_LIB.BASEBOARD_FAB2(SCH_1):UPI_CPU1_CPU0_P0P0_DP<6>
  BB7  UPI_CPU1_CPU0_P0P0_DP<5>  UPI0_RX_DP<14>  @BASEBOARD_FAB2_LIB.BASEBOARD_FAB2(SCH_1):UPI_CPU1_CPU0_P0P0_DP<5>
  BF7  UPI_CPU1_CPU0_P0P0_DP<4>  UPI0_RX_DP<15>  @BASEBOARD_FAB2_LIB.BASEBOARD_FAB2(SCH_1):UPI_CPU1_CPU0_P0P0_DP<4>
  AV9  UPI_CPU1_CPU0_P0P0_DP<3>  UPI0_RX_DP<16>  @BASEBOARD_FAB2_LIB.BASEBOARD_FAB2(SCH_1):UPI_CPU1_CPU0_P0P0_DP<3>
  BB9  UPI_CPU1_CPU0_P0P0_DP<2>  UPI0_RX_DP<17>  @BASEBOARD_FAB2_LIB.BASEBOARD_FAB2(SCH_1):UPI_CPU1_CPU0_P0P0_DP<2>
  BC10  UPI_CPU1_CPU0_P0P0_DP<1>  UPI0_RX_DP<18>  @BASEBOARD_FAB2_LIB.BASEBOARD_FAB2(SCH_1):UPI_CPU1_CPU0_P0P0_DP<1>
  AB9  UPI_CPU1_CPU0_P0P0_DP<19>  UPI0_RX_DP<0>  @BASEBOARD_FAB2_LIB.BASEBOARD_FAB2(SCH_1):UPI_CPU1_CPU0_P0P0_DP<19>
  AC8  UPI_CPU1_CPU0_P0P0_DP<18>  UPI0_RX_DP<1>  @BASEBOARD_FAB2_LIB.BASEBOARD_FAB2(SCH_1):UPI_CPU1_CPU0_P0P0_DP<18>
  AA6  UPI_CPU1_CPU0_P0P0_DP<17>  UPI0_RX_DP<2>  @BASEBOARD_FAB2_LIB.BASEBOARD_FAB2(SCH_1):UPI_CPU1_CPU0_P0P0_DP<17>
  AC6  UPI_CPU1_CPU0_P0P0_DP<16>  UPI0_RX_DP<3>  @BASEBOARD_FAB2_LIB.BASEBOARD_FAB2(SCH_1):UPI_CPU1_CPU0_P0P0_DP<16>
  AG6  UPI_CPU1_CPU0_P0P0_DP<15>  UPI0_RX_DP<4>  @BASEBOARD_FAB2_LIB.BASEBOARD_FAB2(SCH_1):UPI_CPU1_CPU0_P0P0_DP<15>
  AF7  UPI_CPU1_CPU0_P0P0_DP<14>  UPI0_RX_DP<5>  @BASEBOARD_FAB2_LIB.BASEBOARD_FAB2(SCH_1):UPI_CPU1_CPU0_P0P0_DP<14>
  AH7  UPI_CPU1_CPU0_P0P0_DP<13>  UPI0_RX_DP<6>  @BASEBOARD_FAB2_LIB.BASEBOARD_FAB2(SCH_1):UPI_CPU1_CPU0_P0P0_DP<13>
  AK5  UPI_CPU1_CPU0_P0P0_DP<12>  UPI0_RX_DP<7>  @BASEBOARD_FAB2_LIB.BASEBOARD_FAB2(SCH_1):UPI_CPU1_CPU0_P0P0_DP<12>
  AM7  UPI_CPU1_CPU0_P0P0_DP<11>  UPI0_RX_DP<8>  @BASEBOARD_FAB2_LIB.BASEBOARD_FAB2(SCH_1):UPI_CPU1_CPU0_P0P0_DP<11>
  AL8  UPI_CPU1_CPU0_P0P0_DP<10>  UPI0_RX_DP<9>  @BASEBOARD_FAB2_LIB.BASEBOARD_FAB2(SCH_1):UPI_CPU1_CPU0_P0P0_DP<10>
  BA10  UPI_CPU1_CPU0_P0P0_DP<0>  UPI0_RX_DP<19>  @BASEBOARD_FAB2_LIB.BASEBOARD_FAB2(SCH_1):UPI_CPU1_CPU0_P0P0_DP<0>
  AP7  UPI_CPU1_CPU0_P0P0_DN<9>  UPI0_RX_DN<10>  @BASEBOARD_FAB2_LIB.BASEBOARD_FAB2(SCH_1):UPI_CPU1_CPU0_P0P0_DN<9>
  AR8  UPI_CPU1_CPU0_P0P0_DN<8>  UPI0_RX_DN<11>  @BASEBOARD_FAB2_LIB.BASEBOARD_FAB2(SCH_1):UPI_CPU1_CPU0_P0P0_DN<8>
  AU10  UPI_CPU1_CPU0_P0P0_DN<7>  UPI0_RX_DN<12>  @BASEBOARD_FAB2_LIB.BASEBOARD_FAB2(SCH_1):UPI_CPU1_CPU0_P0P0_DN<7>
  BA8  UPI_CPU1_CPU0_P0P0_DN<6>  UPI0_RX_DN<13>  @BASEBOARD_FAB2_LIB.BASEBOARD_FAB2(SCH_1):UPI_CPU1_CPU0_P0P0_DN<6>
  BC6  UPI_CPU1_CPU0_P0P0_DN<5>  UPI0_RX_DN<14>  @BASEBOARD_FAB2_LIB.BASEBOARD_FAB2(SCH_1):UPI_CPU1_CPU0_P0P0_DN<5>
  BD7  UPI_CPU1_CPU0_P0P0_DN<4>  UPI0_RX_DN<15>  @BASEBOARD_FAB2_LIB.BASEBOARD_FAB2(SCH_1):UPI_CPU1_CPU0_P0P0_DN<4>
  AW8  UPI_CPU1_CPU0_P0P0_DN<3>  UPI0_RX_DN<16>  @BASEBOARD_FAB2_LIB.BASEBOARD_FAB2(SCH_1):UPI_CPU1_CPU0_P0P0_DN<3>
  AY9  UPI_CPU1_CPU0_P0P0_DN<2>  UPI0_RX_DN<17>  @BASEBOARD_FAB2_LIB.BASEBOARD_FAB2(SCH_1):UPI_CPU1_CPU0_P0P0_DN<2>
  BD9  UPI_CPU1_CPU0_P0P0_DN<1>  UPI0_RX_DN<18>  @BASEBOARD_FAB2_LIB.BASEBOARD_FAB2(SCH_1):UPI_CPU1_CPU0_P0P0_DN<1>
  AC10  UPI_CPU1_CPU0_P0P0_DN<19>  UPI0_RX_DN<0>  @BASEBOARD_FAB2_LIB.BASEBOARD_FAB2(SCH_1):UPI_CPU1_CPU0_P0P0_DN<19>
  AA8  UPI_CPU1_CPU0_P0P0_DN<18>  UPI0_RX_DN<1>  @BASEBOARD_FAB2_LIB.BASEBOARD_FAB2(SCH_1):UPI_CPU1_CPU0_P0P0_DN<18>
  AB7  UPI_CPU1_CPU0_P0P0_DN<17>  UPI0_RX_DN<2>  @BASEBOARD_FAB2_LIB.BASEBOARD_FAB2(SCH_1):UPI_CPU1_CPU0_P0P0_DN<17>
  AD5  UPI_CPU1_CPU0_P0P0_DN<16>  UPI0_RX_DN<3>  @BASEBOARD_FAB2_LIB.BASEBOARD_FAB2(SCH_1):UPI_CPU1_CPU0_P0P0_DN<16>
  AE6  UPI_CPU1_CPU0_P0P0_DN<15>  UPI0_RX_DN<4>  @BASEBOARD_FAB2_LIB.BASEBOARD_FAB2(SCH_1):UPI_CPU1_CPU0_P0P0_DN<15>
  AG8  UPI_CPU1_CPU0_P0P0_DN<14>  UPI0_RX_DN<5>  @BASEBOARD_FAB2_LIB.BASEBOARD_FAB2(SCH_1):UPI_CPU1_CPU0_P0P0_DN<14>
  AJ6  UPI_CPU1_CPU0_P0P0_DN<13>  UPI0_RX_DN<6>  @BASEBOARD_FAB2_LIB.BASEBOARD_FAB2(SCH_1):UPI_CPU1_CPU0_P0P0_DN<13>
  AL6  UPI_CPU1_CPU0_P0P0_DN<12>  UPI0_RX_DN<7>  @BASEBOARD_FAB2_LIB.BASEBOARD_FAB2(SCH_1):UPI_CPU1_CPU0_P0P0_DN<12>
  AK7  UPI_CPU1_CPU0_P0P0_DN<11>  UPI0_RX_DN<8>  @BASEBOARD_FAB2_LIB.BASEBOARD_FAB2(SCH_1):UPI_CPU1_CPU0_P0P0_DN<11>
  AM9  UPI_CPU1_CPU0_P0P0_DN<10>  UPI0_RX_DN<9>  @BASEBOARD_FAB2_LIB.BASEBOARD_FAB2(SCH_1):UPI_CPU1_CPU0_P0P0_DN<10>
  BB11  UPI_CPU1_CPU0_P0P0_DN<0>  UPI0_RX_DN<19>  @BASEBOARD_FAB2_LIB.BASEBOARD_FAB2(SCH_1):UPI_CPU1_CPU0_P0P0_DN<0>
  AK3  UPI_CPU0_CPU1_P0P0_DP<9>  UPI0_TX_DP<10>  @BASEBOARD_FAB2_LIB.BASEBOARD_FAB2(SCH_1):UPI_CPU0_CPU1_P0P0_DP<9>
  AP3  UPI_CPU0_CPU1_P0P0_DP<8>  UPI0_TX_DP<11>  @BASEBOARD_FAB2_LIB.BASEBOARD_FAB2(SCH_1):UPI_CPU0_CPU1_P0P0_DP<8>
  AP1  UPI_CPU0_CPU1_P0P0_DP<7>  UPI0_TX_DP<12>  @BASEBOARD_FAB2_LIB.BASEBOARD_FAB2(SCH_1):UPI_CPU0_CPU1_P0P0_DP<7>
  AR2  UPI_CPU0_CPU1_P0P0_DP<6>  UPI0_TX_DP<13>  @BASEBOARD_FAB2_LIB.BASEBOARD_FAB2(SCH_1):UPI_CPU0_CPU1_P0P0_DP<6>
  AR4  UPI_CPU0_CPU1_P0P0_DP<5>  UPI0_TX_DP<14>  @BASEBOARD_FAB2_LIB.BASEBOARD_FAB2(SCH_1):UPI_CPU0_CPU1_P0P0_DP<5>
  AW4  UPI_CPU0_CPU1_P0P0_DP<4>  UPI0_TX_DP<15>  @BASEBOARD_FAB2_LIB.BASEBOARD_FAB2(SCH_1):UPI_CPU0_CPU1_P0P0_DP<4>
  AY3  UPI_CPU0_CPU1_P0P0_DP<3>  UPI0_TX_DP<16>  @BASEBOARD_FAB2_LIB.BASEBOARD_FAB2(SCH_1):UPI_CPU0_CPU1_P0P0_DP<3>
  BC2  UPI_CPU0_CPU1_P0P0_DP<2>  UPI0_TX_DP<17>  @BASEBOARD_FAB2_LIB.BASEBOARD_FAB2(SCH_1):UPI_CPU0_CPU1_P0P0_DP<2>
  BD3  UPI_CPU0_CPU1_P0P0_DP<1>  UPI0_TX_DP<18>  @BASEBOARD_FAB2_LIB.BASEBOARD_FAB2(SCH_1):UPI_CPU0_CPU1_P0P0_DP<1>
   M1  UPI_CPU0_CPU1_P0P0_DP<19>  UPI0_TX_DP<0>  @BASEBOARD_FAB2_LIB.BASEBOARD_FAB2(SCH_1):UPI_CPU0_CPU1_P0P0_DP<19>
   T1  UPI_CPU0_CPU1_P0P0_DP<18>  UPI0_TX_DP<1>  @BASEBOARD_FAB2_LIB.BASEBOARD_FAB2(SCH_1):UPI_CPU0_CPU1_P0P0_DP<18>
   Y3  UPI_CPU0_CPU1_P0P0_DP<17>  UPI0_TX_DP<2>  @BASEBOARD_FAB2_LIB.BASEBOARD_FAB2(SCH_1):UPI_CPU0_CPU1_P0P0_DP<17>
   W2  UPI_CPU0_CPU1_P0P0_DP<16>  UPI0_TX_DP<3>  @BASEBOARD_FAB2_LIB.BASEBOARD_FAB2(SCH_1):UPI_CPU0_CPU1_P0P0_DP<16>
  AA2  UPI_CPU0_CPU1_P0P0_DP<15>  UPI0_TX_DP<4>  @BASEBOARD_FAB2_LIB.BASEBOARD_FAB2(SCH_1):UPI_CPU0_CPU1_P0P0_DP<15>
  AD1  UPI_CPU0_CPU1_P0P0_DP<14>  UPI0_TX_DP<5>  @BASEBOARD_FAB2_LIB.BASEBOARD_FAB2(SCH_1):UPI_CPU0_CPU1_P0P0_DP<14>
  AF3  UPI_CPU0_CPU1_P0P0_DP<13>  UPI0_TX_DP<6>  @BASEBOARD_FAB2_LIB.BASEBOARD_FAB2(SCH_1):UPI_CPU0_CPU1_P0P0_DP<13>
  AG2  UPI_CPU0_CPU1_P0P0_DP<12>  UPI0_TX_DP<7>  @BASEBOARD_FAB2_LIB.BASEBOARD_FAB2(SCH_1):UPI_CPU0_CPU1_P0P0_DP<12>
  AJ2  UPI_CPU0_CPU1_P0P0_DP<11>  UPI0_TX_DP<8>  @BASEBOARD_FAB2_LIB.BASEBOARD_FAB2(SCH_1):UPI_CPU0_CPU1_P0P0_DP<11>
  AK1  UPI_CPU0_CPU1_P0P0_DP<10>  UPI0_TX_DP<9>  @BASEBOARD_FAB2_LIB.BASEBOARD_FAB2(SCH_1):UPI_CPU0_CPU1_P0P0_DP<10>
  BH3  UPI_CPU0_CPU1_P0P0_DP<0>  UPI0_TX_DP<19>  @BASEBOARD_FAB2_LIB.BASEBOARD_FAB2(SCH_1):UPI_CPU0_CPU1_P0P0_DP<0>
  AM3  UPI_CPU0_CPU1_P0P0_DN<9>  UPI0_TX_DN<10>  @BASEBOARD_FAB2_LIB.BASEBOARD_FAB2(SCH_1):UPI_CPU0_CPU1_P0P0_DN<9>
  AN4  UPI_CPU0_CPU1_P0P0_DN<8>  UPI0_TX_DN<11>  @BASEBOARD_FAB2_LIB.BASEBOARD_FAB2(SCH_1):UPI_CPU0_CPU1_P0P0_DN<8>
  AT1  UPI_CPU0_CPU1_P0P0_DN<7>  UPI0_TX_DN<12>  @BASEBOARD_FAB2_LIB.BASEBOARD_FAB2(SCH_1):UPI_CPU0_CPU1_P0P0_DN<7>
  AT3  UPI_CPU0_CPU1_P0P0_DN<6>  UPI0_TX_DN<13>  @BASEBOARD_FAB2_LIB.BASEBOARD_FAB2(SCH_1):UPI_CPU0_CPU1_P0P0_DN<6>
  AU4  UPI_CPU0_CPU1_P0P0_DN<5>  UPI0_TX_DN<14>  @BASEBOARD_FAB2_LIB.BASEBOARD_FAB2(SCH_1):UPI_CPU0_CPU1_P0P0_DN<5>
  AV5  UPI_CPU0_CPU1_P0P0_DN<4>  UPI0_TX_DN<15>  @BASEBOARD_FAB2_LIB.BASEBOARD_FAB2(SCH_1):UPI_CPU0_CPU1_P0P0_DN<4>
  BA4  UPI_CPU0_CPU1_P0P0_DN<3>  UPI0_TX_DN<16>  @BASEBOARD_FAB2_LIB.BASEBOARD_FAB2(SCH_1):UPI_CPU0_CPU1_P0P0_DN<3>
  BB3  UPI_CPU0_CPU1_P0P0_DN<2>  UPI0_TX_DN<17>  @BASEBOARD_FAB2_LIB.BASEBOARD_FAB2(SCH_1):UPI_CPU0_CPU1_P0P0_DN<2>
  BF3  UPI_CPU0_CPU1_P0P0_DN<1>  UPI0_TX_DN<18>  @BASEBOARD_FAB2_LIB.BASEBOARD_FAB2(SCH_1):UPI_CPU0_CPU1_P0P0_DN<1>
   N2  UPI_CPU0_CPU1_P0P0_DN<19>  UPI0_TX_DN<0>  @BASEBOARD_FAB2_LIB.BASEBOARD_FAB2(SCH_1):UPI_CPU0_CPU1_P0P0_DN<19>
   P1  UPI_CPU0_CPU1_P0P0_DN<18>  UPI0_TX_DN<1>  @BASEBOARD_FAB2_LIB.BASEBOARD_FAB2(SCH_1):UPI_CPU0_CPU1_P0P0_DN<18>
   V3  UPI_CPU0_CPU1_P0P0_DN<17>  UPI0_TX_DN<2>  @BASEBOARD_FAB2_LIB.BASEBOARD_FAB2(SCH_1):UPI_CPU0_CPU1_P0P0_DN<17>
   Y1  UPI_CPU0_CPU1_P0P0_DN<16>  UPI0_TX_DN<3>  @BASEBOARD_FAB2_LIB.BASEBOARD_FAB2(SCH_1):UPI_CPU0_CPU1_P0P0_DN<16>
  AB3  UPI_CPU0_CPU1_P0P0_DN<15>  UPI0_TX_DN<4>  @BASEBOARD_FAB2_LIB.BASEBOARD_FAB2(SCH_1):UPI_CPU0_CPU1_P0P0_DN<15>
  AC2  UPI_CPU0_CPU1_P0P0_DN<14>  UPI0_TX_DN<5>  @BASEBOARD_FAB2_LIB.BASEBOARD_FAB2(SCH_1):UPI_CPU0_CPU1_P0P0_DN<14>
  AG4  UPI_CPU0_CPU1_P0P0_DN<13>  UPI0_TX_DN<6>  @BASEBOARD_FAB2_LIB.BASEBOARD_FAB2(SCH_1):UPI_CPU0_CPU1_P0P0_DN<13>
  AE2  UPI_CPU0_CPU1_P0P0_DN<12>  UPI0_TX_DN<7>  @BASEBOARD_FAB2_LIB.BASEBOARD_FAB2(SCH_1):UPI_CPU0_CPU1_P0P0_DN<12>
  AH3  UPI_CPU0_CPU1_P0P0_DN<11>  UPI0_TX_DN<8>  @BASEBOARD_FAB2_LIB.BASEBOARD_FAB2(SCH_1):UPI_CPU0_CPU1_P0P0_DN<11>
  AL2  UPI_CPU0_CPU1_P0P0_DN<10>  UPI0_TX_DN<9>  @BASEBOARD_FAB2_LIB.BASEBOARD_FAB2(SCH_1):UPI_CPU0_CPU1_P0P0_DN<10>
  BG4  UPI_CPU0_CPU1_P0P0_DN<0>  UPI0_TX_DN<19>  @BASEBOARD_FAB2_LIB.BASEBOARD_FAB2(SCH_1):UPI_CPU0_CPU1_P0P0_DN<0>

SKX_EXT_B_BGA1  I89  U5D1   [SKX_EXT_B_BGA1-IC,TBD]
  DM5  P3E_CPU0_PE3_OCP_TXP<9>  PE3_TX_DP<9>  @BASEBOARD_FAB2_LIB.BASEBOARD_FAB2(SCH_1):P3E_CPU0_PE3_OCP_TXP<9>
  DN6  P3E_CPU0_PE3_OCP_TXP<8>  PE3_TX_DP<8>  @BASEBOARD_FAB2_LIB.BASEBOARD_FAB2(SCH_1):P3E_CPU0_PE3_OCP_TXP<8>
  DP7  P3E_CPU0_PE3_OCP_TXP<7>  PE3_TX_DP<7>  @BASEBOARD_FAB2_LIB.BASEBOARD_FAB2(SCH_1):P3E_CPU0_PE3_OCP_TXP<7>
  DT9  P3E_CPU0_PE3_OCP_TXP<6>  PE3_TX_DP<6>  @BASEBOARD_FAB2_LIB.BASEBOARD_FAB2(SCH_1):P3E_CPU0_PE3_OCP_TXP<6>
  DV9  P3E_CPU0_PE3_OCP_TXP<5>  PE3_TX_DP<5>  @BASEBOARD_FAB2_LIB.BASEBOARD_FAB2(SCH_1):P3E_CPU0_PE3_OCP_TXP<5>
  DY9  P3E_CPU0_PE3_OCP_TXP<4>  PE3_TX_DP<4>  @BASEBOARD_FAB2_LIB.BASEBOARD_FAB2(SCH_1):P3E_CPU0_PE3_OCP_TXP<4>
  EA10  P3E_CPU0_PE3_OCP_TXP<3>  PE3_TX_DP<3>  @BASEBOARD_FAB2_LIB.BASEBOARD_FAB2(SCH_1):P3E_CPU0_PE3_OCP_TXP<3>
  EB11  P3E_CPU0_PE3_OCP_TXP<2>  PE3_TX_DP<2>  @BASEBOARD_FAB2_LIB.BASEBOARD_FAB2(SCH_1):P3E_CPU0_PE3_OCP_TXP<2>
  ED13  P3E_CPU0_PE3_OCP_TXP<1>  PE3_TX_DP<1>  @BASEBOARD_FAB2_LIB.BASEBOARD_FAB2(SCH_1):P3E_CPU0_PE3_OCP_TXP<1>
  CV5  P3E_CPU0_PE3_OCP_TXP<15>  PE3_TX_DP<15>  @BASEBOARD_FAB2_LIB.BASEBOARD_FAB2(SCH_1):P3E_CPU0_PE3_OCP_TXP<15>
  DA4  P3E_CPU0_PE3_OCP_TXP<14>  PE3_TX_DP<14>  @BASEBOARD_FAB2_LIB.BASEBOARD_FAB2(SCH_1):P3E_CPU0_PE3_OCP_TXP<14>
  DC6  P3E_CPU0_PE3_OCP_TXP<13>  PE3_TX_DP<13>  @BASEBOARD_FAB2_LIB.BASEBOARD_FAB2(SCH_1):P3E_CPU0_PE3_OCP_TXP<13>
  DG6  P3E_CPU0_PE3_OCP_TXP<12>  PE3_TX_DP<12>  @BASEBOARD_FAB2_LIB.BASEBOARD_FAB2(SCH_1):P3E_CPU0_PE3_OCP_TXP<12>
  DH5  P3E_CPU0_PE3_OCP_TXP<11>  PE3_TX_DP<11>  @BASEBOARD_FAB2_LIB.BASEBOARD_FAB2(SCH_1):P3E_CPU0_PE3_OCP_TXP<11>
  DK5  P3E_CPU0_PE3_OCP_TXP<10>  PE3_TX_DP<10>  @BASEBOARD_FAB2_LIB.BASEBOARD_FAB2(SCH_1):P3E_CPU0_PE3_OCP_TXP<10>
  EC14  P3E_CPU0_PE3_OCP_TXP<0>  PE3_TX_DP<0>  @BASEBOARD_FAB2_LIB.BASEBOARD_FAB2(SCH_1):P3E_CPU0_PE3_OCP_TXP<0>
  DP5  P3E_CPU0_PE3_OCP_TXN<9>  PE3_TX_DN<9>  @BASEBOARD_FAB2_LIB.BASEBOARD_FAB2(SCH_1):P3E_CPU0_PE3_OCP_TXN<9>
  DM7  P3E_CPU0_PE3_OCP_TXN<8>  PE3_TX_DN<8>  @BASEBOARD_FAB2_LIB.BASEBOARD_FAB2(SCH_1):P3E_CPU0_PE3_OCP_TXN<8>
  DR8  P3E_CPU0_PE3_OCP_TXN<7>  PE3_TX_DN<7>  @BASEBOARD_FAB2_LIB.BASEBOARD_FAB2(SCH_1):P3E_CPU0_PE3_OCP_TXN<7>
  DU8  P3E_CPU0_PE3_OCP_TXN<6>  PE3_TX_DN<6>  @BASEBOARD_FAB2_LIB.BASEBOARD_FAB2(SCH_1):P3E_CPU0_PE3_OCP_TXN<6>
  DW10  P3E_CPU0_PE3_OCP_TXN<5>  PE3_TX_DN<5>  @BASEBOARD_FAB2_LIB.BASEBOARD_FAB2(SCH_1):P3E_CPU0_PE3_OCP_TXN<5>
  EB9  P3E_CPU0_PE3_OCP_TXN<4>  PE3_TX_DN<4>  @BASEBOARD_FAB2_LIB.BASEBOARD_FAB2(SCH_1):P3E_CPU0_PE3_OCP_TXN<4>
  DY11  P3E_CPU0_PE3_OCP_TXN<3>  PE3_TX_DN<3>  @BASEBOARD_FAB2_LIB.BASEBOARD_FAB2(SCH_1):P3E_CPU0_PE3_OCP_TXN<3>
  EC12  P3E_CPU0_PE3_OCP_TXN<2>  PE3_TX_DN<2>  @BASEBOARD_FAB2_LIB.BASEBOARD_FAB2(SCH_1):P3E_CPU0_PE3_OCP_TXN<2>
  EE12  P3E_CPU0_PE3_OCP_TXN<1>  PE3_TX_DN<1>  @BASEBOARD_FAB2_LIB.BASEBOARD_FAB2(SCH_1):P3E_CPU0_PE3_OCP_TXN<1>
  CY5  P3E_CPU0_PE3_OCP_TXN<15>  PE3_TX_DN<15>  @BASEBOARD_FAB2_LIB.BASEBOARD_FAB2(SCH_1):P3E_CPU0_PE3_OCP_TXN<15>
  DB5  P3E_CPU0_PE3_OCP_TXN<14>  PE3_TX_DN<14>  @BASEBOARD_FAB2_LIB.BASEBOARD_FAB2(SCH_1):P3E_CPU0_PE3_OCP_TXN<14>
  DD5  P3E_CPU0_PE3_OCP_TXN<13>  PE3_TX_DN<13>  @BASEBOARD_FAB2_LIB.BASEBOARD_FAB2(SCH_1):P3E_CPU0_PE3_OCP_TXN<13>
  DJ6  P3E_CPU0_PE3_OCP_TXN<12>  PE3_TX_DN<12>  @BASEBOARD_FAB2_LIB.BASEBOARD_FAB2(SCH_1):P3E_CPU0_PE3_OCP_TXN<12>
  DJ4  P3E_CPU0_PE3_OCP_TXN<11>  PE3_TX_DN<11>  @BASEBOARD_FAB2_LIB.BASEBOARD_FAB2(SCH_1):P3E_CPU0_PE3_OCP_TXN<11>
  DL6  P3E_CPU0_PE3_OCP_TXN<10>  PE3_TX_DN<10>  @BASEBOARD_FAB2_LIB.BASEBOARD_FAB2(SCH_1):P3E_CPU0_PE3_OCP_TXN<10>
  EE14  P3E_CPU0_PE3_OCP_TXN<0>  PE3_TX_DN<0>  @BASEBOARD_FAB2_LIB.BASEBOARD_FAB2(SCH_1):P3E_CPU0_PE3_OCP_TXN<0>
  DH11  P3E_CPU0_PE3_OCP_RXP<9>  PE3_RX_DP<9>  @BASEBOARD_FAB2_LIB.BASEBOARD_FAB2(SCH_1):P3E_CPU0_PE3_OCP_RXP<9>
  DK13  P3E_CPU0_PE3_OCP_RXP<8>  PE3_RX_DP<8>  @BASEBOARD_FAB2_LIB.BASEBOARD_FAB2(SCH_1):P3E_CPU0_PE3_OCP_RXP<8>
  DJ14  P3E_CPU0_PE3_OCP_RXP<7>  PE3_RX_DP<7>  @BASEBOARD_FAB2_LIB.BASEBOARD_FAB2(SCH_1):P3E_CPU0_PE3_OCP_RXP<7>
  DM13  P3E_CPU0_PE3_OCP_RXP<6>  PE3_RX_DP<6>  @BASEBOARD_FAB2_LIB.BASEBOARD_FAB2(SCH_1):P3E_CPU0_PE3_OCP_RXP<6>
  DP15  P3E_CPU0_PE3_OCP_RXP<5>  PE3_RX_DP<5>  @BASEBOARD_FAB2_LIB.BASEBOARD_FAB2(SCH_1):P3E_CPU0_PE3_OCP_RXP<5>
  DN16  P3E_CPU0_PE3_OCP_RXP<4>  PE3_RX_DP<4>  @BASEBOARD_FAB2_LIB.BASEBOARD_FAB2(SCH_1):P3E_CPU0_PE3_OCP_RXP<4>
  DR18  P3E_CPU0_PE3_OCP_RXP<3>  PE3_RX_DP<3>  @BASEBOARD_FAB2_LIB.BASEBOARD_FAB2(SCH_1):P3E_CPU0_PE3_OCP_RXP<3>
  DV17  P3E_CPU0_PE3_OCP_RXP<2>  PE3_RX_DP<2>  @BASEBOARD_FAB2_LIB.BASEBOARD_FAB2(SCH_1):P3E_CPU0_PE3_OCP_RXP<2>
  DU18  P3E_CPU0_PE3_OCP_RXP<1>  PE3_RX_DP<1>  @BASEBOARD_FAB2_LIB.BASEBOARD_FAB2(SCH_1):P3E_CPU0_PE3_OCP_RXP<1>
  CU10  P3E_CPU0_PE3_OCP_RXP<15>  PE3_RX_DP<15>  @BASEBOARD_FAB2_LIB.BASEBOARD_FAB2(SCH_1):P3E_CPU0_PE3_OCP_RXP<15>
  CW10  P3E_CPU0_PE3_OCP_RXP<14>  PE3_RX_DP<14>  @BASEBOARD_FAB2_LIB.BASEBOARD_FAB2(SCH_1):P3E_CPU0_PE3_OCP_RXP<14>
  DA12  P3E_CPU0_PE3_OCP_RXP<13>  PE3_RX_DP<13>  @BASEBOARD_FAB2_LIB.BASEBOARD_FAB2(SCH_1):P3E_CPU0_PE3_OCP_RXP<13>
  DC12  P3E_CPU0_PE3_OCP_RXP<12>  PE3_RX_DP<12>  @BASEBOARD_FAB2_LIB.BASEBOARD_FAB2(SCH_1):P3E_CPU0_PE3_OCP_RXP<12>
  DF11  P3E_CPU0_PE3_OCP_RXP<11>  PE3_RX_DP<11>  @BASEBOARD_FAB2_LIB.BASEBOARD_FAB2(SCH_1):P3E_CPU0_PE3_OCP_RXP<11>
  DE12  P3E_CPU0_PE3_OCP_RXP<10>  PE3_RX_DP<10>  @BASEBOARD_FAB2_LIB.BASEBOARD_FAB2(SCH_1):P3E_CPU0_PE3_OCP_RXP<10>
  DY17  P3E_CPU0_PE3_OCP_RXP<0>  PE3_RX_DP<0>  @BASEBOARD_FAB2_LIB.BASEBOARD_FAB2(SCH_1):P3E_CPU0_PE3_OCP_RXP<0>
  DJ12  P3E_CPU0_PE3_OCP_RXN<9>  PE3_RX_DN<9>  @BASEBOARD_FAB2_LIB.BASEBOARD_FAB2(SCH_1):P3E_CPU0_PE3_OCP_RXN<9>
  DL12  P3E_CPU0_PE3_OCP_RXN<8>  PE3_RX_DN<8>  @BASEBOARD_FAB2_LIB.BASEBOARD_FAB2(SCH_1):P3E_CPU0_PE3_OCP_RXN<8>
  DL14  P3E_CPU0_PE3_OCP_RXN<7>  PE3_RX_DN<7>  @BASEBOARD_FAB2_LIB.BASEBOARD_FAB2(SCH_1):P3E_CPU0_PE3_OCP_RXN<7>
  DN14  P3E_CPU0_PE3_OCP_RXN<6>  PE3_RX_DN<6>  @BASEBOARD_FAB2_LIB.BASEBOARD_FAB2(SCH_1):P3E_CPU0_PE3_OCP_RXN<6>
  DR14  P3E_CPU0_PE3_OCP_RXN<5>  PE3_RX_DN<5>  @BASEBOARD_FAB2_LIB.BASEBOARD_FAB2(SCH_1):P3E_CPU0_PE3_OCP_RXN<5>
  DR16  P3E_CPU0_PE3_OCP_RXN<4>  PE3_RX_DN<4>  @BASEBOARD_FAB2_LIB.BASEBOARD_FAB2(SCH_1):P3E_CPU0_PE3_OCP_RXN<4>
  DT19  P3E_CPU0_PE3_OCP_RXN<3>  PE3_RX_DN<3>  @BASEBOARD_FAB2_LIB.BASEBOARD_FAB2(SCH_1):P3E_CPU0_PE3_OCP_RXN<3>
  DW16  P3E_CPU0_PE3_OCP_RXN<2>  PE3_RX_DN<2>  @BASEBOARD_FAB2_LIB.BASEBOARD_FAB2(SCH_1):P3E_CPU0_PE3_OCP_RXN<2>
  DW18  P3E_CPU0_PE3_OCP_RXN<1>  PE3_RX_DN<1>  @BASEBOARD_FAB2_LIB.BASEBOARD_FAB2(SCH_1):P3E_CPU0_PE3_OCP_RXN<1>
  CV9  P3E_CPU0_PE3_OCP_RXN<15>  PE3_RX_DN<15>  @BASEBOARD_FAB2_LIB.BASEBOARD_FAB2(SCH_1):P3E_CPU0_PE3_OCP_RXN<15>
  CY11  P3E_CPU0_PE3_OCP_RXN<14>  PE3_RX_DN<14>  @BASEBOARD_FAB2_LIB.BASEBOARD_FAB2(SCH_1):P3E_CPU0_PE3_OCP_RXN<14>
  DB11  P3E_CPU0_PE3_OCP_RXN<13>  PE3_RX_DN<13>  @BASEBOARD_FAB2_LIB.BASEBOARD_FAB2(SCH_1):P3E_CPU0_PE3_OCP_RXN<13>
  DD13  P3E_CPU0_PE3_OCP_RXN<12>  PE3_RX_DN<12>  @BASEBOARD_FAB2_LIB.BASEBOARD_FAB2(SCH_1):P3E_CPU0_PE3_OCP_RXN<12>
  DG10  P3E_CPU0_PE3_OCP_RXN<11>  PE3_RX_DN<11>  @BASEBOARD_FAB2_LIB.BASEBOARD_FAB2(SCH_1):P3E_CPU0_PE3_OCP_RXN<11>
  DG12  P3E_CPU0_PE3_OCP_RXN<10>  PE3_RX_DN<10>  @BASEBOARD_FAB2_LIB.BASEBOARD_FAB2(SCH_1):P3E_CPU0_PE3_OCP_RXN<10>
  EA18  P3E_CPU0_PE3_OCP_RXN<0>  PE3_RX_DN<0>  @BASEBOARD_FAB2_LIB.BASEBOARD_FAB2(SCH_1):P3E_CPU0_PE3_OCP_RXN<0>

SKX_EXT_B_BGA1  I106  U5D1   [SKX_EXT_B_BGA1-IC,TBD]
  BY3  P3E_CPU0_PE2_SS_TXP<9>  PE2_TX_DP<9>  @BASEBOARD_FAB2_LIB.BASEBOARD_FAB2(SCH_1):P3E_CPU0_PE2_SS_TXP<9>
  CD3  P3E_CPU0_PE2_SS_TXP<8>  PE2_TX_DP<8>  @BASEBOARD_FAB2_LIB.BASEBOARD_FAB2(SCH_1):P3E_CPU0_PE2_SS_TXP<8>
  CE4  P3E_CPU0_PE2_SS_TXP<7>  PE2_TX_DP<7>  @BASEBOARD_FAB2_LIB.BASEBOARD_FAB2(SCH_1):P3E_CPU0_PE2_SS_TXP<7>
  CE2  P3E_CPU0_PE2_SS_TXP<6>  PE2_TX_DP<6>  @BASEBOARD_FAB2_LIB.BASEBOARD_FAB2(SCH_1):P3E_CPU0_PE2_SS_TXP<6>
  CK3  P3E_CPU0_PE2_SS_TXP<5>  PE2_TX_DP<5>  @BASEBOARD_FAB2_LIB.BASEBOARD_FAB2(SCH_1):P3E_CPU0_PE2_SS_TXP<5>
  CK1  P3E_CPU0_PE2_SS_TXP<4>  PE2_TX_DP<4>  @BASEBOARD_FAB2_LIB.BASEBOARD_FAB2(SCH_1):P3E_CPU0_PE2_SS_TXP<4>
  CP3  P3E_CPU0_PE2_SS_TXP<3>  PE2_TX_DP<3>  @BASEBOARD_FAB2_LIB.BASEBOARD_FAB2(SCH_1):P3E_CPU0_PE2_SS_TXP<3>
  CR2  P3E_CPU0_PE2_SS_TXP<2>  PE2_TX_DP<2>  @BASEBOARD_FAB2_LIB.BASEBOARD_FAB2(SCH_1):P3E_CPU0_PE2_SS_TXP<2>
  CU2  P3E_CPU0_PE2_SS_TXP<1>  PE2_TX_DP<1>  @BASEBOARD_FAB2_LIB.BASEBOARD_FAB2(SCH_1):P3E_CPU0_PE2_SS_TXP<1>
  BK5  P3E_CPU0_PE2_SS_TXP<15>  PE2_TX_DP<15>  @BASEBOARD_FAB2_LIB.BASEBOARD_FAB2(SCH_1):P3E_CPU0_PE2_SS_TXP<15>
  BM3  P3E_CPU0_PE2_SS_TXP<14>  PE2_TX_DP<14>  @BASEBOARD_FAB2_LIB.BASEBOARD_FAB2(SCH_1):P3E_CPU0_PE2_SS_TXP<14>
  BN4  P3E_CPU0_PE2_SS_TXP<13>  PE2_TX_DP<13>  @BASEBOARD_FAB2_LIB.BASEBOARD_FAB2(SCH_1):P3E_CPU0_PE2_SS_TXP<13>
  BR4  P3E_CPU0_PE2_SS_TXP<12>  PE2_TX_DP<12>  @BASEBOARD_FAB2_LIB.BASEBOARD_FAB2(SCH_1):P3E_CPU0_PE2_SS_TXP<12>
  BV3  P3E_CPU0_PE2_SS_TXP<11>  PE2_TX_DP<11>  @BASEBOARD_FAB2_LIB.BASEBOARD_FAB2(SCH_1):P3E_CPU0_PE2_SS_TXP<11>
  BY5  P3E_CPU0_PE2_SS_TXP<10>  PE2_TX_DP<10>  @BASEBOARD_FAB2_LIB.BASEBOARD_FAB2(SCH_1):P3E_CPU0_PE2_SS_TXP<10>
  CW4  P3E_CPU0_PE2_SS_TXP<0>  PE2_TX_DP<0>  @BASEBOARD_FAB2_LIB.BASEBOARD_FAB2(SCH_1):P3E_CPU0_PE2_SS_TXP<0>
  CB3  P3E_CPU0_PE2_SS_TXN<9>  PE2_TX_DN<9>  @BASEBOARD_FAB2_LIB.BASEBOARD_FAB2(SCH_1):P3E_CPU0_PE2_SS_TXN<9>
  CC2  P3E_CPU0_PE2_SS_TXN<8>  PE2_TX_DN<8>  @BASEBOARD_FAB2_LIB.BASEBOARD_FAB2(SCH_1):P3E_CPU0_PE2_SS_TXN<8>
  CF3  P3E_CPU0_PE2_SS_TXN<7>  PE2_TX_DN<7>  @BASEBOARD_FAB2_LIB.BASEBOARD_FAB2(SCH_1):P3E_CPU0_PE2_SS_TXN<7>
  CG2  P3E_CPU0_PE2_SS_TXN<6>  PE2_TX_DN<6>  @BASEBOARD_FAB2_LIB.BASEBOARD_FAB2(SCH_1):P3E_CPU0_PE2_SS_TXN<6>
  CL2  P3E_CPU0_PE2_SS_TXN<5>  PE2_TX_DN<5>  @BASEBOARD_FAB2_LIB.BASEBOARD_FAB2(SCH_1):P3E_CPU0_PE2_SS_TXN<5>
  CM1  P3E_CPU0_PE2_SS_TXN<4>  PE2_TX_DN<4>  @BASEBOARD_FAB2_LIB.BASEBOARD_FAB2(SCH_1):P3E_CPU0_PE2_SS_TXN<4>
  CT3  P3E_CPU0_PE2_SS_TXN<3>  PE2_TX_DN<3>  @BASEBOARD_FAB2_LIB.BASEBOARD_FAB2(SCH_1):P3E_CPU0_PE2_SS_TXN<3>
  CT1  P3E_CPU0_PE2_SS_TXN<2>  PE2_TX_DN<2>  @BASEBOARD_FAB2_LIB.BASEBOARD_FAB2(SCH_1):P3E_CPU0_PE2_SS_TXN<2>
  CV3  P3E_CPU0_PE2_SS_TXN<1>  PE2_TX_DN<1>  @BASEBOARD_FAB2_LIB.BASEBOARD_FAB2(SCH_1):P3E_CPU0_PE2_SS_TXN<1>
  BM5  P3E_CPU0_PE2_SS_TXN<15>  PE2_TX_DN<15>  @BASEBOARD_FAB2_LIB.BASEBOARD_FAB2(SCH_1):P3E_CPU0_PE2_SS_TXN<15>
  BL4  P3E_CPU0_PE2_SS_TXN<14>  PE2_TX_DN<14>  @BASEBOARD_FAB2_LIB.BASEBOARD_FAB2(SCH_1):P3E_CPU0_PE2_SS_TXN<14>
  BP5  P3E_CPU0_PE2_SS_TXN<13>  PE2_TX_DN<13>  @BASEBOARD_FAB2_LIB.BASEBOARD_FAB2(SCH_1):P3E_CPU0_PE2_SS_TXN<13>
  BU4  P3E_CPU0_PE2_SS_TXN<12>  PE2_TX_DN<12>  @BASEBOARD_FAB2_LIB.BASEBOARD_FAB2(SCH_1):P3E_CPU0_PE2_SS_TXN<12>
  BW4  P3E_CPU0_PE2_SS_TXN<11>  PE2_TX_DN<11>  @BASEBOARD_FAB2_LIB.BASEBOARD_FAB2(SCH_1):P3E_CPU0_PE2_SS_TXN<11>
  CA4  P3E_CPU0_PE2_SS_TXN<10>  PE2_TX_DN<10>  @BASEBOARD_FAB2_LIB.BASEBOARD_FAB2(SCH_1):P3E_CPU0_PE2_SS_TXN<10>
  CY3  P3E_CPU0_PE2_SS_TXN<0>  PE2_TX_DN<0>  @BASEBOARD_FAB2_LIB.BASEBOARD_FAB2(SCH_1):P3E_CPU0_PE2_SS_TXN<0>
  BW8  P3E_CPU0_PE2_SS_RXP<9>  PE2_RX_DP<9>  @BASEBOARD_FAB2_LIB.BASEBOARD_FAB2(SCH_1):P3E_CPU0_PE2_SS_RXP<9>
  BV9  P3E_CPU0_PE2_SS_RXP<8>  PE2_RX_DP<8>  @BASEBOARD_FAB2_LIB.BASEBOARD_FAB2(SCH_1):P3E_CPU0_PE2_SS_RXP<8>
  CC8  P3E_CPU0_PE2_SS_RXP<7>  PE2_RX_DP<7>  @BASEBOARD_FAB2_LIB.BASEBOARD_FAB2(SCH_1):P3E_CPU0_PE2_SS_RXP<7>
  CD7  P3E_CPU0_PE2_SS_RXP<6>  PE2_RX_DP<6>  @BASEBOARD_FAB2_LIB.BASEBOARD_FAB2(SCH_1):P3E_CPU0_PE2_SS_RXP<6>
  CF7  P3E_CPU0_PE2_SS_RXP<5>  PE2_RX_DP<5>  @BASEBOARD_FAB2_LIB.BASEBOARD_FAB2(SCH_1):P3E_CPU0_PE2_SS_RXP<5>
  CH7  P3E_CPU0_PE2_SS_RXP<4>  PE2_RX_DP<4>  @BASEBOARD_FAB2_LIB.BASEBOARD_FAB2(SCH_1):P3E_CPU0_PE2_SS_RXP<4>
  CL6  P3E_CPU0_PE2_SS_RXP<3>  PE2_RX_DP<3>  @BASEBOARD_FAB2_LIB.BASEBOARD_FAB2(SCH_1):P3E_CPU0_PE2_SS_RXP<3>
  CN8  P3E_CPU0_PE2_SS_RXP<2>  PE2_RX_DP<2>  @BASEBOARD_FAB2_LIB.BASEBOARD_FAB2(SCH_1):P3E_CPU0_PE2_SS_RXP<2>
  CM9  P3E_CPU0_PE2_SS_RXP<1>  PE2_RX_DP<1>  @BASEBOARD_FAB2_LIB.BASEBOARD_FAB2(SCH_1):P3E_CPU0_PE2_SS_RXP<1>
  BJ10  P3E_CPU0_PE2_SS_RXP<15>  PE2_RX_DP<15>  @BASEBOARD_FAB2_LIB.BASEBOARD_FAB2(SCH_1):P3E_CPU0_PE2_SS_RXP<15>
  BJ8  P3E_CPU0_PE2_SS_RXP<14>  PE2_RX_DP<14>  @BASEBOARD_FAB2_LIB.BASEBOARD_FAB2(SCH_1):P3E_CPU0_PE2_SS_RXP<14>
  BM7  P3E_CPU0_PE2_SS_RXP<13>  PE2_RX_DP<13>  @BASEBOARD_FAB2_LIB.BASEBOARD_FAB2(SCH_1):P3E_CPU0_PE2_SS_RXP<13>
  BP9  P3E_CPU0_PE2_SS_RXP<12>  PE2_RX_DP<12>  @BASEBOARD_FAB2_LIB.BASEBOARD_FAB2(SCH_1):P3E_CPU0_PE2_SS_RXP<12>
  BP7  P3E_CPU0_PE2_SS_RXP<11>  PE2_RX_DP<11>  @BASEBOARD_FAB2_LIB.BASEBOARD_FAB2(SCH_1):P3E_CPU0_PE2_SS_RXP<11>
  BU6  P3E_CPU0_PE2_SS_RXP<10>  PE2_RX_DP<10>  @BASEBOARD_FAB2_LIB.BASEBOARD_FAB2(SCH_1):P3E_CPU0_PE2_SS_RXP<10>
  CR8  P3E_CPU0_PE2_SS_RXP<0>  PE2_RX_DP<0>  @BASEBOARD_FAB2_LIB.BASEBOARD_FAB2(SCH_1):P3E_CPU0_PE2_SS_RXP<0>
  BY7  P3E_CPU0_PE2_SS_RXN<9>  PE2_RX_DN<9>  @BASEBOARD_FAB2_LIB.BASEBOARD_FAB2(SCH_1):P3E_CPU0_PE2_SS_RXN<9>
  BY9  P3E_CPU0_PE2_SS_RXN<8>  PE2_RX_DN<8>  @BASEBOARD_FAB2_LIB.BASEBOARD_FAB2(SCH_1):P3E_CPU0_PE2_SS_RXN<8>
  CE8  P3E_CPU0_PE2_SS_RXN<7>  PE2_RX_DN<7>  @BASEBOARD_FAB2_LIB.BASEBOARD_FAB2(SCH_1):P3E_CPU0_PE2_SS_RXN<7>
  CE6  P3E_CPU0_PE2_SS_RXN<6>  PE2_RX_DN<6>  @BASEBOARD_FAB2_LIB.BASEBOARD_FAB2(SCH_1):P3E_CPU0_PE2_SS_RXN<6>
  CG8  P3E_CPU0_PE2_SS_RXN<5>  PE2_RX_DN<5>  @BASEBOARD_FAB2_LIB.BASEBOARD_FAB2(SCH_1):P3E_CPU0_PE2_SS_RXN<5>
  CK7  P3E_CPU0_PE2_SS_RXN<4>  PE2_RX_DN<4>  @BASEBOARD_FAB2_LIB.BASEBOARD_FAB2(SCH_1):P3E_CPU0_PE2_SS_RXN<4>
  CM7  P3E_CPU0_PE2_SS_RXN<3>  PE2_RX_DN<3>  @BASEBOARD_FAB2_LIB.BASEBOARD_FAB2(SCH_1):P3E_CPU0_PE2_SS_RXN<3>
  CP7  P3E_CPU0_PE2_SS_RXN<2>  PE2_RX_DN<2>  @BASEBOARD_FAB2_LIB.BASEBOARD_FAB2(SCH_1):P3E_CPU0_PE2_SS_RXN<2>
  CP9  P3E_CPU0_PE2_SS_RXN<1>  PE2_RX_DN<1>  @BASEBOARD_FAB2_LIB.BASEBOARD_FAB2(SCH_1):P3E_CPU0_PE2_SS_RXN<1>
  BK9  P3E_CPU0_PE2_SS_RXN<15>  PE2_RX_DN<15>  @BASEBOARD_FAB2_LIB.BASEBOARD_FAB2(SCH_1):P3E_CPU0_PE2_SS_RXN<15>
  BL8  P3E_CPU0_PE2_SS_RXN<14>  PE2_RX_DN<14>  @BASEBOARD_FAB2_LIB.BASEBOARD_FAB2(SCH_1):P3E_CPU0_PE2_SS_RXN<14>
  BN8  P3E_CPU0_PE2_SS_RXN<13>  PE2_RX_DN<13>  @BASEBOARD_FAB2_LIB.BASEBOARD_FAB2(SCH_1):P3E_CPU0_PE2_SS_RXN<13>
  BR8  P3E_CPU0_PE2_SS_RXN<12>  PE2_RX_DN<12>  @BASEBOARD_FAB2_LIB.BASEBOARD_FAB2(SCH_1):P3E_CPU0_PE2_SS_RXN<12>
  BT7  P3E_CPU0_PE2_SS_RXN<11>  PE2_RX_DN<11>  @BASEBOARD_FAB2_LIB.BASEBOARD_FAB2(SCH_1):P3E_CPU0_PE2_SS_RXN<11>
  BV7  P3E_CPU0_PE2_SS_RXN<10>  PE2_RX_DN<10>  @BASEBOARD_FAB2_LIB.BASEBOARD_FAB2(SCH_1):P3E_CPU0_PE2_SS_RXN<10>
  CT9  P3E_CPU0_PE2_SS_RXN<0>  PE2_RX_DN<0>  @BASEBOARD_FAB2_LIB.BASEBOARD_FAB2(SCH_1):P3E_CPU0_PE2_SS_RXN<0>

SKX_EXT_B_BGA1  I84  U5D1   [SKX_EXT_B_BGA1-IC,TBD]
  DP3  P3E_CPU0_PE1_SS_TXP<7>  PE1_TX_DP<7>  @BASEBOARD_FAB2_LIB.BASEBOARD_FAB2(SCH_1):P3E_CPU0_PE1_SS_TXP<7>
  DL2  P3E_CPU0_PE1_SS_TXP<6>  PE1_TX_DP<6>  @BASEBOARD_FAB2_LIB.BASEBOARD_FAB2(SCH_1):P3E_CPU0_PE1_SS_TXP<6>
  DH3  P3E_CPU0_PE1_SS_TXP<5>  PE1_TX_DP<5>  @BASEBOARD_FAB2_LIB.BASEBOARD_FAB2(SCH_1):P3E_CPU0_PE1_SS_TXP<5>
  DF3  P3E_CPU0_PE1_SS_TXP<4>  PE1_TX_DP<4>  @BASEBOARD_FAB2_LIB.BASEBOARD_FAB2(SCH_1):P3E_CPU0_PE1_SS_TXP<4>
  DC4  P3E_CPU0_PE1_SS_TXP<3>  PE1_TX_DP<3>  @BASEBOARD_FAB2_LIB.BASEBOARD_FAB2(SCH_1):P3E_CPU0_PE1_SS_TXP<3>
  DD3  P3E_CPU0_PE1_SS_TXP<2>  PE1_TX_DP<2>  @BASEBOARD_FAB2_LIB.BASEBOARD_FAB2(SCH_1):P3E_CPU0_PE1_SS_TXP<2>
  DB1  P3E_CPU0_PE1_SS_TXP<1>  PE1_TX_DP<1>  @BASEBOARD_FAB2_LIB.BASEBOARD_FAB2(SCH_1):P3E_CPU0_PE1_SS_TXP<1>
  CW2  P3E_CPU0_PE1_SS_TXP<0>  PE1_TX_DP<0>  @BASEBOARD_FAB2_LIB.BASEBOARD_FAB2(SCH_1):P3E_CPU0_PE1_SS_TXP<0>
  DN4  P3E_CPU0_PE1_SS_TXN<7>  PE1_TX_DN<7>  @BASEBOARD_FAB2_LIB.BASEBOARD_FAB2(SCH_1):P3E_CPU0_PE1_SS_TXN<7>
  DM3  P3E_CPU0_PE1_SS_TXN<6>  PE1_TX_DN<6>  @BASEBOARD_FAB2_LIB.BASEBOARD_FAB2(SCH_1):P3E_CPU0_PE1_SS_TXN<6>
  DK3  P3E_CPU0_PE1_SS_TXN<5>  PE1_TX_DN<5>  @BASEBOARD_FAB2_LIB.BASEBOARD_FAB2(SCH_1):P3E_CPU0_PE1_SS_TXN<5>
  DG4  P3E_CPU0_PE1_SS_TXN<4>  PE1_TX_DN<4>  @BASEBOARD_FAB2_LIB.BASEBOARD_FAB2(SCH_1):P3E_CPU0_PE1_SS_TXN<4>
  DE4  P3E_CPU0_PE1_SS_TXN<3>  PE1_TX_DN<3>  @BASEBOARD_FAB2_LIB.BASEBOARD_FAB2(SCH_1):P3E_CPU0_PE1_SS_TXN<3>
  DE2  P3E_CPU0_PE1_SS_TXN<2>  PE1_TX_DN<2>  @BASEBOARD_FAB2_LIB.BASEBOARD_FAB2(SCH_1):P3E_CPU0_PE1_SS_TXN<2>
  DC2  P3E_CPU0_PE1_SS_TXN<1>  PE1_TX_DN<1>  @BASEBOARD_FAB2_LIB.BASEBOARD_FAB2(SCH_1):P3E_CPU0_PE1_SS_TXN<1>
  DA2  P3E_CPU0_PE1_SS_TXN<0>  PE1_TX_DN<0>  @BASEBOARD_FAB2_LIB.BASEBOARD_FAB2(SCH_1):P3E_CPU0_PE1_SS_TXN<0>
  DL10  P3E_CPU0_PE1_SS_RXP<7>  PE1_RX_DP<7>  @BASEBOARD_FAB2_LIB.BASEBOARD_FAB2(SCH_1):P3E_CPU0_PE1_SS_RXP<7>
  DJ8  P3E_CPU0_PE1_SS_RXP<6>  PE1_RX_DP<6>  @BASEBOARD_FAB2_LIB.BASEBOARD_FAB2(SCH_1):P3E_CPU0_PE1_SS_RXP<6>
  DF9  P3E_CPU0_PE1_SS_RXP<5>  PE1_RX_DP<5>  @BASEBOARD_FAB2_LIB.BASEBOARD_FAB2(SCH_1):P3E_CPU0_PE1_SS_RXP<5>
  DD9  P3E_CPU0_PE1_SS_RXP<4>  PE1_RX_DP<4>  @BASEBOARD_FAB2_LIB.BASEBOARD_FAB2(SCH_1):P3E_CPU0_PE1_SS_RXP<4>
  DA10  P3E_CPU0_PE1_SS_RXP<3>  PE1_RX_DP<3>  @BASEBOARD_FAB2_LIB.BASEBOARD_FAB2(SCH_1):P3E_CPU0_PE1_SS_RXP<3>
  DB9  P3E_CPU0_PE1_SS_RXP<2>  PE1_RX_DP<2>  @BASEBOARD_FAB2_LIB.BASEBOARD_FAB2(SCH_1):P3E_CPU0_PE1_SS_RXP<2>
  CY7  P3E_CPU0_PE1_SS_RXP<1>  PE1_RX_DP<1>  @BASEBOARD_FAB2_LIB.BASEBOARD_FAB2(SCH_1):P3E_CPU0_PE1_SS_RXP<1>
  CU8  P3E_CPU0_PE1_SS_RXP<0>  PE1_RX_DP<0>  @BASEBOARD_FAB2_LIB.BASEBOARD_FAB2(SCH_1):P3E_CPU0_PE1_SS_RXP<0>
  DM9  P3E_CPU0_PE1_SS_RXN<7>  PE1_RX_DN<7>  @BASEBOARD_FAB2_LIB.BASEBOARD_FAB2(SCH_1):P3E_CPU0_PE1_SS_RXN<7>
  DK9  P3E_CPU0_PE1_SS_RXN<6>  PE1_RX_DN<6>  @BASEBOARD_FAB2_LIB.BASEBOARD_FAB2(SCH_1):P3E_CPU0_PE1_SS_RXN<6>
  DH9  P3E_CPU0_PE1_SS_RXN<5>  PE1_RX_DN<5>  @BASEBOARD_FAB2_LIB.BASEBOARD_FAB2(SCH_1):P3E_CPU0_PE1_SS_RXN<5>
  DE10  P3E_CPU0_PE1_SS_RXN<4>  PE1_RX_DN<4>  @BASEBOARD_FAB2_LIB.BASEBOARD_FAB2(SCH_1):P3E_CPU0_PE1_SS_RXN<4>
  DC10  P3E_CPU0_PE1_SS_RXN<3>  PE1_RX_DN<3>  @BASEBOARD_FAB2_LIB.BASEBOARD_FAB2(SCH_1):P3E_CPU0_PE1_SS_RXN<3>
  DC8  P3E_CPU0_PE1_SS_RXN<2>  PE1_RX_DN<2>  @BASEBOARD_FAB2_LIB.BASEBOARD_FAB2(SCH_1):P3E_CPU0_PE1_SS_RXN<2>
  DA8  P3E_CPU0_PE1_SS_RXN<1>  PE1_RX_DN<1>  @BASEBOARD_FAB2_LIB.BASEBOARD_FAB2(SCH_1):P3E_CPU0_PE1_SS_RXN<1>
  CW8  P3E_CPU0_PE1_SS_RXN<0>  PE1_RX_DN<0>  @BASEBOARD_FAB2_LIB.BASEBOARD_FAB2(SCH_1):P3E_CPU0_PE1_SS_RXN<0>
  DU2  P3E_CPU0_PE1_PCH_TXP<9>  PE1_TX_DP<9>  @BASEBOARD_FAB2_LIB.BASEBOARD_FAB2(SCH_1):P3E_CPU0_PE1_PCH_TXP<9>
  DR4  P3E_CPU0_PE1_PCH_TXP<8>  PE1_TX_DP<8>  @BASEBOARD_FAB2_LIB.BASEBOARD_FAB2(SCH_1):P3E_CPU0_PE1_PCH_TXP<8>
  EC8  P3E_CPU0_PE1_PCH_TXP<15>  PE1_TX_DP<15>  @BASEBOARD_FAB2_LIB.BASEBOARD_FAB2(SCH_1):P3E_CPU0_PE1_PCH_TXP<15>
  EB7  P3E_CPU0_PE1_PCH_TXP<14>  PE1_TX_DP<14>  @BASEBOARD_FAB2_LIB.BASEBOARD_FAB2(SCH_1):P3E_CPU0_PE1_PCH_TXP<14>
  DW6  P3E_CPU0_PE1_PCH_TXP<13>  PE1_TX_DP<13>  @BASEBOARD_FAB2_LIB.BASEBOARD_FAB2(SCH_1):P3E_CPU0_PE1_PCH_TXP<13>
  DT7  P3E_CPU0_PE1_PCH_TXP<12>  PE1_TX_DP<12>  @BASEBOARD_FAB2_LIB.BASEBOARD_FAB2(SCH_1):P3E_CPU0_PE1_PCH_TXP<12>
  DV5  P3E_CPU0_PE1_PCH_TXP<11>  PE1_TX_DP<11>  @BASEBOARD_FAB2_LIB.BASEBOARD_FAB2(SCH_1):P3E_CPU0_PE1_PCH_TXP<11>
  DU4  P3E_CPU0_PE1_PCH_TXP<10>  PE1_TX_DP<10>  @BASEBOARD_FAB2_LIB.BASEBOARD_FAB2(SCH_1):P3E_CPU0_PE1_PCH_TXP<10>
  DV3  P3E_CPU0_PE1_PCH_TXN<9>  PE1_TX_DN<9>  @BASEBOARD_FAB2_LIB.BASEBOARD_FAB2(SCH_1):P3E_CPU0_PE1_PCH_TXN<9>
  DT5  P3E_CPU0_PE1_PCH_TXN<8>  PE1_TX_DN<8>  @BASEBOARD_FAB2_LIB.BASEBOARD_FAB2(SCH_1):P3E_CPU0_PE1_PCH_TXN<8>
  ED9  P3E_CPU0_PE1_PCH_TXN<15>  PE1_TX_DN<15>  @BASEBOARD_FAB2_LIB.BASEBOARD_FAB2(SCH_1):P3E_CPU0_PE1_PCH_TXN<15>
  EA8  P3E_CPU0_PE1_PCH_TXN<14>  PE1_TX_DN<14>  @BASEBOARD_FAB2_LIB.BASEBOARD_FAB2(SCH_1):P3E_CPU0_PE1_PCH_TXN<14>
  DY7  P3E_CPU0_PE1_PCH_TXN<13>  PE1_TX_DN<13>  @BASEBOARD_FAB2_LIB.BASEBOARD_FAB2(SCH_1):P3E_CPU0_PE1_PCH_TXN<13>
  DV7  P3E_CPU0_PE1_PCH_TXN<12>  PE1_TX_DN<12>  @BASEBOARD_FAB2_LIB.BASEBOARD_FAB2(SCH_1):P3E_CPU0_PE1_PCH_TXN<12>
  DU6  P3E_CPU0_PE1_PCH_TXN<11>  PE1_TX_DN<11>  @BASEBOARD_FAB2_LIB.BASEBOARD_FAB2(SCH_1):P3E_CPU0_PE1_PCH_TXN<11>
  DW4  P3E_CPU0_PE1_PCH_TXN<10>  PE1_TX_DN<10>  @BASEBOARD_FAB2_LIB.BASEBOARD_FAB2(SCH_1):P3E_CPU0_PE1_PCH_TXN<10>
  DN10  P3E_CPU0_PE1_PCH_RXP<9>  PE1_RX_DP<9>  @BASEBOARD_FAB2_LIB.BASEBOARD_FAB2(SCH_1):P3E_CPU0_PE1_PCH_RXP<9>
  DK11  P3E_CPU0_PE1_PCH_RXP<8>  PE1_RX_DP<8>  @BASEBOARD_FAB2_LIB.BASEBOARD_FAB2(SCH_1):P3E_CPU0_PE1_PCH_RXP<8>
  DT15  P3E_CPU0_PE1_PCH_RXP<15>  PE1_RX_DP<15>  @BASEBOARD_FAB2_LIB.BASEBOARD_FAB2(SCH_1):P3E_CPU0_PE1_PCH_RXP<15>
  DV15  P3E_CPU0_PE1_PCH_RXP<14>  PE1_RX_DP<14>  @BASEBOARD_FAB2_LIB.BASEBOARD_FAB2(SCH_1):P3E_CPU0_PE1_PCH_RXP<14>
  DY13  P3E_CPU0_PE1_PCH_RXP<13>  PE1_RX_DP<13>  @BASEBOARD_FAB2_LIB.BASEBOARD_FAB2(SCH_1):P3E_CPU0_PE1_PCH_RXP<13>
  DU12  P3E_CPU0_PE1_PCH_RXP<12>  PE1_RX_DP<12>  @BASEBOARD_FAB2_LIB.BASEBOARD_FAB2(SCH_1):P3E_CPU0_PE1_PCH_RXP<12>
  DP13  P3E_CPU0_PE1_PCH_RXP<11>  PE1_RX_DP<11>  @BASEBOARD_FAB2_LIB.BASEBOARD_FAB2(SCH_1):P3E_CPU0_PE1_PCH_RXP<11>
  DR12  P3E_CPU0_PE1_PCH_RXP<10>  PE1_RX_DP<10>  @BASEBOARD_FAB2_LIB.BASEBOARD_FAB2(SCH_1):P3E_CPU0_PE1_PCH_RXP<10>
  DP11  P3E_CPU0_PE1_PCH_RXN<9>  PE1_RX_DN<9>  @BASEBOARD_FAB2_LIB.BASEBOARD_FAB2(SCH_1):P3E_CPU0_PE1_PCH_RXN<9>
  DM11  P3E_CPU0_PE1_PCH_RXN<8>  PE1_RX_DN<8>  @BASEBOARD_FAB2_LIB.BASEBOARD_FAB2(SCH_1):P3E_CPU0_PE1_PCH_RXN<8>
  DU16  P3E_CPU0_PE1_PCH_RXN<15>  PE1_RX_DN<15>  @BASEBOARD_FAB2_LIB.BASEBOARD_FAB2(SCH_1):P3E_CPU0_PE1_PCH_RXN<15>
  DY15  P3E_CPU0_PE1_PCH_RXN<14>  PE1_RX_DN<14>  @BASEBOARD_FAB2_LIB.BASEBOARD_FAB2(SCH_1):P3E_CPU0_PE1_PCH_RXN<14>
  DW14  P3E_CPU0_PE1_PCH_RXN<13>  PE1_RX_DN<13>  @BASEBOARD_FAB2_LIB.BASEBOARD_FAB2(SCH_1):P3E_CPU0_PE1_PCH_RXN<13>
  DV13  P3E_CPU0_PE1_PCH_RXN<12>  PE1_RX_DN<12>  @BASEBOARD_FAB2_LIB.BASEBOARD_FAB2(SCH_1):P3E_CPU0_PE1_PCH_RXN<12>
  DT13  P3E_CPU0_PE1_PCH_RXN<11>  PE1_RX_DN<11>  @BASEBOARD_FAB2_LIB.BASEBOARD_FAB2(SCH_1):P3E_CPU0_PE1_PCH_RXN<11>
  DT11  P3E_CPU0_PE1_PCH_RXN<10>  PE1_RX_DN<10>  @BASEBOARD_FAB2_LIB.BASEBOARD_FAB2(SCH_1):P3E_CPU0_PE1_PCH_RXN<10>

SKX_EXT_B_BGA1  I61  U5D1   [SKX_EXT_B_BGA1-IC,TBD]
  AR62  TP_CPU0_RSVD_190  RSVD<190>  @BASEBOARD_FAB2_LIB.BASEBOARD_FAB2(SCH_1):TP_CPU0_RSVD_190
  AT13  TP_CPU0_RSVD_189  RSVD<189>  @BASEBOARD_FAB2_LIB.BASEBOARD_FAB2(SCH_1):TP_CPU0_RSVD_189
  AV77  TP_CPU0_RSVD_186  RSVD<186>  @BASEBOARD_FAB2_LIB.BASEBOARD_FAB2(SCH_1):TP_CPU0_RSVD_186
  AW64  TP_CPU0_RSVD_184  RSVD<184>  @BASEBOARD_FAB2_LIB.BASEBOARD_FAB2(SCH_1):TP_CPU0_RSVD_184
  AW76  TP_CPU0_RSVD_183  RSVD<183>  @BASEBOARD_FAB2_LIB.BASEBOARD_FAB2(SCH_1):TP_CPU0_RSVD_183
  AY65  TP_CPU0_RSVD_182  RSVD<182>  @BASEBOARD_FAB2_LIB.BASEBOARD_FAB2(SCH_1):TP_CPU0_RSVD_182
  AY67  TP_CPU0_RSVD_181  RSVD<181>  @BASEBOARD_FAB2_LIB.BASEBOARD_FAB2(SCH_1):TP_CPU0_RSVD_181
  AY75  TP_CPU0_RSVD_180  RSVD<180>  @BASEBOARD_FAB2_LIB.BASEBOARD_FAB2(SCH_1):TP_CPU0_RSVD_180
  AY77  TP_CPU0_RSVD_179  RSVD<179>  @BASEBOARD_FAB2_LIB.BASEBOARD_FAB2(SCH_1):TP_CPU0_RSVD_179
  BA14  TP_CPU0_RSVD_178  RSVD<178>  @BASEBOARD_FAB2_LIB.BASEBOARD_FAB2(SCH_1):TP_CPU0_RSVD_178
  BA16  TP_CPU0_RSVD_177  RSVD<177>  @BASEBOARD_FAB2_LIB.BASEBOARD_FAB2(SCH_1):TP_CPU0_RSVD_177
  BA18  TP_CPU0_RSVD_176  RSVD<176>  @BASEBOARD_FAB2_LIB.BASEBOARD_FAB2(SCH_1):TP_CPU0_RSVD_176
  BA22  TP_CPU0_RSVD_175  RSVD<175>  @BASEBOARD_FAB2_LIB.BASEBOARD_FAB2(SCH_1):TP_CPU0_RSVD_175
  BA64  TP_CPU0_RSVD_174  RSVD<174>  @BASEBOARD_FAB2_LIB.BASEBOARD_FAB2(SCH_1):TP_CPU0_RSVD_174
  BA66  TP_CPU0_RSVD_173  RSVD<173>  @BASEBOARD_FAB2_LIB.BASEBOARD_FAB2(SCH_1):TP_CPU0_RSVD_173
  BA76  TP_CPU0_RSVD_172  RSVD<172>  @BASEBOARD_FAB2_LIB.BASEBOARD_FAB2(SCH_1):TP_CPU0_RSVD_172
  BH23  SMB_HFI1_CPU0_LVC2_SDA  CD_HFI1_I2CDAT  @BASEBOARD_FAB2_LIB.BASEBOARD_FAB2(SCH_1):SMB_HFI1_CPU0_LVC2_SDA
  BJ22  SMB_HFI1_CPU0_LVC2_SCL  CD_HFI1_I2CCLK  @BASEBOARD_FAB2_LIB.BASEBOARD_FAB2(SCH_1):SMB_HFI1_CPU0_LVC2_SCL
  BP23  SMB_HFI0_CPU0_LVC2_SDA  CD_HFI0_I2CDAT  @BASEBOARD_FAB2_LIB.BASEBOARD_FAB2(SCH_1):SMB_HFI0_CPU0_LVC2_SDA
  BN22  SMB_HFI0_CPU0_LVC2_SCL  CD_HFI0_I2CCLK  @BASEBOARD_FAB2_LIB.BASEBOARD_FAB2(SCH_1):SMB_HFI0_CPU0_LVC2_SCL
  BK23  RST_HFI1_CPU0_LVT2_N  CD_HFI1_RESET_N  @BASEBOARD_FAB2_LIB.BASEBOARD_FAB2(SCH_1):RST_HFI1_CPU0_LVT2_N
  BN24  RST_HFI0_CPU0_LVT2_N  CD_HFI0_RESET_N  @BASEBOARD_FAB2_LIB.BASEBOARD_FAB2(SCH_1):RST_HFI0_CPU0_LVT2_N
  CF25  RST_CD_CPU0_POR_N  CD_POR_N  @BASEBOARD_FAB2_LIB.BASEBOARD_FAB2(SCH_1):RST_CD_CPU0_POR_N
  AR20  PVCCMCP_CPU0   RSVD<193>  @BASEBOARD_FAB2_LIB.BASEBOARD_FAB2(SCH_1):PVCCMCP_CPU0
  AR22  PVCCMCP_CPU0   RSVD<192>  @BASEBOARD_FAB2_LIB.BASEBOARD_FAB2(SCH_1):PVCCMCP_CPU0
  AR26  PVCCMCP_CPU0   RSVD<191>  @BASEBOARD_FAB2_LIB.BASEBOARD_FAB2(SCH_1):PVCCMCP_CPU0
  AT23  PVCCMCP_CPU0   RSVD<188>  @BASEBOARD_FAB2_LIB.BASEBOARD_FAB2(SCH_1):PVCCMCP_CPU0
  AT25  PVCCMCP_CPU0   RSVD<187>  @BASEBOARD_FAB2_LIB.BASEBOARD_FAB2(SCH_1):PVCCMCP_CPU0
  BM23  LED_HFI1_CPU0_N  CD_HFI1_LED_N  @BASEBOARD_FAB2_LIB.BASEBOARD_FAB2(SCH_1):LED_HFI1_CPU0_N
  BK21  LED_HFI0_CPU0_N  CD_HFI0_LED_N  @BASEBOARD_FAB2_LIB.BASEBOARD_FAB2(SCH_1):LED_HFI0_CPU0_N
  CD23  JTAG_MCP_TRST_N  CD_TRST_N  @BASEBOARD_FAB2_LIB.BASEBOARD_FAB2(SCH_1):JTAG_MCP_TRST_N
  CE24  JTAG_MCP_TMS   CD_TMS  @BASEBOARD_FAB2_LIB.BASEBOARD_FAB2(SCH_1):JTAG_MCP_TMS
  CB23  JTAG_MCP_TCK   CD_TCLK  @BASEBOARD_FAB2_LIB.BASEBOARD_FAB2(SCH_1):JTAG_MCP_TCK
  CC22  JTAG_MCP_CPU0_TDO  CD_TDO  @BASEBOARD_FAB2_LIB.BASEBOARD_FAB2(SCH_1):JTAG_MCP_CPU0_TDO
  BY21  JTAG_MCP_CPU0_TDI  CD_TDI  @BASEBOARD_FAB2_LIB.BASEBOARD_FAB2(SCH_1):JTAG_MCP_CPU0_TDI
  BM21  IRQ_HFI1_CPU0_LVT2_N  CD_HFI1_INT_N  @BASEBOARD_FAB2_LIB.BASEBOARD_FAB2(SCH_1):IRQ_HFI1_CPU0_LVT2_N
  BP19  IRQ_HFI0_CPU0_LVT2_N  CD_HFI0_INT_N  @BASEBOARD_FAB2_LIB.BASEBOARD_FAB2(SCH_1):IRQ_HFI0_CPU0_LVT2_N
  BT19  FM_MODPRST_HFI1_CPU0_LVT2_N  CD_HFI1_MODPRST_N  @BASEBOARD_FAB2_LIB.BASEBOARD_FAB2(SCH_1):FM_MODPRST_HFI1_CPU0_LVT2_N
  BR20  FM_MODPRST_HFI0_CPU0_LVT2_N  CD_HFI0_MODPRST_N  @BASEBOARD_FAB2_LIB.BASEBOARD_FAB2(SCH_1):FM_MODPRST_HFI0_CPU0_LVT2_N
  CR4  DMI_CPU0_PCH_TX_DP<3>  DMI_TX_DP<3>  @BASEBOARD_FAB2_LIB.BASEBOARD_FAB2(SCH_1):DMI_CPU0_PCH_TX_DP<3>
  CM3  DMI_CPU0_PCH_TX_DP<2>  DMI_TX_DP<2>  @BASEBOARD_FAB2_LIB.BASEBOARD_FAB2(SCH_1):DMI_CPU0_PCH_TX_DP<2>
  CL4  DMI_CPU0_PCH_TX_DP<1>  DMI_TX_DP<1>  @BASEBOARD_FAB2_LIB.BASEBOARD_FAB2(SCH_1):DMI_CPU0_PCH_TX_DP<1>
  CH5  DMI_CPU0_PCH_TX_DP<0>  DMI_TX_DP<0>  @BASEBOARD_FAB2_LIB.BASEBOARD_FAB2(SCH_1):DMI_CPU0_PCH_TX_DP<0>
  CP5  DMI_CPU0_PCH_TX_DN<3>  DMI_TX_DN<3>  @BASEBOARD_FAB2_LIB.BASEBOARD_FAB2(SCH_1):DMI_CPU0_PCH_TX_DN<3>
  CN4  DMI_CPU0_PCH_TX_DN<2>  DMI_TX_DN<2>  @BASEBOARD_FAB2_LIB.BASEBOARD_FAB2(SCH_1):DMI_CPU0_PCH_TX_DN<2>
  CJ4  DMI_CPU0_PCH_TX_DN<1>  DMI_TX_DN<1>  @BASEBOARD_FAB2_LIB.BASEBOARD_FAB2(SCH_1):DMI_CPU0_PCH_TX_DN<1>
  CG4  DMI_CPU0_PCH_TX_DN<0>  DMI_TX_DN<0>  @BASEBOARD_FAB2_LIB.BASEBOARD_FAB2(SCH_1):DMI_CPU0_PCH_TX_DN<0>
  CV11  DMI_CPU0_PCH_RX_C_DP<3>  DMI_RX_DP<3>  @BASEBOARD_FAB2_LIB.BASEBOARD_FAB2(SCH_1):DMI_CPU0_PCH_RX_C_DP<3>
  CP11  DMI_CPU0_PCH_RX_C_DP<2>  DMI_RX_DP<2>  @BASEBOARD_FAB2_LIB.BASEBOARD_FAB2(SCH_1):DMI_CPU0_PCH_RX_C_DP<2>
  CN10  DMI_CPU0_PCH_RX_C_DP<1>  DMI_RX_DP<1>  @BASEBOARD_FAB2_LIB.BASEBOARD_FAB2(SCH_1):DMI_CPU0_PCH_RX_C_DP<1>
  CL10  DMI_CPU0_PCH_RX_C_DP<0>  DMI_RX_DP<0>  @BASEBOARD_FAB2_LIB.BASEBOARD_FAB2(SCH_1):DMI_CPU0_PCH_RX_C_DP<0>
  CT11  DMI_CPU0_PCH_RX_C_DN<3>  DMI_RX_DN<3>  @BASEBOARD_FAB2_LIB.BASEBOARD_FAB2(SCH_1):DMI_CPU0_PCH_RX_C_DN<3>
  CR12  DMI_CPU0_PCH_RX_C_DN<2>  DMI_RX_DN<2>  @BASEBOARD_FAB2_LIB.BASEBOARD_FAB2(SCH_1):DMI_CPU0_PCH_RX_C_DN<2>
  CM11  DMI_CPU0_PCH_RX_C_DN<1>  DMI_RX_DN<1>  @BASEBOARD_FAB2_LIB.BASEBOARD_FAB2(SCH_1):DMI_CPU0_PCH_RX_C_DN<1>
  CK9  DMI_CPU0_PCH_RX_C_DN<0>  DMI_RX_DN<0>  @BASEBOARD_FAB2_LIB.BASEBOARD_FAB2(SCH_1):DMI_CPU0_PCH_RX_C_DN<0>
  BG16  CLK_156M_OSC_CPU0_HFI_DP  CD_HFI_REFCLK_DP  @BASEBOARD_FAB2_LIB.BASEBOARD_FAB2(SCH_1):CLK_156M_OSC_CPU0_HFI_DP
  BE16  CLK_156M_OSC_CPU0_HFI_DN  CD_HFI_REFCLK_DN  @BASEBOARD_FAB2_LIB.BASEBOARD_FAB2(SCH_1):CLK_156M_OSC_CPU0_HFI_DN
  BW24  CLK_100M_CPU0_PE_REFCLK_DP  CD_PE_REFCLK_DP  @BASEBOARD_FAB2_LIB.BASEBOARD_FAB2(SCH_1):CLK_100M_CPU0_PE_REFCLK_DP
  BU24  CLK_100M_CPU0_PE_REFCLK_DN  CD_PE_REFCLK_DN  @BASEBOARD_FAB2_LIB.BASEBOARD_FAB2(SCH_1):CLK_100M_CPU0_PE_REFCLK_DN

SKX_EXT_B_BGA1  I172  U5D1   [SKX_EXT_B_BGA1-IC,TBD]
  DK53  M_F_PAR        DDR5_PAR  @BASEBOARD_FAB2_LIB.BASEBOARD_FAB2(SCH_1):M_F_PAR
  DF47  M_F_ODT<3>     DDR5_ODT<3>  @BASEBOARD_FAB2_LIB.BASEBOARD_FAB2(SCH_1):M_F_ODT<3>
  DK49  M_F_ODT<2>     DDR5_ODT<2>  @BASEBOARD_FAB2_LIB.BASEBOARD_FAB2(SCH_1):M_F_ODT<2>
  DG48  M_F_ODT<1>     DDR5_ODT<1>  @BASEBOARD_FAB2_LIB.BASEBOARD_FAB2(SCH_1):M_F_ODT<1>
  DG50  M_F_ODT<0>     DDR5_ODT<0>  @BASEBOARD_FAB2_LIB.BASEBOARD_FAB2(SCH_1):M_F_ODT<0>
  DA58  M_F_MA<9>      DDR5_MA<9>  @BASEBOARD_FAB2_LIB.BASEBOARD_FAB2(SCH_1):M_F_MA<9>
  DD59  M_F_MA<8>      DDR5_MA<8>  @BASEBOARD_FAB2_LIB.BASEBOARD_FAB2(SCH_1):M_F_MA<8>
  DC60  M_F_MA<7>      DDR5_MA<7>  @BASEBOARD_FAB2_LIB.BASEBOARD_FAB2(SCH_1):M_F_MA<7>
  DK59  M_F_MA<6>      DDR5_MA<6>  @BASEBOARD_FAB2_LIB.BASEBOARD_FAB2(SCH_1):M_F_MA<6>
  DF59  M_F_MA<5>      DDR5_MA<5>  @BASEBOARD_FAB2_LIB.BASEBOARD_FAB2(SCH_1):M_F_MA<5>
  DJ58  M_F_MA<4>      DDR5_MA<4>  @BASEBOARD_FAB2_LIB.BASEBOARD_FAB2(SCH_1):M_F_MA<4>
  DG58  M_F_MA<3>      DDR5_MA<3>  @BASEBOARD_FAB2_LIB.BASEBOARD_FAB2(SCH_1):M_F_MA<3>
  DD57  M_F_MA<2>      DDR5_MA<2>  @BASEBOARD_FAB2_LIB.BASEBOARD_FAB2(SCH_1):M_F_MA<2>
  DC58  M_F_MA<1>      DDR5_MA<1>  @BASEBOARD_FAB2_LIB.BASEBOARD_FAB2(SCH_1):M_F_MA<1>
  DE46  M_F_MA<17>     DDR5_MA<17>  @BASEBOARD_FAB2_LIB.BASEBOARD_FAB2(SCH_1):M_F_MA<17>
  DG52  M_F_MA<16>     DDR5_MA<16>  @BASEBOARD_FAB2_LIB.BASEBOARD_FAB2(SCH_1):M_F_MA<16>
  DC54  M_F_MA<15>     DDR5_MA<15>  @BASEBOARD_FAB2_LIB.BASEBOARD_FAB2(SCH_1):M_F_MA<15>
  DJ50  M_F_MA<14>     DDR5_MA<14>  @BASEBOARD_FAB2_LIB.BASEBOARD_FAB2(SCH_1):M_F_MA<14>
  DD53  M_F_MA<13>     DDR5_MA<13>  @BASEBOARD_FAB2_LIB.BASEBOARD_FAB2(SCH_1):M_F_MA<13>
  DG60  M_F_MA<12>     DDR5_MA<12>  @BASEBOARD_FAB2_LIB.BASEBOARD_FAB2(SCH_1):M_F_MA<12>
  DA60  M_F_MA<11>     DDR5_MA<11>  @BASEBOARD_FAB2_LIB.BASEBOARD_FAB2(SCH_1):M_F_MA<11>
  DD55  M_F_MA<10>     DDR5_MA<10>  @BASEBOARD_FAB2_LIB.BASEBOARD_FAB2(SCH_1):M_F_MA<10>
  DF53  M_F_MA<0>      DDR5_MA<0>  @BASEBOARD_FAB2_LIB.BASEBOARD_FAB2(SCH_1):M_F_MA<0>
  CM69  M_F_ECC<7>     DDR5_ECC<7>  @BASEBOARD_FAB2_LIB.BASEBOARD_FAB2(SCH_1):M_F_ECC<7>
  CH69  M_F_ECC<6>     DDR5_ECC<6>  @BASEBOARD_FAB2_LIB.BASEBOARD_FAB2(SCH_1):M_F_ECC<6>
  CL72  M_F_ECC<5>     DDR5_ECC<5>  @BASEBOARD_FAB2_LIB.BASEBOARD_FAB2(SCH_1):M_F_ECC<5>
  CJ72  M_F_ECC<4>     DDR5_ECC<4>  @BASEBOARD_FAB2_LIB.BASEBOARD_FAB2(SCH_1):M_F_ECC<4>
  CL68  M_F_ECC<3>     DDR5_ECC<3>  @BASEBOARD_FAB2_LIB.BASEBOARD_FAB2(SCH_1):M_F_ECC<3>
  CJ68  M_F_ECC<2>     DDR5_ECC<2>  @BASEBOARD_FAB2_LIB.BASEBOARD_FAB2(SCH_1):M_F_ECC<2>
  CM71  M_F_ECC<1>     DDR5_ECC<1>  @BASEBOARD_FAB2_LIB.BASEBOARD_FAB2(SCH_1):M_F_ECC<1>
  CH71  M_F_ECC<0>     DDR5_ECC<0>  @BASEBOARD_FAB2_LIB.BASEBOARD_FAB2(SCH_1):M_F_ECC<0>
  CU74  M_F_DQS_DP<9>  DDR5_DQS_DP<9>  @BASEBOARD_FAB2_LIB.BASEBOARD_FAB2(SCH_1):M_F_DQS_DP<9>
  CL70  M_F_DQS_DP<8>  DDR5_DQS_DP<8>  @BASEBOARD_FAB2_LIB.BASEBOARD_FAB2(SCH_1):M_F_DQS_DP<8>
  DB29  M_F_DQS_DP<7>  DDR5_DQS_DP<7>  @BASEBOARD_FAB2_LIB.BASEBOARD_FAB2(SCH_1):M_F_DQS_DP<7>
  DB35  M_F_DQS_DP<6>  DDR5_DQS_DP<6>  @BASEBOARD_FAB2_LIB.BASEBOARD_FAB2(SCH_1):M_F_DQS_DP<6>
  DJ32  M_F_DQS_DP<5>  DDR5_DQS_DP<5>  @BASEBOARD_FAB2_LIB.BASEBOARD_FAB2(SCH_1):M_F_DQS_DP<5>
  DJ40  M_F_DQS_DP<4>  DDR5_DQS_DP<4>  @BASEBOARD_FAB2_LIB.BASEBOARD_FAB2(SCH_1):M_F_DQS_DP<4>
  CT65  M_F_DQS_DP<3>  DDR5_DQS_DP<3>  @BASEBOARD_FAB2_LIB.BASEBOARD_FAB2(SCH_1):M_F_DQS_DP<3>
  DK71  M_F_DQS_DP<2>  DDR5_DQS_DP<2>  @BASEBOARD_FAB2_LIB.BASEBOARD_FAB2(SCH_1):M_F_DQS_DP<2>
  DE76  M_F_DQS_DP<1>  DDR5_DQS_DP<1>  @BASEBOARD_FAB2_LIB.BASEBOARD_FAB2(SCH_1):M_F_DQS_DP<1>
  CG70  M_F_DQS_DP<17>  DDR5_DQS_DP<17>  @BASEBOARD_FAB2_LIB.BASEBOARD_FAB2(SCH_1):M_F_DQS_DP<17>
  CV29  M_F_DQS_DP<16>  DDR5_DQS_DP<16>  @BASEBOARD_FAB2_LIB.BASEBOARD_FAB2(SCH_1):M_F_DQS_DP<16>
  CV35  M_F_DQS_DP<15>  DDR5_DQS_DP<15>  @BASEBOARD_FAB2_LIB.BASEBOARD_FAB2(SCH_1):M_F_DQS_DP<15>
  DE32  M_F_DQS_DP<14>  DDR5_DQS_DP<14>  @BASEBOARD_FAB2_LIB.BASEBOARD_FAB2(SCH_1):M_F_DQS_DP<14>
  DC40  M_F_DQS_DP<13>  DDR5_DQS_DP<13>  @BASEBOARD_FAB2_LIB.BASEBOARD_FAB2(SCH_1):M_F_DQS_DP<13>
  CM65  M_F_DQS_DP<12>  DDR5_DQS_DP<12>  @BASEBOARD_FAB2_LIB.BASEBOARD_FAB2(SCH_1):M_F_DQS_DP<12>
  DH69  M_F_DQS_DP<11>  DDR5_DQS_DP<11>  @BASEBOARD_FAB2_LIB.BASEBOARD_FAB2(SCH_1):M_F_DQS_DP<11>
  DG74  M_F_DQS_DP<10>  DDR5_DQS_DP<10>  @BASEBOARD_FAB2_LIB.BASEBOARD_FAB2(SCH_1):M_F_DQS_DP<10>
  CR76  M_F_DQS_DP<0>  DDR5_DQS_DP<0>  @BASEBOARD_FAB2_LIB.BASEBOARD_FAB2(SCH_1):M_F_DQS_DP<0>
  CT75  M_F_DQS_DN<9>  DDR5_DQS_DN<9>  @BASEBOARD_FAB2_LIB.BASEBOARD_FAB2(SCH_1):M_F_DQS_DN<9>
  CN70  M_F_DQS_DN<8>  DDR5_DQS_DN<8>  @BASEBOARD_FAB2_LIB.BASEBOARD_FAB2(SCH_1):M_F_DQS_DN<8>
  DD29  M_F_DQS_DN<7>  DDR5_DQS_DN<7>  @BASEBOARD_FAB2_LIB.BASEBOARD_FAB2(SCH_1):M_F_DQS_DN<7>
  DD35  M_F_DQS_DN<6>  DDR5_DQS_DN<6>  @BASEBOARD_FAB2_LIB.BASEBOARD_FAB2(SCH_1):M_F_DQS_DN<6>
  DL32  M_F_DQS_DN<5>  DDR5_DQS_DN<5>  @BASEBOARD_FAB2_LIB.BASEBOARD_FAB2(SCH_1):M_F_DQS_DN<5>
  DG40  M_F_DQS_DN<4>  DDR5_DQS_DN<4>  @BASEBOARD_FAB2_LIB.BASEBOARD_FAB2(SCH_1):M_F_DQS_DN<4>
  CV65  M_F_DQS_DN<3>  DDR5_DQS_DN<3>  @BASEBOARD_FAB2_LIB.BASEBOARD_FAB2(SCH_1):M_F_DQS_DN<3>
  DL72  M_F_DQS_DN<2>  DDR5_DQS_DN<2>  @BASEBOARD_FAB2_LIB.BASEBOARD_FAB2(SCH_1):M_F_DQS_DN<2>
  DD77  M_F_DQS_DN<1>  DDR5_DQS_DN<1>  @BASEBOARD_FAB2_LIB.BASEBOARD_FAB2(SCH_1):M_F_DQS_DN<1>
  CJ70  M_F_DQS_DN<17>  DDR5_DQS_DN<17>  @BASEBOARD_FAB2_LIB.BASEBOARD_FAB2(SCH_1):M_F_DQS_DN<17>
  CY29  M_F_DQS_DN<16>  DDR5_DQS_DN<16>  @BASEBOARD_FAB2_LIB.BASEBOARD_FAB2(SCH_1):M_F_DQS_DN<16>
  CY35  M_F_DQS_DN<15>  DDR5_DQS_DN<15>  @BASEBOARD_FAB2_LIB.BASEBOARD_FAB2(SCH_1):M_F_DQS_DN<15>
  DG32  M_F_DQS_DN<14>  DDR5_DQS_DN<14>  @BASEBOARD_FAB2_LIB.BASEBOARD_FAB2(SCH_1):M_F_DQS_DN<14>
  DE40  M_F_DQS_DN<13>  DDR5_DQS_DN<13>  @BASEBOARD_FAB2_LIB.BASEBOARD_FAB2(SCH_1):M_F_DQS_DN<13>
  CP65  M_F_DQS_DN<12>  DDR5_DQS_DN<12>  @BASEBOARD_FAB2_LIB.BASEBOARD_FAB2(SCH_1):M_F_DQS_DN<12>
  DJ70  M_F_DQS_DN<11>  DDR5_DQS_DN<11>  @BASEBOARD_FAB2_LIB.BASEBOARD_FAB2(SCH_1):M_F_DQS_DN<11>
  DF75  M_F_DQS_DN<10>  DDR5_DQS_DN<10>  @BASEBOARD_FAB2_LIB.BASEBOARD_FAB2(SCH_1):M_F_DQS_DN<10>
  CP77  M_F_DQS_DN<0>  DDR5_DQS_DN<0>  @BASEBOARD_FAB2_LIB.BASEBOARD_FAB2(SCH_1):M_F_DQS_DN<0>
  DC76  M_F_DQ<9>      DDR5_DQ<9>  @BASEBOARD_FAB2_LIB.BASEBOARD_FAB2(SCH_1):M_F_DQ<9>
  DE74  M_F_DQ<8>      DDR5_DQ<8>  @BASEBOARD_FAB2_LIB.BASEBOARD_FAB2(SCH_1):M_F_DQ<8>
  CT77  M_F_DQ<7>      DDR5_DQ<7>  @BASEBOARD_FAB2_LIB.BASEBOARD_FAB2(SCH_1):M_F_DQ<7>
  CV75  M_F_DQ<6>      DDR5_DQ<6>  @BASEBOARD_FAB2_LIB.BASEBOARD_FAB2(SCH_1):M_F_DQ<6>
  DC28  M_F_DQ<63>     DDR5_DQ<63>  @BASEBOARD_FAB2_LIB.BASEBOARD_FAB2(SCH_1):M_F_DQ<63>
  CW28  M_F_DQ<62>     DDR5_DQ<62>  @BASEBOARD_FAB2_LIB.BASEBOARD_FAB2(SCH_1):M_F_DQ<62>
  DB31  M_F_DQ<61>     DDR5_DQ<61>  @BASEBOARD_FAB2_LIB.BASEBOARD_FAB2(SCH_1):M_F_DQ<61>
  CY31  M_F_DQ<60>     DDR5_DQ<60>  @BASEBOARD_FAB2_LIB.BASEBOARD_FAB2(SCH_1):M_F_DQ<60>
  CM75  M_F_DQ<5>      DDR5_DQ<5>  @BASEBOARD_FAB2_LIB.BASEBOARD_FAB2(SCH_1):M_F_DQ<5>
  DB27  M_F_DQ<59>     DDR5_DQ<59>  @BASEBOARD_FAB2_LIB.BASEBOARD_FAB2(SCH_1):M_F_DQ<59>
  CY27  M_F_DQ<58>     DDR5_DQ<58>  @BASEBOARD_FAB2_LIB.BASEBOARD_FAB2(SCH_1):M_F_DQ<58>
  DC30  M_F_DQ<57>     DDR5_DQ<57>  @BASEBOARD_FAB2_LIB.BASEBOARD_FAB2(SCH_1):M_F_DQ<57>
  CW30  M_F_DQ<56>     DDR5_DQ<56>  @BASEBOARD_FAB2_LIB.BASEBOARD_FAB2(SCH_1):M_F_DQ<56>
  DC34  M_F_DQ<55>     DDR5_DQ<55>  @BASEBOARD_FAB2_LIB.BASEBOARD_FAB2(SCH_1):M_F_DQ<55>
  CW34  M_F_DQ<54>     DDR5_DQ<54>  @BASEBOARD_FAB2_LIB.BASEBOARD_FAB2(SCH_1):M_F_DQ<54>
  DB37  M_F_DQ<53>     DDR5_DQ<53>  @BASEBOARD_FAB2_LIB.BASEBOARD_FAB2(SCH_1):M_F_DQ<53>
  CY37  M_F_DQ<52>     DDR5_DQ<52>  @BASEBOARD_FAB2_LIB.BASEBOARD_FAB2(SCH_1):M_F_DQ<52>
  DB33  M_F_DQ<51>     DDR5_DQ<51>  @BASEBOARD_FAB2_LIB.BASEBOARD_FAB2(SCH_1):M_F_DQ<51>
  CY33  M_F_DQ<50>     DDR5_DQ<50>  @BASEBOARD_FAB2_LIB.BASEBOARD_FAB2(SCH_1):M_F_DQ<50>
  CN74  M_F_DQ<4>      DDR5_DQ<4>  @BASEBOARD_FAB2_LIB.BASEBOARD_FAB2(SCH_1):M_F_DQ<4>
  DC36  M_F_DQ<49>     DDR5_DQ<49>  @BASEBOARD_FAB2_LIB.BASEBOARD_FAB2(SCH_1):M_F_DQ<49>
  CW36  M_F_DQ<48>     DDR5_DQ<48>  @BASEBOARD_FAB2_LIB.BASEBOARD_FAB2(SCH_1):M_F_DQ<48>
  DK31  M_F_DQ<47>     DDR5_DQ<47>  @BASEBOARD_FAB2_LIB.BASEBOARD_FAB2(SCH_1):M_F_DQ<47>
  DF31  M_F_DQ<46>     DDR5_DQ<46>  @BASEBOARD_FAB2_LIB.BASEBOARD_FAB2(SCH_1):M_F_DQ<46>
  DJ34  M_F_DQ<45>     DDR5_DQ<45>  @BASEBOARD_FAB2_LIB.BASEBOARD_FAB2(SCH_1):M_F_DQ<45>
  DG34  M_F_DQ<44>     DDR5_DQ<44>  @BASEBOARD_FAB2_LIB.BASEBOARD_FAB2(SCH_1):M_F_DQ<44>
  DJ30  M_F_DQ<43>     DDR5_DQ<43>  @BASEBOARD_FAB2_LIB.BASEBOARD_FAB2(SCH_1):M_F_DQ<43>
  DG30  M_F_DQ<42>     DDR5_DQ<42>  @BASEBOARD_FAB2_LIB.BASEBOARD_FAB2(SCH_1):M_F_DQ<42>
  DK33  M_F_DQ<41>     DDR5_DQ<41>  @BASEBOARD_FAB2_LIB.BASEBOARD_FAB2(SCH_1):M_F_DQ<41>
  DF33  M_F_DQ<40>     DDR5_DQ<40>  @BASEBOARD_FAB2_LIB.BASEBOARD_FAB2(SCH_1):M_F_DQ<40>
  CV77  M_F_DQ<3>      DDR5_DQ<3>  @BASEBOARD_FAB2_LIB.BASEBOARD_FAB2(SCH_1):M_F_DQ<3>
  DH39  M_F_DQ<39>     DDR5_DQ<39>  @BASEBOARD_FAB2_LIB.BASEBOARD_FAB2(SCH_1):M_F_DQ<39>
  DD39  M_F_DQ<38>     DDR5_DQ<38>  @BASEBOARD_FAB2_LIB.BASEBOARD_FAB2(SCH_1):M_F_DQ<38>
  DE42  M_F_DQ<37>     DDR5_DQ<37>  @BASEBOARD_FAB2_LIB.BASEBOARD_FAB2(SCH_1):M_F_DQ<37>
  DA42  M_F_DQ<36>     DDR5_DQ<36>  @BASEBOARD_FAB2_LIB.BASEBOARD_FAB2(SCH_1):M_F_DQ<36>
  DG38  M_F_DQ<35>     DDR5_DQ<35>  @BASEBOARD_FAB2_LIB.BASEBOARD_FAB2(SCH_1):M_F_DQ<35>
  DE38  M_F_DQ<34>     DDR5_DQ<34>  @BASEBOARD_FAB2_LIB.BASEBOARD_FAB2(SCH_1):M_F_DQ<34>
  DG42  M_F_DQ<33>     DDR5_DQ<33>  @BASEBOARD_FAB2_LIB.BASEBOARD_FAB2(SCH_1):M_F_DQ<33>
  DD41  M_F_DQ<32>     DDR5_DQ<32>  @BASEBOARD_FAB2_LIB.BASEBOARD_FAB2(SCH_1):M_F_DQ<32>
  CU64  M_F_DQ<31>     DDR5_DQ<31>  @BASEBOARD_FAB2_LIB.BASEBOARD_FAB2(SCH_1):M_F_DQ<31>
  CN64  M_F_DQ<30>     DDR5_DQ<30>  @BASEBOARD_FAB2_LIB.BASEBOARD_FAB2(SCH_1):M_F_DQ<30>
  CW76  M_F_DQ<2>      DDR5_DQ<2>  @BASEBOARD_FAB2_LIB.BASEBOARD_FAB2(SCH_1):M_F_DQ<2>
  CT67  M_F_DQ<29>     DDR5_DQ<29>  @BASEBOARD_FAB2_LIB.BASEBOARD_FAB2(SCH_1):M_F_DQ<29>
  CP67  M_F_DQ<28>     DDR5_DQ<28>  @BASEBOARD_FAB2_LIB.BASEBOARD_FAB2(SCH_1):M_F_DQ<28>
  CT63  M_F_DQ<27>     DDR5_DQ<27>  @BASEBOARD_FAB2_LIB.BASEBOARD_FAB2(SCH_1):M_F_DQ<27>
  CP63  M_F_DQ<26>     DDR5_DQ<26>  @BASEBOARD_FAB2_LIB.BASEBOARD_FAB2(SCH_1):M_F_DQ<26>
  CU66  M_F_DQ<25>     DDR5_DQ<25>  @BASEBOARD_FAB2_LIB.BASEBOARD_FAB2(SCH_1):M_F_DQ<25>
  CN66  M_F_DQ<24>     DDR5_DQ<24>  @BASEBOARD_FAB2_LIB.BASEBOARD_FAB2(SCH_1):M_F_DQ<24>
  DM71  M_F_DQ<23>     DDR5_DQ<23>  @BASEBOARD_FAB2_LIB.BASEBOARD_FAB2(SCH_1):M_F_DQ<23>
  DK69  M_F_DQ<22>     DDR5_DQ<22>  @BASEBOARD_FAB2_LIB.BASEBOARD_FAB2(SCH_1):M_F_DQ<22>
  DG72  M_F_DQ<21>     DDR5_DQ<21>  @BASEBOARD_FAB2_LIB.BASEBOARD_FAB2(SCH_1):M_F_DQ<21>
  DF71  M_F_DQ<20>     DDR5_DQ<20>  @BASEBOARD_FAB2_LIB.BASEBOARD_FAB2(SCH_1):M_F_DQ<20>
  CN76  M_F_DQ<1>      DDR5_DQ<1>  @BASEBOARD_FAB2_LIB.BASEBOARD_FAB2(SCH_1):M_F_DQ<1>
  DN70  M_F_DQ<19>     DDR5_DQ<19>  @BASEBOARD_FAB2_LIB.BASEBOARD_FAB2(SCH_1):M_F_DQ<19>
  DM69  M_F_DQ<18>     DDR5_DQ<18>  @BASEBOARD_FAB2_LIB.BASEBOARD_FAB2(SCH_1):M_F_DQ<18>
  DJ72  M_F_DQ<17>     DDR5_DQ<17>  @BASEBOARD_FAB2_LIB.BASEBOARD_FAB2(SCH_1):M_F_DQ<17>
  DG70  M_F_DQ<16>     DDR5_DQ<16>  @BASEBOARD_FAB2_LIB.BASEBOARD_FAB2(SCH_1):M_F_DQ<16>
  DH77  M_F_DQ<15>     DDR5_DQ<15>  @BASEBOARD_FAB2_LIB.BASEBOARD_FAB2(SCH_1):M_F_DQ<15>
  DF77  M_F_DQ<14>     DDR5_DQ<14>  @BASEBOARD_FAB2_LIB.BASEBOARD_FAB2(SCH_1):M_F_DQ<14>
  DB75  M_F_DQ<13>     DDR5_DQ<13>  @BASEBOARD_FAB2_LIB.BASEBOARD_FAB2(SCH_1):M_F_DQ<13>
  DC74  M_F_DQ<12>     DDR5_DQ<12>  @BASEBOARD_FAB2_LIB.BASEBOARD_FAB2(SCH_1):M_F_DQ<12>
  DJ76  M_F_DQ<11>     DDR5_DQ<11>  @BASEBOARD_FAB2_LIB.BASEBOARD_FAB2(SCH_1):M_F_DQ<11>
  DH75  M_F_DQ<10>     DDR5_DQ<10>  @BASEBOARD_FAB2_LIB.BASEBOARD_FAB2(SCH_1):M_F_DQ<10>
  CR74  M_F_DQ<0>      DDR5_DQ<0>  @BASEBOARD_FAB2_LIB.BASEBOARD_FAB2(SCH_1):M_F_DQ<0>
  DK45  M_F_CS_N<7>    DDR5_CS_N<7>  @BASEBOARD_FAB2_LIB.BASEBOARD_FAB2(SCH_1):M_F_CS_N<7>
  DM45  M_F_CS_N<6>    DDR5_CS_N<6>  @BASEBOARD_FAB2_LIB.BASEBOARD_FAB2(SCH_1):M_F_CS_N<6>
  DJ48  M_F_CS_N<5>    DDR5_CS_N<5>  @BASEBOARD_FAB2_LIB.BASEBOARD_FAB2(SCH_1):M_F_CS_N<5>
  DF51  M_F_CS_N<4>    DDR5_CS_N<4>  @BASEBOARD_FAB2_LIB.BASEBOARD_FAB2(SCH_1):M_F_CS_N<4>
  DG46  M_F_CS_N<3>    DDR5_CS_N<3>  @BASEBOARD_FAB2_LIB.BASEBOARD_FAB2(SCH_1):M_F_CS_N<3>
  DJ46  M_F_CS_N<2>    DDR5_CS_N<2>  @BASEBOARD_FAB2_LIB.BASEBOARD_FAB2(SCH_1):M_F_CS_N<2>
  DF49  M_F_CS_N<1>    DDR5_CS_N<1>  @BASEBOARD_FAB2_LIB.BASEBOARD_FAB2(SCH_1):M_F_CS_N<1>
  DK51  M_F_CS_N<0>    DDR5_CS_N<0>  @BASEBOARD_FAB2_LIB.BASEBOARD_FAB2(SCH_1):M_F_CS_N<0>
  DG56  M_F_CLK_DP<3>  DDR5_CLK_DP<3>  @BASEBOARD_FAB2_LIB.BASEBOARD_FAB2(SCH_1):M_F_CLK_DP<3>
  DJ56  M_F_CLK_DP<2>  DDR5_CLK_DP<2>  @BASEBOARD_FAB2_LIB.BASEBOARD_FAB2(SCH_1):M_F_CLK_DP<2>
  DG54  M_F_CLK_DP<1>  DDR5_CLK_DP<1>  @BASEBOARD_FAB2_LIB.BASEBOARD_FAB2(SCH_1):M_F_CLK_DP<1>
  DJ54  M_F_CLK_DP<0>  DDR5_CLK_DP<0>  @BASEBOARD_FAB2_LIB.BASEBOARD_FAB2(SCH_1):M_F_CLK_DP<0>
  DF57  M_F_CLK_DN<3>  DDR5_CLK_DN<3>  @BASEBOARD_FAB2_LIB.BASEBOARD_FAB2(SCH_1):M_F_CLK_DN<3>
  DK57  M_F_CLK_DN<2>  DDR5_CLK_DN<2>  @BASEBOARD_FAB2_LIB.BASEBOARD_FAB2(SCH_1):M_F_CLK_DN<2>
  DF55  M_F_CLK_DN<1>  DDR5_CLK_DN<1>  @BASEBOARD_FAB2_LIB.BASEBOARD_FAB2(SCH_1):M_F_CLK_DN<1>
  DK55  M_F_CLK_DN<0>  DDR5_CLK_DN<0>  @BASEBOARD_FAB2_LIB.BASEBOARD_FAB2(SCH_1):M_F_CLK_DN<0>
  DF63  M_F_CKE<3>     DDR5_CKE<3>  @BASEBOARD_FAB2_LIB.BASEBOARD_FAB2(SCH_1):M_F_CKE<3>
  DK63  M_F_CKE<2>     DDR5_CKE<2>  @BASEBOARD_FAB2_LIB.BASEBOARD_FAB2(SCH_1):M_F_CKE<2>
  DD63  M_F_CKE<1>     DDR5_CKE<1>  @BASEBOARD_FAB2_LIB.BASEBOARD_FAB2(SCH_1):M_F_CKE<1>
  DG62  M_F_CKE<0>     DDR5_CKE<0>  @BASEBOARD_FAB2_LIB.BASEBOARD_FAB2(SCH_1):M_F_CKE<0>
  DF45  M_F_C<2>       DDR5_CID<2>  @BASEBOARD_FAB2_LIB.BASEBOARD_FAB2(SCH_1):M_F_C<2>
  DF61  M_F_BG<1>      DDR5_BG<1>  @BASEBOARD_FAB2_LIB.BASEBOARD_FAB2(SCH_1):M_F_BG<1>
  DA62  M_F_BG<0>      DDR5_BG<0>  @BASEBOARD_FAB2_LIB.BASEBOARD_FAB2(SCH_1):M_F_BG<0>
  DC56  M_F_BA<1>      DDR5_BA<1>  @BASEBOARD_FAB2_LIB.BASEBOARD_FAB2(SCH_1):M_F_BA<1>
  DJ52  M_F_BA<0>      DDR5_BA<0>  @BASEBOARD_FAB2_LIB.BASEBOARD_FAB2(SCH_1):M_F_BA<0>
  DD61  M_F_ALERT_N    DDR5_ALERT_N  @BASEBOARD_FAB2_LIB.BASEBOARD_FAB2(SCH_1):M_F_ALERT_N
  DC62  M_F_ACT_N      DDR5_ACT_N  @BASEBOARD_FAB2_LIB.BASEBOARD_FAB2(SCH_1):M_F_ACT_N

SKX_EXT_B_BGA1  I172  U5D1   [SKX_EXT_B_BGA1-IC,TBD]
  DV53  M_E_PAR        DDR4_PAR  @BASEBOARD_FAB2_LIB.BASEBOARD_FAB2(SCH_1):M_E_PAR
  DM47  M_E_ODT<3>     DDR4_ODT<3>  @BASEBOARD_FAB2_LIB.BASEBOARD_FAB2(SCH_1):M_E_ODT<3>
  DT49  M_E_ODT<2>     DDR4_ODT<2>  @BASEBOARD_FAB2_LIB.BASEBOARD_FAB2(SCH_1):M_E_ODT<2>
  DN48  M_E_ODT<1>     DDR4_ODT<1>  @BASEBOARD_FAB2_LIB.BASEBOARD_FAB2(SCH_1):M_E_ODT<1>
  DR50  M_E_ODT<0>     DDR4_ODT<0>  @BASEBOARD_FAB2_LIB.BASEBOARD_FAB2(SCH_1):M_E_ODT<0>
  DV59  M_E_MA<9>      DDR4_MA<9>  @BASEBOARD_FAB2_LIB.BASEBOARD_FAB2(SCH_1):M_E_MA<9>
  DJ60  M_E_MA<8>      DDR4_MA<8>  @BASEBOARD_FAB2_LIB.BASEBOARD_FAB2(SCH_1):M_E_MA<8>
  DK61  M_E_MA<7>      DDR4_MA<7>  @BASEBOARD_FAB2_LIB.BASEBOARD_FAB2(SCH_1):M_E_MA<7>
  DM59  M_E_MA<6>      DDR4_MA<6>  @BASEBOARD_FAB2_LIB.BASEBOARD_FAB2(SCH_1):M_E_MA<6>
  DN58  M_E_MA<5>      DDR4_MA<5>  @BASEBOARD_FAB2_LIB.BASEBOARD_FAB2(SCH_1):M_E_MA<5>
  DT59  M_E_MA<4>      DDR4_MA<4>  @BASEBOARD_FAB2_LIB.BASEBOARD_FAB2(SCH_1):M_E_MA<4>
  DR58  M_E_MA<3>      DDR4_MA<3>  @BASEBOARD_FAB2_LIB.BASEBOARD_FAB2(SCH_1):M_E_MA<3>
  DV57  M_E_MA<2>      DDR4_MA<2>  @BASEBOARD_FAB2_LIB.BASEBOARD_FAB2(SCH_1):M_E_MA<2>
  DW58  M_E_MA<1>      DDR4_MA<1>  @BASEBOARD_FAB2_LIB.BASEBOARD_FAB2(SCH_1):M_E_MA<1>
  DR48  M_E_MA<17>     DDR4_MA<17>  @BASEBOARD_FAB2_LIB.BASEBOARD_FAB2(SCH_1):M_E_MA<17>
  DN52  M_E_MA<16>     DDR4_MA<16>  @BASEBOARD_FAB2_LIB.BASEBOARD_FAB2(SCH_1):M_E_MA<16>
  DR52  M_E_MA<15>     DDR4_MA<15>  @BASEBOARD_FAB2_LIB.BASEBOARD_FAB2(SCH_1):M_E_MA<15>
  DM51  M_E_MA<14>     DDR4_MA<14>  @BASEBOARD_FAB2_LIB.BASEBOARD_FAB2(SCH_1):M_E_MA<14>
  DT51  M_E_MA<13>     DDR4_MA<13>  @BASEBOARD_FAB2_LIB.BASEBOARD_FAB2(SCH_1):M_E_MA<13>
  DN60  M_E_MA<12>     DDR4_MA<12>  @BASEBOARD_FAB2_LIB.BASEBOARD_FAB2(SCH_1):M_E_MA<12>
  DR60  M_E_MA<11>     DDR4_MA<11>  @BASEBOARD_FAB2_LIB.BASEBOARD_FAB2(SCH_1):M_E_MA<11>
  DT55  M_E_MA<10>     DDR4_MA<10>  @BASEBOARD_FAB2_LIB.BASEBOARD_FAB2(SCH_1):M_E_MA<10>
  DW52  M_E_MA<0>      DDR4_MA<0>  @BASEBOARD_FAB2_LIB.BASEBOARD_FAB2(SCH_1):M_E_MA<0>
  EA66  M_E_ECC<7>     DDR4_ECC<7>  @BASEBOARD_FAB2_LIB.BASEBOARD_FAB2(SCH_1):M_E_ECC<7>
  DU66  M_E_ECC<6>     DDR4_ECC<6>  @BASEBOARD_FAB2_LIB.BASEBOARD_FAB2(SCH_1):M_E_ECC<6>
  DV69  M_E_ECC<5>     DDR4_ECC<5>  @BASEBOARD_FAB2_LIB.BASEBOARD_FAB2(SCH_1):M_E_ECC<5>
  DU68  M_E_ECC<4>     DDR4_ECC<4>  @BASEBOARD_FAB2_LIB.BASEBOARD_FAB2(SCH_1):M_E_ECC<4>
  DY65  M_E_ECC<3>     DDR4_ECC<3>  @BASEBOARD_FAB2_LIB.BASEBOARD_FAB2(SCH_1):M_E_ECC<3>
  DV65  M_E_ECC<2>     DDR4_ECC<2>  @BASEBOARD_FAB2_LIB.BASEBOARD_FAB2(SCH_1):M_E_ECC<2>
  EA68  M_E_ECC<1>     DDR4_ECC<1>  @BASEBOARD_FAB2_LIB.BASEBOARD_FAB2(SCH_1):M_E_ECC<1>
  DY69  M_E_ECC<0>     DDR4_ECC<0>  @BASEBOARD_FAB2_LIB.BASEBOARD_FAB2(SCH_1):M_E_ECC<0>
  CP79  M_E_DQS_DP<9>  DDR4_DQS_DP<9>  @BASEBOARD_FAB2_LIB.BASEBOARD_FAB2(SCH_1):M_E_DQS_DP<9>
  DY67  M_E_DQS_DP<8>  DDR4_DQS_DP<8>  @BASEBOARD_FAB2_LIB.BASEBOARD_FAB2(SCH_1):M_E_DQS_DP<8>
  DJ26  M_E_DQS_DP<7>  DDR4_DQS_DP<7>  @BASEBOARD_FAB2_LIB.BASEBOARD_FAB2(SCH_1):M_E_DQS_DP<7>
  EC26  M_E_DQS_DP<6>  DDR4_DQS_DP<6>  @BASEBOARD_FAB2_LIB.BASEBOARD_FAB2(SCH_1):M_E_DQS_DP<6>
  EC32  M_E_DQS_DP<5>  DDR4_DQS_DP<5>  @BASEBOARD_FAB2_LIB.BASEBOARD_FAB2(SCH_1):M_E_DQS_DP<5>
  DT41  M_E_DQS_DP<4>  DDR4_DQS_DP<4>  @BASEBOARD_FAB2_LIB.BASEBOARD_FAB2(SCH_1):M_E_DQS_DP<4>
  ED73  M_E_DQS_DP<3>  DDR4_DQS_DP<3>  @BASEBOARD_FAB2_LIB.BASEBOARD_FAB2(SCH_1):M_E_DQS_DP<3>
  EB79  M_E_DQS_DP<2>  DDR4_DQS_DP<2>  @BASEBOARD_FAB2_LIB.BASEBOARD_FAB2(SCH_1):M_E_DQS_DP<2>
  DB81  M_E_DQS_DP<1>  DDR4_DQS_DP<1>  @BASEBOARD_FAB2_LIB.BASEBOARD_FAB2(SCH_1):M_E_DQS_DP<1>
  DT67  M_E_DQS_DP<17>  DDR4_DQS_DP<17>  @BASEBOARD_FAB2_LIB.BASEBOARD_FAB2(SCH_1):M_E_DQS_DP<17>
  DE26  M_E_DQS_DP<16>  DDR4_DQS_DP<16>  @BASEBOARD_FAB2_LIB.BASEBOARD_FAB2(SCH_1):M_E_DQS_DP<16>
  DW26  M_E_DQS_DP<15>  DDR4_DQS_DP<15>  @BASEBOARD_FAB2_LIB.BASEBOARD_FAB2(SCH_1):M_E_DQS_DP<15>
  DW32  M_E_DQS_DP<14>  DDR4_DQS_DP<14>  @BASEBOARD_FAB2_LIB.BASEBOARD_FAB2(SCH_1):M_E_DQS_DP<14>
  DM41  M_E_DQS_DP<13>  DDR4_DQS_DP<13>  @BASEBOARD_FAB2_LIB.BASEBOARD_FAB2(SCH_1):M_E_DQS_DP<13>
  DY73  M_E_DQS_DP<12>  DDR4_DQS_DP<12>  @BASEBOARD_FAB2_LIB.BASEBOARD_FAB2(SCH_1):M_E_DQS_DP<12>
  DV79  M_E_DQS_DP<11>  DDR4_DQS_DP<11>  @BASEBOARD_FAB2_LIB.BASEBOARD_FAB2(SCH_1):M_E_DQS_DP<11>
  DD79  M_E_DQS_DP<10>  DDR4_DQS_DP<10>  @BASEBOARD_FAB2_LIB.BASEBOARD_FAB2(SCH_1):M_E_DQS_DP<10>
  CM81  M_E_DQS_DP<0>  DDR4_DQS_DP<0>  @BASEBOARD_FAB2_LIB.BASEBOARD_FAB2(SCH_1):M_E_DQS_DP<0>
  CN80  M_E_DQS_DN<9>  DDR4_DQS_DN<9>  @BASEBOARD_FAB2_LIB.BASEBOARD_FAB2(SCH_1):M_E_DQS_DN<9>
  EB67  M_E_DQS_DN<8>  DDR4_DQS_DN<8>  @BASEBOARD_FAB2_LIB.BASEBOARD_FAB2(SCH_1):M_E_DQS_DN<8>
  DL26  M_E_DQS_DN<7>  DDR4_DQS_DN<7>  @BASEBOARD_FAB2_LIB.BASEBOARD_FAB2(SCH_1):M_E_DQS_DN<7>
  EE26  M_E_DQS_DN<6>  DDR4_DQS_DN<6>  @BASEBOARD_FAB2_LIB.BASEBOARD_FAB2(SCH_1):M_E_DQS_DN<6>
  EE32  M_E_DQS_DN<5>  DDR4_DQS_DN<5>  @BASEBOARD_FAB2_LIB.BASEBOARD_FAB2(SCH_1):M_E_DQS_DN<5>
  DV41  M_E_DQS_DN<4>  DDR4_DQS_DN<4>  @BASEBOARD_FAB2_LIB.BASEBOARD_FAB2(SCH_1):M_E_DQS_DN<4>
  EF73  M_E_DQS_DN<3>  DDR4_DQS_DN<3>  @BASEBOARD_FAB2_LIB.BASEBOARD_FAB2(SCH_1):M_E_DQS_DN<3>
  ED79  M_E_DQS_DN<2>  DDR4_DQS_DN<2>  @BASEBOARD_FAB2_LIB.BASEBOARD_FAB2(SCH_1):M_E_DQS_DN<2>
  DA82  M_E_DQS_DN<1>  DDR4_DQS_DN<1>  @BASEBOARD_FAB2_LIB.BASEBOARD_FAB2(SCH_1):M_E_DQS_DN<1>
  DV67  M_E_DQS_DN<17>  DDR4_DQS_DN<17>  @BASEBOARD_FAB2_LIB.BASEBOARD_FAB2(SCH_1):M_E_DQS_DN<17>
  DG26  M_E_DQS_DN<16>  DDR4_DQS_DN<16>  @BASEBOARD_FAB2_LIB.BASEBOARD_FAB2(SCH_1):M_E_DQS_DN<16>
  EA26  M_E_DQS_DN<15>  DDR4_DQS_DN<15>  @BASEBOARD_FAB2_LIB.BASEBOARD_FAB2(SCH_1):M_E_DQS_DN<15>
  EA32  M_E_DQS_DN<14>  DDR4_DQS_DN<14>  @BASEBOARD_FAB2_LIB.BASEBOARD_FAB2(SCH_1):M_E_DQS_DN<14>
  DP41  M_E_DQS_DN<13>  DDR4_DQS_DN<13>  @BASEBOARD_FAB2_LIB.BASEBOARD_FAB2(SCH_1):M_E_DQS_DN<13>
  EB73  M_E_DQS_DN<12>  DDR4_DQS_DN<12>  @BASEBOARD_FAB2_LIB.BASEBOARD_FAB2(SCH_1):M_E_DQS_DN<12>
  DY79  M_E_DQS_DN<11>  DDR4_DQS_DN<11>  @BASEBOARD_FAB2_LIB.BASEBOARD_FAB2(SCH_1):M_E_DQS_DN<11>
  DC80  M_E_DQS_DN<10>  DDR4_DQS_DN<10>  @BASEBOARD_FAB2_LIB.BASEBOARD_FAB2(SCH_1):M_E_DQS_DN<10>
  CL82  M_E_DQS_DN<0>  DDR4_DQS_DN<0>  @BASEBOARD_FAB2_LIB.BASEBOARD_FAB2(SCH_1):M_E_DQS_DN<0>
  CY81  M_E_DQ<9>      DDR4_DQ<9>  @BASEBOARD_FAB2_LIB.BASEBOARD_FAB2(SCH_1):M_E_DQ<9>
  DB79  M_E_DQ<8>      DDR4_DQ<8>  @BASEBOARD_FAB2_LIB.BASEBOARD_FAB2(SCH_1):M_E_DQ<8>
  CN82  M_E_DQ<7>      DDR4_DQ<7>  @BASEBOARD_FAB2_LIB.BASEBOARD_FAB2(SCH_1):M_E_DQ<7>
  CR80  M_E_DQ<6>      DDR4_DQ<6>  @BASEBOARD_FAB2_LIB.BASEBOARD_FAB2(SCH_1):M_E_DQ<6>
  DK25  M_E_DQ<63>     DDR4_DQ<63>  @BASEBOARD_FAB2_LIB.BASEBOARD_FAB2(SCH_1):M_E_DQ<63>
  DF25  M_E_DQ<62>     DDR4_DQ<62>  @BASEBOARD_FAB2_LIB.BASEBOARD_FAB2(SCH_1):M_E_DQ<62>
  DJ28  M_E_DQ<61>     DDR4_DQ<61>  @BASEBOARD_FAB2_LIB.BASEBOARD_FAB2(SCH_1):M_E_DQ<61>
  DG28  M_E_DQ<60>     DDR4_DQ<60>  @BASEBOARD_FAB2_LIB.BASEBOARD_FAB2(SCH_1):M_E_DQ<60>
  CJ80  M_E_DQ<5>      DDR4_DQ<5>  @BASEBOARD_FAB2_LIB.BASEBOARD_FAB2(SCH_1):M_E_DQ<5>
  DJ24  M_E_DQ<59>     DDR4_DQ<59>  @BASEBOARD_FAB2_LIB.BASEBOARD_FAB2(SCH_1):M_E_DQ<59>
  DD25  M_E_DQ<58>     DDR4_DQ<58>  @BASEBOARD_FAB2_LIB.BASEBOARD_FAB2(SCH_1):M_E_DQ<58>
  DK27  M_E_DQ<57>     DDR4_DQ<57>  @BASEBOARD_FAB2_LIB.BASEBOARD_FAB2(SCH_1):M_E_DQ<57>
  DF27  M_E_DQ<56>     DDR4_DQ<56>  @BASEBOARD_FAB2_LIB.BASEBOARD_FAB2(SCH_1):M_E_DQ<56>
  ED25  M_E_DQ<55>     DDR4_DQ<55>  @BASEBOARD_FAB2_LIB.BASEBOARD_FAB2(SCH_1):M_E_DQ<55>
  DY25  M_E_DQ<54>     DDR4_DQ<54>  @BASEBOARD_FAB2_LIB.BASEBOARD_FAB2(SCH_1):M_E_DQ<54>
  EA28  M_E_DQ<53>     DDR4_DQ<53>  @BASEBOARD_FAB2_LIB.BASEBOARD_FAB2(SCH_1):M_E_DQ<53>
  DY27  M_E_DQ<52>     DDR4_DQ<52>  @BASEBOARD_FAB2_LIB.BASEBOARD_FAB2(SCH_1):M_E_DQ<52>
  EC24  M_E_DQ<51>     DDR4_DQ<51>  @BASEBOARD_FAB2_LIB.BASEBOARD_FAB2(SCH_1):M_E_DQ<51>
  EA24  M_E_DQ<50>     DDR4_DQ<50>  @BASEBOARD_FAB2_LIB.BASEBOARD_FAB2(SCH_1):M_E_DQ<50>
  CK79  M_E_DQ<4>      DDR4_DQ<4>  @BASEBOARD_FAB2_LIB.BASEBOARD_FAB2(SCH_1):M_E_DQ<4>
  ED27  M_E_DQ<49>     DDR4_DQ<49>  @BASEBOARD_FAB2_LIB.BASEBOARD_FAB2(SCH_1):M_E_DQ<49>
  EC28  M_E_DQ<48>     DDR4_DQ<48>  @BASEBOARD_FAB2_LIB.BASEBOARD_FAB2(SCH_1):M_E_DQ<48>
  ED31  M_E_DQ<47>     DDR4_DQ<47>  @BASEBOARD_FAB2_LIB.BASEBOARD_FAB2(SCH_1):M_E_DQ<47>
  DY31  M_E_DQ<46>     DDR4_DQ<46>  @BASEBOARD_FAB2_LIB.BASEBOARD_FAB2(SCH_1):M_E_DQ<46>
  EA34  M_E_DQ<45>     DDR4_DQ<45>  @BASEBOARD_FAB2_LIB.BASEBOARD_FAB2(SCH_1):M_E_DQ<45>
  DY33  M_E_DQ<44>     DDR4_DQ<44>  @BASEBOARD_FAB2_LIB.BASEBOARD_FAB2(SCH_1):M_E_DQ<44>
  EC30  M_E_DQ<43>     DDR4_DQ<43>  @BASEBOARD_FAB2_LIB.BASEBOARD_FAB2(SCH_1):M_E_DQ<43>
  EA30  M_E_DQ<42>     DDR4_DQ<42>  @BASEBOARD_FAB2_LIB.BASEBOARD_FAB2(SCH_1):M_E_DQ<42>
  ED33  M_E_DQ<41>     DDR4_DQ<41>  @BASEBOARD_FAB2_LIB.BASEBOARD_FAB2(SCH_1):M_E_DQ<41>
  EC34  M_E_DQ<40>     DDR4_DQ<40>  @BASEBOARD_FAB2_LIB.BASEBOARD_FAB2(SCH_1):M_E_DQ<40>
  CR82  M_E_DQ<3>      DDR4_DQ<3>  @BASEBOARD_FAB2_LIB.BASEBOARD_FAB2(SCH_1):M_E_DQ<3>
  DU40  M_E_DQ<39>     DDR4_DQ<39>  @BASEBOARD_FAB2_LIB.BASEBOARD_FAB2(SCH_1):M_E_DQ<39>
  DN40  M_E_DQ<38>     DDR4_DQ<38>  @BASEBOARD_FAB2_LIB.BASEBOARD_FAB2(SCH_1):M_E_DQ<38>
  DN42  M_E_DQ<37>     DDR4_DQ<37>  @BASEBOARD_FAB2_LIB.BASEBOARD_FAB2(SCH_1):M_E_DQ<37>
  DL42  M_E_DQ<36>     DDR4_DQ<36>  @BASEBOARD_FAB2_LIB.BASEBOARD_FAB2(SCH_1):M_E_DQ<36>
  DT39  M_E_DQ<35>     DDR4_DQ<35>  @BASEBOARD_FAB2_LIB.BASEBOARD_FAB2(SCH_1):M_E_DQ<35>
  DP39  M_E_DQ<34>     DDR4_DQ<34>  @BASEBOARD_FAB2_LIB.BASEBOARD_FAB2(SCH_1):M_E_DQ<34>
  DW42  M_E_DQ<33>     DDR4_DQ<33>  @BASEBOARD_FAB2_LIB.BASEBOARD_FAB2(SCH_1):M_E_DQ<33>
  DU42  M_E_DQ<32>     DDR4_DQ<32>  @BASEBOARD_FAB2_LIB.BASEBOARD_FAB2(SCH_1):M_E_DQ<32>
  EE72  M_E_DQ<31>     DDR4_DQ<31>  @BASEBOARD_FAB2_LIB.BASEBOARD_FAB2(SCH_1):M_E_DQ<31>
  EA72  M_E_DQ<30>     DDR4_DQ<30>  @BASEBOARD_FAB2_LIB.BASEBOARD_FAB2(SCH_1):M_E_DQ<30>
  CT81  M_E_DQ<2>      DDR4_DQ<2>  @BASEBOARD_FAB2_LIB.BASEBOARD_FAB2(SCH_1):M_E_DQ<2>
  EB75  M_E_DQ<29>     DDR4_DQ<29>  @BASEBOARD_FAB2_LIB.BASEBOARD_FAB2(SCH_1):M_E_DQ<29>
  EA74  M_E_DQ<28>     DDR4_DQ<28>  @BASEBOARD_FAB2_LIB.BASEBOARD_FAB2(SCH_1):M_E_DQ<28>
  ED71  M_E_DQ<27>     DDR4_DQ<27>  @BASEBOARD_FAB2_LIB.BASEBOARD_FAB2(SCH_1):M_E_DQ<27>
  EB71  M_E_DQ<26>     DDR4_DQ<26>  @BASEBOARD_FAB2_LIB.BASEBOARD_FAB2(SCH_1):M_E_DQ<26>
  EE74  M_E_DQ<25>     DDR4_DQ<25>  @BASEBOARD_FAB2_LIB.BASEBOARD_FAB2(SCH_1):M_E_DQ<25>
  ED75  M_E_DQ<24>     DDR4_DQ<24>  @BASEBOARD_FAB2_LIB.BASEBOARD_FAB2(SCH_1):M_E_DQ<24>
  EC78  M_E_DQ<23>     DDR4_DQ<23>  @BASEBOARD_FAB2_LIB.BASEBOARD_FAB2(SCH_1):M_E_DQ<23>
  DW78  M_E_DQ<22>     DDR4_DQ<22>  @BASEBOARD_FAB2_LIB.BASEBOARD_FAB2(SCH_1):M_E_DQ<22>
  EB81  M_E_DQ<21>     DDR4_DQ<21>  @BASEBOARD_FAB2_LIB.BASEBOARD_FAB2(SCH_1):M_E_DQ<21>
  DY81  M_E_DQ<20>     DDR4_DQ<20>  @BASEBOARD_FAB2_LIB.BASEBOARD_FAB2(SCH_1):M_E_DQ<20>
  CK81  M_E_DQ<1>      DDR4_DQ<1>  @BASEBOARD_FAB2_LIB.BASEBOARD_FAB2(SCH_1):M_E_DQ<1>
  EB77  M_E_DQ<19>     DDR4_DQ<19>  @BASEBOARD_FAB2_LIB.BASEBOARD_FAB2(SCH_1):M_E_DQ<19>
  DY77  M_E_DQ<18>     DDR4_DQ<18>  @BASEBOARD_FAB2_LIB.BASEBOARD_FAB2(SCH_1):M_E_DQ<18>
  EC80  M_E_DQ<17>     DDR4_DQ<17>  @BASEBOARD_FAB2_LIB.BASEBOARD_FAB2(SCH_1):M_E_DQ<17>
  DW80  M_E_DQ<16>     DDR4_DQ<16>  @BASEBOARD_FAB2_LIB.BASEBOARD_FAB2(SCH_1):M_E_DQ<16>
  DE82  M_E_DQ<15>     DDR4_DQ<15>  @BASEBOARD_FAB2_LIB.BASEBOARD_FAB2(SCH_1):M_E_DQ<15>
  DC82  M_E_DQ<14>     DDR4_DQ<14>  @BASEBOARD_FAB2_LIB.BASEBOARD_FAB2(SCH_1):M_E_DQ<14>
  CW80  M_E_DQ<13>     DDR4_DQ<13>  @BASEBOARD_FAB2_LIB.BASEBOARD_FAB2(SCH_1):M_E_DQ<13>
  CY79  M_E_DQ<12>     DDR4_DQ<12>  @BASEBOARD_FAB2_LIB.BASEBOARD_FAB2(SCH_1):M_E_DQ<12>
  DF81  M_E_DQ<11>     DDR4_DQ<11>  @BASEBOARD_FAB2_LIB.BASEBOARD_FAB2(SCH_1):M_E_DQ<11>
  DE80  M_E_DQ<10>     DDR4_DQ<10>  @BASEBOARD_FAB2_LIB.BASEBOARD_FAB2(SCH_1):M_E_DQ<10>
  CM79  M_E_DQ<0>      DDR4_DQ<0>  @BASEBOARD_FAB2_LIB.BASEBOARD_FAB2(SCH_1):M_E_DQ<0>
  DN46  M_E_CS_N<7>    DDR4_CS_N<7>  @BASEBOARD_FAB2_LIB.BASEBOARD_FAB2(SCH_1):M_E_CS_N<7>
  DT45  M_E_CS_N<6>    DDR4_CS_N<6>  @BASEBOARD_FAB2_LIB.BASEBOARD_FAB2(SCH_1):M_E_CS_N<6>
  DM49  M_E_CS_N<5>    DDR4_CS_N<5>  @BASEBOARD_FAB2_LIB.BASEBOARD_FAB2(SCH_1):M_E_CS_N<5>
  DW50  M_E_CS_N<4>    DDR4_CS_N<4>  @BASEBOARD_FAB2_LIB.BASEBOARD_FAB2(SCH_1):M_E_CS_N<4>
  DK47  M_E_CS_N<3>    DDR4_CS_N<3>  @BASEBOARD_FAB2_LIB.BASEBOARD_FAB2(SCH_1):M_E_CS_N<3>
  DR46  M_E_CS_N<2>    DDR4_CS_N<2>  @BASEBOARD_FAB2_LIB.BASEBOARD_FAB2(SCH_1):M_E_CS_N<2>
  DN50  M_E_CS_N<1>    DDR4_CS_N<1>  @BASEBOARD_FAB2_LIB.BASEBOARD_FAB2(SCH_1):M_E_CS_N<1>
  DV51  M_E_CS_N<0>    DDR4_CS_N<0>  @BASEBOARD_FAB2_LIB.BASEBOARD_FAB2(SCH_1):M_E_CS_N<0>
  DR56  M_E_CLK_DP<3>  DDR4_CLK_DP<3>  @BASEBOARD_FAB2_LIB.BASEBOARD_FAB2(SCH_1):M_E_CLK_DP<3>
  DN56  M_E_CLK_DP<2>  DDR4_CLK_DP<2>  @BASEBOARD_FAB2_LIB.BASEBOARD_FAB2(SCH_1):M_E_CLK_DP<2>
  DT53  M_E_CLK_DP<1>  DDR4_CLK_DP<1>  @BASEBOARD_FAB2_LIB.BASEBOARD_FAB2(SCH_1):M_E_CLK_DP<1>
  DN54  M_E_CLK_DP<0>  DDR4_CLK_DP<0>  @BASEBOARD_FAB2_LIB.BASEBOARD_FAB2(SCH_1):M_E_CLK_DP<0>
  DT57  M_E_CLK_DN<3>  DDR4_CLK_DN<3>  @BASEBOARD_FAB2_LIB.BASEBOARD_FAB2(SCH_1):M_E_CLK_DN<3>
  DM57  M_E_CLK_DN<2>  DDR4_CLK_DN<2>  @BASEBOARD_FAB2_LIB.BASEBOARD_FAB2(SCH_1):M_E_CLK_DN<2>
  DR54  M_E_CLK_DN<1>  DDR4_CLK_DN<1>  @BASEBOARD_FAB2_LIB.BASEBOARD_FAB2(SCH_1):M_E_CLK_DN<1>
  DM55  M_E_CLK_DN<0>  DDR4_CLK_DN<0>  @BASEBOARD_FAB2_LIB.BASEBOARD_FAB2(SCH_1):M_E_CLK_DN<0>
  DR64  M_E_CKE<3>     DDR4_CKE<3>  @BASEBOARD_FAB2_LIB.BASEBOARD_FAB2(SCH_1):M_E_CKE<3>
  DL64  M_E_CKE<2>     DDR4_CKE<2>  @BASEBOARD_FAB2_LIB.BASEBOARD_FAB2(SCH_1):M_E_CKE<2>
  DN64  M_E_CKE<1>     DDR4_CKE<1>  @BASEBOARD_FAB2_LIB.BASEBOARD_FAB2(SCH_1):M_E_CKE<1>
  DM63  M_E_CKE<0>     DDR4_CKE<0>  @BASEBOARD_FAB2_LIB.BASEBOARD_FAB2(SCH_1):M_E_CKE<0>
  DT47  M_E_C<2>       DDR4_CID<2>  @BASEBOARD_FAB2_LIB.BASEBOARD_FAB2(SCH_1):M_E_C<2>
  DM61  M_E_BG<1>      DDR4_BG<1>  @BASEBOARD_FAB2_LIB.BASEBOARD_FAB2(SCH_1):M_E_BG<1>
  DJ62  M_E_BG<0>      DDR4_BG<0>  @BASEBOARD_FAB2_LIB.BASEBOARD_FAB2(SCH_1):M_E_BG<0>
  DV55  M_E_BA<1>      DDR4_BA<1>  @BASEBOARD_FAB2_LIB.BASEBOARD_FAB2(SCH_1):M_E_BA<1>
  DM53  M_E_BA<0>      DDR4_BA<0>  @BASEBOARD_FAB2_LIB.BASEBOARD_FAB2(SCH_1):M_E_BA<0>
  DT61  M_E_ALERT_N    DDR4_ALERT_N  @BASEBOARD_FAB2_LIB.BASEBOARD_FAB2(SCH_1):M_E_ALERT_N
  DR62  M_E_ACT_N      DDR4_ACT_N  @BASEBOARD_FAB2_LIB.BASEBOARD_FAB2(SCH_1):M_E_ACT_N

SKX_EXT_B_BGA1  I172  U5D1   [SKX_EXT_B_BGA1-IC,TBD]
  ED53  M_D_PAR        DDR3_PAR  @BASEBOARD_FAB2_LIB.BASEBOARD_FAB2(SCH_1):M_D_PAR
  EA48  M_D_ODT<3>     DDR3_ODT<3>  @BASEBOARD_FAB2_LIB.BASEBOARD_FAB2(SCH_1):M_D_ODT<3>
  EA50  M_D_ODT<2>     DDR3_ODT<2>  @BASEBOARD_FAB2_LIB.BASEBOARD_FAB2(SCH_1):M_D_ODT<2>
  EE48  M_D_ODT<1>     DDR3_ODT<1>  @BASEBOARD_FAB2_LIB.BASEBOARD_FAB2(SCH_1):M_D_ODT<1>
  EE50  M_D_ODT<0>     DDR3_ODT<0>  @BASEBOARD_FAB2_LIB.BASEBOARD_FAB2(SCH_1):M_D_ODT<0>
  EF61  M_D_MA<9>      DDR3_MA<9>  @BASEBOARD_FAB2_LIB.BASEBOARD_FAB2(SCH_1):M_D_MA<9>
  EB59  M_D_MA<8>      DDR3_MA<8>  @BASEBOARD_FAB2_LIB.BASEBOARD_FAB2(SCH_1):M_D_MA<8>
  EA60  M_D_MA<7>      DDR3_MA<7>  @BASEBOARD_FAB2_LIB.BASEBOARD_FAB2(SCH_1):M_D_MA<7>
  EE60  M_D_MA<6>      DDR3_MA<6>  @BASEBOARD_FAB2_LIB.BASEBOARD_FAB2(SCH_1):M_D_MA<6>
  EA58  M_D_MA<5>      DDR3_MA<5>  @BASEBOARD_FAB2_LIB.BASEBOARD_FAB2(SCH_1):M_D_MA<5>
  ED59  M_D_MA<4>      DDR3_MA<4>  @BASEBOARD_FAB2_LIB.BASEBOARD_FAB2(SCH_1):M_D_MA<4>
  EB57  M_D_MA<3>      DDR3_MA<3>  @BASEBOARD_FAB2_LIB.BASEBOARD_FAB2(SCH_1):M_D_MA<3>
  EE58  M_D_MA<2>      DDR3_MA<2>  @BASEBOARD_FAB2_LIB.BASEBOARD_FAB2(SCH_1):M_D_MA<2>
  ED57  M_D_MA<1>      DDR3_MA<1>  @BASEBOARD_FAB2_LIB.BASEBOARD_FAB2(SCH_1):M_D_MA<1>
  EA46  M_D_MA<17>     DDR3_MA<17>  @BASEBOARD_FAB2_LIB.BASEBOARD_FAB2(SCH_1):M_D_MA<17>
  EA52  M_D_MA<16>     DDR3_MA<16>  @BASEBOARD_FAB2_LIB.BASEBOARD_FAB2(SCH_1):M_D_MA<16>
  DV49  M_D_MA<15>     DDR3_MA<15>  @BASEBOARD_FAB2_LIB.BASEBOARD_FAB2(SCH_1):M_D_MA<15>
  ED51  M_D_MA<14>     DDR3_MA<14>  @BASEBOARD_FAB2_LIB.BASEBOARD_FAB2(SCH_1):M_D_MA<14>
  DW48  M_D_MA<13>     DDR3_MA<13>  @BASEBOARD_FAB2_LIB.BASEBOARD_FAB2(SCH_1):M_D_MA<13>
  DT63  M_D_MA<12>     DDR3_MA<12>  @BASEBOARD_FAB2_LIB.BASEBOARD_FAB2(SCH_1):M_D_MA<12>
  EB61  M_D_MA<11>     DDR3_MA<11>  @BASEBOARD_FAB2_LIB.BASEBOARD_FAB2(SCH_1):M_D_MA<11>
  DW54  M_D_MA<10>     DDR3_MA<10>  @BASEBOARD_FAB2_LIB.BASEBOARD_FAB2(SCH_1):M_D_MA<10>
  EB53  M_D_MA<0>      DDR3_MA<0>  @BASEBOARD_FAB2_LIB.BASEBOARD_FAB2(SCH_1):M_D_MA<0>
  DE66  M_D_ECC<7>     DDR3_ECC<7>  @BASEBOARD_FAB2_LIB.BASEBOARD_FAB2(SCH_1):M_D_ECC<7>
  DA66  M_D_ECC<6>     DDR3_ECC<6>  @BASEBOARD_FAB2_LIB.BASEBOARD_FAB2(SCH_1):M_D_ECC<6>
  DD69  M_D_ECC<5>     DDR3_ECC<5>  @BASEBOARD_FAB2_LIB.BASEBOARD_FAB2(SCH_1):M_D_ECC<5>
  DB69  M_D_ECC<4>     DDR3_ECC<4>  @BASEBOARD_FAB2_LIB.BASEBOARD_FAB2(SCH_1):M_D_ECC<4>
  DD65  M_D_ECC<3>     DDR3_ECC<3>  @BASEBOARD_FAB2_LIB.BASEBOARD_FAB2(SCH_1):M_D_ECC<3>
  DB65  M_D_ECC<2>     DDR3_ECC<2>  @BASEBOARD_FAB2_LIB.BASEBOARD_FAB2(SCH_1):M_D_ECC<2>
  DE68  M_D_ECC<1>     DDR3_ECC<1>  @BASEBOARD_FAB2_LIB.BASEBOARD_FAB2(SCH_1):M_D_ECC<1>
  DA68  M_D_ECC<0>     DDR3_ECC<0>  @BASEBOARD_FAB2_LIB.BASEBOARD_FAB2(SCH_1):M_D_ECC<0>
  CP85  M_D_DQS_DP<9>  DDR3_DQS_DP<9>  @BASEBOARD_FAB2_LIB.BASEBOARD_FAB2(SCH_1):M_D_DQS_DP<9>
  DD67  M_D_DQS_DP<8>  DDR3_DQS_DP<8>  @BASEBOARD_FAB2_LIB.BASEBOARD_FAB2(SCH_1):M_D_DQS_DP<8>
  DT23  M_D_DQS_DP<7>  DDR3_DQS_DP<7>  @BASEBOARD_FAB2_LIB.BASEBOARD_FAB2(SCH_1):M_D_DQS_DP<7>
  DT29  M_D_DQS_DP<6>  DDR3_DQS_DP<6>  @BASEBOARD_FAB2_LIB.BASEBOARD_FAB2(SCH_1):M_D_DQS_DP<6>
  DT35  M_D_DQS_DP<5>  DDR3_DQS_DP<5>  @BASEBOARD_FAB2_LIB.BASEBOARD_FAB2(SCH_1):M_D_DQS_DP<5>
  EC38  M_D_DQS_DP<4>  DDR3_DQS_DP<4>  @BASEBOARD_FAB2_LIB.BASEBOARD_FAB2(SCH_1):M_D_DQS_DP<4>
  DT75  M_D_DQS_DP<3>  DDR3_DQS_DP<3>  @BASEBOARD_FAB2_LIB.BASEBOARD_FAB2(SCH_1):M_D_DQS_DP<3>
  DM81  M_D_DQS_DP<2>  DDR3_DQS_DP<2>  @BASEBOARD_FAB2_LIB.BASEBOARD_FAB2(SCH_1):M_D_DQS_DP<2>
  DP85  M_D_DQS_DP<1>  DDR3_DQS_DP<1>  @BASEBOARD_FAB2_LIB.BASEBOARD_FAB2(SCH_1):M_D_DQS_DP<1>
  CY67  M_D_DQS_DP<17>  DDR3_DQS_DP<17>  @BASEBOARD_FAB2_LIB.BASEBOARD_FAB2(SCH_1):M_D_DQS_DP<17>
  DP23  M_D_DQS_DP<16>  DDR3_DQS_DP<16>  @BASEBOARD_FAB2_LIB.BASEBOARD_FAB2(SCH_1):M_D_DQS_DP<16>
  DP29  M_D_DQS_DP<15>  DDR3_DQS_DP<15>  @BASEBOARD_FAB2_LIB.BASEBOARD_FAB2(SCH_1):M_D_DQS_DP<15>
  DM35  M_D_DQS_DP<14>  DDR3_DQS_DP<14>  @BASEBOARD_FAB2_LIB.BASEBOARD_FAB2(SCH_1):M_D_DQS_DP<14>
  DW38  M_D_DQS_DP<13>  DDR3_DQS_DP<13>  @BASEBOARD_FAB2_LIB.BASEBOARD_FAB2(SCH_1):M_D_DQS_DP<13>
  DM75  M_D_DQS_DP<12>  DDR3_DQS_DP<12>  @BASEBOARD_FAB2_LIB.BASEBOARD_FAB2(SCH_1):M_D_DQS_DP<12>
  DP79  M_D_DQS_DP<11>  DDR3_DQS_DP<11>  @BASEBOARD_FAB2_LIB.BASEBOARD_FAB2(SCH_1):M_D_DQS_DP<11>
  DL84  M_D_DQS_DP<10>  DDR3_DQS_DP<10>  @BASEBOARD_FAB2_LIB.BASEBOARD_FAB2(SCH_1):M_D_DQS_DP<10>
  CV85  M_D_DQS_DP<0>  DDR3_DQS_DP<0>  @BASEBOARD_FAB2_LIB.BASEBOARD_FAB2(SCH_1):M_D_DQS_DP<0>
  CR84  M_D_DQS_DN<9>  DDR3_DQS_DN<9>  @BASEBOARD_FAB2_LIB.BASEBOARD_FAB2(SCH_1):M_D_DQS_DN<9>
  DF67  M_D_DQS_DN<8>  DDR3_DQS_DN<8>  @BASEBOARD_FAB2_LIB.BASEBOARD_FAB2(SCH_1):M_D_DQS_DN<8>
  DV23  M_D_DQS_DN<7>  DDR3_DQS_DN<7>  @BASEBOARD_FAB2_LIB.BASEBOARD_FAB2(SCH_1):M_D_DQS_DN<7>
  DV29  M_D_DQS_DN<6>  DDR3_DQS_DN<6>  @BASEBOARD_FAB2_LIB.BASEBOARD_FAB2(SCH_1):M_D_DQS_DN<6>
  DV35  M_D_DQS_DN<5>  DDR3_DQS_DN<5>  @BASEBOARD_FAB2_LIB.BASEBOARD_FAB2(SCH_1):M_D_DQS_DN<5>
  EE38  M_D_DQS_DN<4>  DDR3_DQS_DN<4>  @BASEBOARD_FAB2_LIB.BASEBOARD_FAB2(SCH_1):M_D_DQS_DN<4>
  DV75  M_D_DQS_DN<3>  DDR3_DQS_DN<3>  @BASEBOARD_FAB2_LIB.BASEBOARD_FAB2(SCH_1):M_D_DQS_DN<3>
  DL82  M_D_DQS_DN<2>  DDR3_DQS_DN<2>  @BASEBOARD_FAB2_LIB.BASEBOARD_FAB2(SCH_1):M_D_DQS_DN<2>
  DN84  M_D_DQS_DN<1>  DDR3_DQS_DN<1>  @BASEBOARD_FAB2_LIB.BASEBOARD_FAB2(SCH_1):M_D_DQS_DN<1>
  DB67  M_D_DQS_DN<17>  DDR3_DQS_DN<17>  @BASEBOARD_FAB2_LIB.BASEBOARD_FAB2(SCH_1):M_D_DQS_DN<17>
  DM23  M_D_DQS_DN<16>  DDR3_DQS_DN<16>  @BASEBOARD_FAB2_LIB.BASEBOARD_FAB2(SCH_1):M_D_DQS_DN<16>
  DM29  M_D_DQS_DN<15>  DDR3_DQS_DN<15>  @BASEBOARD_FAB2_LIB.BASEBOARD_FAB2(SCH_1):M_D_DQS_DN<15>
  DP35  M_D_DQS_DN<14>  DDR3_DQS_DN<14>  @BASEBOARD_FAB2_LIB.BASEBOARD_FAB2(SCH_1):M_D_DQS_DN<14>
  EA38  M_D_DQS_DN<13>  DDR3_DQS_DN<13>  @BASEBOARD_FAB2_LIB.BASEBOARD_FAB2(SCH_1):M_D_DQS_DN<13>
  DP75  M_D_DQS_DN<12>  DDR3_DQS_DN<12>  @BASEBOARD_FAB2_LIB.BASEBOARD_FAB2(SCH_1):M_D_DQS_DN<12>
  DN80  M_D_DQS_DN<11>  DDR3_DQS_DN<11>  @BASEBOARD_FAB2_LIB.BASEBOARD_FAB2(SCH_1):M_D_DQS_DN<11>
  DM85  M_D_DQS_DN<10>  DDR3_DQS_DN<10>  @BASEBOARD_FAB2_LIB.BASEBOARD_FAB2(SCH_1):M_D_DQS_DN<10>
  CU84  M_D_DQS_DN<0>  DDR3_DQS_DN<0>  @BASEBOARD_FAB2_LIB.BASEBOARD_FAB2(SCH_1):M_D_DQS_DN<0>
  DH85  M_D_DQ<9>      DDR3_DQ<9>  @BASEBOARD_FAB2_LIB.BASEBOARD_FAB2(SCH_1):M_D_DQ<9>
  DG84  M_D_DQ<8>      DDR3_DQ<8>  @BASEBOARD_FAB2_LIB.BASEBOARD_FAB2(SCH_1):M_D_DQ<8>
  CW84  M_D_DQ<7>      DDR3_DQ<7>  @BASEBOARD_FAB2_LIB.BASEBOARD_FAB2(SCH_1):M_D_DQ<7>
  CW86  M_D_DQ<6>      DDR3_DQ<6>  @BASEBOARD_FAB2_LIB.BASEBOARD_FAB2(SCH_1):M_D_DQ<6>
  DW22  M_D_DQ<63>     DDR3_DQ<63>  @BASEBOARD_FAB2_LIB.BASEBOARD_FAB2(SCH_1):M_D_DQ<63>
  EC22  M_D_DQ<62>     DDR3_DQ<62>  @BASEBOARD_FAB2_LIB.BASEBOARD_FAB2(SCH_1):M_D_DQ<62>
  DT25  M_D_DQ<61>     DDR3_DQ<61>  @BASEBOARD_FAB2_LIB.BASEBOARD_FAB2(SCH_1):M_D_DQ<61>
  DP25  M_D_DQ<60>     DDR3_DQ<60>  @BASEBOARD_FAB2_LIB.BASEBOARD_FAB2(SCH_1):M_D_DQ<60>
  CL86  M_D_DQ<5>      DDR3_DQ<5>  @BASEBOARD_FAB2_LIB.BASEBOARD_FAB2(SCH_1):M_D_DQ<5>
  EB21  M_D_DQ<59>     DDR3_DQ<59>  @BASEBOARD_FAB2_LIB.BASEBOARD_FAB2(SCH_1):M_D_DQ<59>
  DY21  M_D_DQ<58>     DDR3_DQ<58>  @BASEBOARD_FAB2_LIB.BASEBOARD_FAB2(SCH_1):M_D_DQ<58>
  DU24  M_D_DQ<57>     DDR3_DQ<57>  @BASEBOARD_FAB2_LIB.BASEBOARD_FAB2(SCH_1):M_D_DQ<57>
  DN24  M_D_DQ<56>     DDR3_DQ<56>  @BASEBOARD_FAB2_LIB.BASEBOARD_FAB2(SCH_1):M_D_DQ<56>
  DU28  M_D_DQ<55>     DDR3_DQ<55>  @BASEBOARD_FAB2_LIB.BASEBOARD_FAB2(SCH_1):M_D_DQ<55>
  DN28  M_D_DQ<54>     DDR3_DQ<54>  @BASEBOARD_FAB2_LIB.BASEBOARD_FAB2(SCH_1):M_D_DQ<54>
  DT31  M_D_DQ<53>     DDR3_DQ<53>  @BASEBOARD_FAB2_LIB.BASEBOARD_FAB2(SCH_1):M_D_DQ<53>
  DP31  M_D_DQ<52>     DDR3_DQ<52>  @BASEBOARD_FAB2_LIB.BASEBOARD_FAB2(SCH_1):M_D_DQ<52>
  DT27  M_D_DQ<51>     DDR3_DQ<51>  @BASEBOARD_FAB2_LIB.BASEBOARD_FAB2(SCH_1):M_D_DQ<51>
  DP27  M_D_DQ<50>     DDR3_DQ<50>  @BASEBOARD_FAB2_LIB.BASEBOARD_FAB2(SCH_1):M_D_DQ<50>
  CL84  M_D_DQ<4>      DDR3_DQ<4>  @BASEBOARD_FAB2_LIB.BASEBOARD_FAB2(SCH_1):M_D_DQ<4>
  DU30  M_D_DQ<49>     DDR3_DQ<49>  @BASEBOARD_FAB2_LIB.BASEBOARD_FAB2(SCH_1):M_D_DQ<49>
  DN30  M_D_DQ<48>     DDR3_DQ<48>  @BASEBOARD_FAB2_LIB.BASEBOARD_FAB2(SCH_1):M_D_DQ<48>
  DU34  M_D_DQ<47>     DDR3_DQ<47>  @BASEBOARD_FAB2_LIB.BASEBOARD_FAB2(SCH_1):M_D_DQ<47>
  DN34  M_D_DQ<46>     DDR3_DQ<46>  @BASEBOARD_FAB2_LIB.BASEBOARD_FAB2(SCH_1):M_D_DQ<46>
  DT37  M_D_DQ<45>     DDR3_DQ<45>  @BASEBOARD_FAB2_LIB.BASEBOARD_FAB2(SCH_1):M_D_DQ<45>
  DP37  M_D_DQ<44>     DDR3_DQ<44>  @BASEBOARD_FAB2_LIB.BASEBOARD_FAB2(SCH_1):M_D_DQ<44>
  DT33  M_D_DQ<43>     DDR3_DQ<43>  @BASEBOARD_FAB2_LIB.BASEBOARD_FAB2(SCH_1):M_D_DQ<43>
  DP33  M_D_DQ<42>     DDR3_DQ<42>  @BASEBOARD_FAB2_LIB.BASEBOARD_FAB2(SCH_1):M_D_DQ<42>
  DU36  M_D_DQ<41>     DDR3_DQ<41>  @BASEBOARD_FAB2_LIB.BASEBOARD_FAB2(SCH_1):M_D_DQ<41>
  DN36  M_D_DQ<40>     DDR3_DQ<40>  @BASEBOARD_FAB2_LIB.BASEBOARD_FAB2(SCH_1):M_D_DQ<40>
  DA84  M_D_DQ<3>      DDR3_DQ<3>  @BASEBOARD_FAB2_LIB.BASEBOARD_FAB2(SCH_1):M_D_DQ<3>
  ED37  M_D_DQ<39>     DDR3_DQ<39>  @BASEBOARD_FAB2_LIB.BASEBOARD_FAB2(SCH_1):M_D_DQ<39>
  DY37  M_D_DQ<38>     DDR3_DQ<38>  @BASEBOARD_FAB2_LIB.BASEBOARD_FAB2(SCH_1):M_D_DQ<38>
  EA40  M_D_DQ<37>     DDR3_DQ<37>  @BASEBOARD_FAB2_LIB.BASEBOARD_FAB2(SCH_1):M_D_DQ<37>
  DY39  M_D_DQ<36>     DDR3_DQ<36>  @BASEBOARD_FAB2_LIB.BASEBOARD_FAB2(SCH_1):M_D_DQ<36>
  EC36  M_D_DQ<35>     DDR3_DQ<35>  @BASEBOARD_FAB2_LIB.BASEBOARD_FAB2(SCH_1):M_D_DQ<35>
  EA36  M_D_DQ<34>     DDR3_DQ<34>  @BASEBOARD_FAB2_LIB.BASEBOARD_FAB2(SCH_1):M_D_DQ<34>
  ED39  M_D_DQ<33>     DDR3_DQ<33>  @BASEBOARD_FAB2_LIB.BASEBOARD_FAB2(SCH_1):M_D_DQ<33>
  EC40  M_D_DQ<32>     DDR3_DQ<32>  @BASEBOARD_FAB2_LIB.BASEBOARD_FAB2(SCH_1):M_D_DQ<32>
  DU74  M_D_DQ<31>     DDR3_DQ<31>  @BASEBOARD_FAB2_LIB.BASEBOARD_FAB2(SCH_1):M_D_DQ<31>
  DN74  M_D_DQ<30>     DDR3_DQ<30>  @BASEBOARD_FAB2_LIB.BASEBOARD_FAB2(SCH_1):M_D_DQ<30>
  DA86  M_D_DQ<2>      DDR3_DQ<2>  @BASEBOARD_FAB2_LIB.BASEBOARD_FAB2(SCH_1):M_D_DQ<2>
  DT77  M_D_DQ<29>     DDR3_DQ<29>  @BASEBOARD_FAB2_LIB.BASEBOARD_FAB2(SCH_1):M_D_DQ<29>
  DP77  M_D_DQ<28>     DDR3_DQ<28>  @BASEBOARD_FAB2_LIB.BASEBOARD_FAB2(SCH_1):M_D_DQ<28>
  DT73  M_D_DQ<27>     DDR3_DQ<27>  @BASEBOARD_FAB2_LIB.BASEBOARD_FAB2(SCH_1):M_D_DQ<27>
  DP73  M_D_DQ<26>     DDR3_DQ<26>  @BASEBOARD_FAB2_LIB.BASEBOARD_FAB2(SCH_1):M_D_DQ<26>
  DU76  M_D_DQ<25>     DDR3_DQ<25>  @BASEBOARD_FAB2_LIB.BASEBOARD_FAB2(SCH_1):M_D_DQ<25>
  DN76  M_D_DQ<24>     DDR3_DQ<24>  @BASEBOARD_FAB2_LIB.BASEBOARD_FAB2(SCH_1):M_D_DQ<24>
  DN82  M_D_DQ<23>     DDR3_DQ<23>  @BASEBOARD_FAB2_LIB.BASEBOARD_FAB2(SCH_1):M_D_DQ<23>
  DR80  M_D_DQ<22>     DDR3_DQ<22>  @BASEBOARD_FAB2_LIB.BASEBOARD_FAB2(SCH_1):M_D_DQ<22>
  DJ80  M_D_DQ<21>     DDR3_DQ<21>  @BASEBOARD_FAB2_LIB.BASEBOARD_FAB2(SCH_1):M_D_DQ<21>
  DK79  M_D_DQ<20>     DDR3_DQ<20>  @BASEBOARD_FAB2_LIB.BASEBOARD_FAB2(SCH_1):M_D_DQ<20>
  CN86  M_D_DQ<1>      DDR3_DQ<1>  @BASEBOARD_FAB2_LIB.BASEBOARD_FAB2(SCH_1):M_D_DQ<1>
  DR82  M_D_DQ<19>     DDR3_DQ<19>  @BASEBOARD_FAB2_LIB.BASEBOARD_FAB2(SCH_1):M_D_DQ<19>
  DT81  M_D_DQ<18>     DDR3_DQ<18>  @BASEBOARD_FAB2_LIB.BASEBOARD_FAB2(SCH_1):M_D_DQ<18>
  DK81  M_D_DQ<17>     DDR3_DQ<17>  @BASEBOARD_FAB2_LIB.BASEBOARD_FAB2(SCH_1):M_D_DQ<17>
  DM79  M_D_DQ<16>     DDR3_DQ<16>  @BASEBOARD_FAB2_LIB.BASEBOARD_FAB2(SCH_1):M_D_DQ<16>
  DV85  M_D_DQ<15>     DDR3_DQ<15>  @BASEBOARD_FAB2_LIB.BASEBOARD_FAB2(SCH_1):M_D_DQ<15>
  DR84  M_D_DQ<14>     DDR3_DQ<14>  @BASEBOARD_FAB2_LIB.BASEBOARD_FAB2(SCH_1):M_D_DQ<14>
  DE84  M_D_DQ<13>     DDR3_DQ<13>  @BASEBOARD_FAB2_LIB.BASEBOARD_FAB2(SCH_1):M_D_DQ<13>
  DD85  M_D_DQ<12>     DDR3_DQ<12>  @BASEBOARD_FAB2_LIB.BASEBOARD_FAB2(SCH_1):M_D_DQ<12>
  DY83  M_D_DQ<11>     DDR3_DQ<11>  @BASEBOARD_FAB2_LIB.BASEBOARD_FAB2(SCH_1):M_D_DQ<11>
  DV83  M_D_DQ<10>     DDR3_DQ<10>  @BASEBOARD_FAB2_LIB.BASEBOARD_FAB2(SCH_1):M_D_DQ<10>
  CN84  M_D_DQ<0>      DDR3_DQ<0>  @BASEBOARD_FAB2_LIB.BASEBOARD_FAB2(SCH_1):M_D_DQ<0>
  EB45  M_D_CS_N<7>    DDR3_CS_N<7>  @BASEBOARD_FAB2_LIB.BASEBOARD_FAB2(SCH_1):M_D_CS_N<7>
  DV45  M_D_CS_N<6>    DDR3_CS_N<6>  @BASEBOARD_FAB2_LIB.BASEBOARD_FAB2(SCH_1):M_D_CS_N<6>
  EB49  M_D_CS_N<5>    DDR3_CS_N<5>  @BASEBOARD_FAB2_LIB.BASEBOARD_FAB2(SCH_1):M_D_CS_N<5>
  EB51  M_D_CS_N<4>    DDR3_CS_N<4>  @BASEBOARD_FAB2_LIB.BASEBOARD_FAB2(SCH_1):M_D_CS_N<4>
  EB47  M_D_CS_N<3>    DDR3_CS_N<3>  @BASEBOARD_FAB2_LIB.BASEBOARD_FAB2(SCH_1):M_D_CS_N<3>
  ED47  M_D_CS_N<2>    DDR3_CS_N<2>  @BASEBOARD_FAB2_LIB.BASEBOARD_FAB2(SCH_1):M_D_CS_N<2>
  ED49  M_D_CS_N<1>    DDR3_CS_N<1>  @BASEBOARD_FAB2_LIB.BASEBOARD_FAB2(SCH_1):M_D_CS_N<1>
  EF51  M_D_CS_N<0>    DDR3_CS_N<0>  @BASEBOARD_FAB2_LIB.BASEBOARD_FAB2(SCH_1):M_D_CS_N<0>
  EE56  M_D_CLK_DP<3>  DDR3_CLK_DP<3>  @BASEBOARD_FAB2_LIB.BASEBOARD_FAB2(SCH_1):M_D_CLK_DP<3>
  EA56  M_D_CLK_DP<2>  DDR3_CLK_DP<2>  @BASEBOARD_FAB2_LIB.BASEBOARD_FAB2(SCH_1):M_D_CLK_DP<2>
  EE54  M_D_CLK_DP<1>  DDR3_CLK_DP<1>  @BASEBOARD_FAB2_LIB.BASEBOARD_FAB2(SCH_1):M_D_CLK_DP<1>
  EB55  M_D_CLK_DP<0>  DDR3_CLK_DP<0>  @BASEBOARD_FAB2_LIB.BASEBOARD_FAB2(SCH_1):M_D_CLK_DP<0>
  EF57  M_D_CLK_DN<3>  DDR3_CLK_DN<3>  @BASEBOARD_FAB2_LIB.BASEBOARD_FAB2(SCH_1):M_D_CLK_DN<3>
  DW56  M_D_CLK_DN<2>  DDR3_CLK_DN<2>  @BASEBOARD_FAB2_LIB.BASEBOARD_FAB2(SCH_1):M_D_CLK_DN<2>
  EF55  M_D_CLK_DN<1>  DDR3_CLK_DN<1>  @BASEBOARD_FAB2_LIB.BASEBOARD_FAB2(SCH_1):M_D_CLK_DN<1>
  ED55  M_D_CLK_DN<0>  DDR3_CLK_DN<0>  @BASEBOARD_FAB2_LIB.BASEBOARD_FAB2(SCH_1):M_D_CLK_DN<0>
  EB63  M_D_CKE<3>     DDR3_CKE<3>  @BASEBOARD_FAB2_LIB.BASEBOARD_FAB2(SCH_1):M_D_CKE<3>
  EA62  M_D_CKE<2>     DDR3_CKE<2>  @BASEBOARD_FAB2_LIB.BASEBOARD_FAB2(SCH_1):M_D_CKE<2>
  EF63  M_D_CKE<1>     DDR3_CKE<1>  @BASEBOARD_FAB2_LIB.BASEBOARD_FAB2(SCH_1):M_D_CKE<1>
  EE62  M_D_CKE<0>     DDR3_CKE<0>  @BASEBOARD_FAB2_LIB.BASEBOARD_FAB2(SCH_1):M_D_CKE<0>
  DV47  M_D_C<2>       DDR3_CID<2>  @BASEBOARD_FAB2_LIB.BASEBOARD_FAB2(SCH_1):M_D_C<2>
  DW62  M_D_BG<1>      DDR3_BG<1>  @BASEBOARD_FAB2_LIB.BASEBOARD_FAB2(SCH_1):M_D_BG<1>
  ED61  M_D_BG<0>      DDR3_BG<0>  @BASEBOARD_FAB2_LIB.BASEBOARD_FAB2(SCH_1):M_D_BG<0>
  EA54  M_D_BA<1>      DDR3_BA<1>  @BASEBOARD_FAB2_LIB.BASEBOARD_FAB2(SCH_1):M_D_BA<1>
  EE52  M_D_BA<0>      DDR3_BA<0>  @BASEBOARD_FAB2_LIB.BASEBOARD_FAB2(SCH_1):M_D_BA<0>
  ED63  M_D_ALERT_N    DDR3_ALERT_N  @BASEBOARD_FAB2_LIB.BASEBOARD_FAB2(SCH_1):M_D_ALERT_N
  DW60  M_D_ACT_N      DDR3_ACT_N  @BASEBOARD_FAB2_LIB.BASEBOARD_FAB2(SCH_1):M_D_ACT_N

SKX_EXT_B_BGA1  I172  U5D1   [SKX_EXT_B_BGA1-IC,TBD]
  V53  M_C_PAR        DDR2_PAR  @BASEBOARD_FAB2_LIB.BASEBOARD_FAB2(SCH_1):M_C_PAR
  AB47  M_C_ODT<3>     DDR2_ODT<3>  @BASEBOARD_FAB2_LIB.BASEBOARD_FAB2(SCH_1):M_C_ODT<3>
  V49  M_C_ODT<2>     DDR2_ODT<2>  @BASEBOARD_FAB2_LIB.BASEBOARD_FAB2(SCH_1):M_C_ODT<2>
  AA48  M_C_ODT<1>     DDR2_ODT<1>  @BASEBOARD_FAB2_LIB.BASEBOARD_FAB2(SCH_1):M_C_ODT<1>
  AA50  M_C_ODT<0>     DDR2_ODT<0>  @BASEBOARD_FAB2_LIB.BASEBOARD_FAB2(SCH_1):M_C_ODT<0>
  AG58  M_C_MA<9>      DDR2_MA<9>  @BASEBOARD_FAB2_LIB.BASEBOARD_FAB2(SCH_1):M_C_MA<9>
  AD59  M_C_MA<8>      DDR2_MA<8>  @BASEBOARD_FAB2_LIB.BASEBOARD_FAB2(SCH_1):M_C_MA<8>
  AE60  M_C_MA<7>      DDR2_MA<7>  @BASEBOARD_FAB2_LIB.BASEBOARD_FAB2(SCH_1):M_C_MA<7>
  AB59  M_C_MA<6>      DDR2_MA<6>  @BASEBOARD_FAB2_LIB.BASEBOARD_FAB2(SCH_1):M_C_MA<6>
  V59  M_C_MA<5>      DDR2_MA<5>  @BASEBOARD_FAB2_LIB.BASEBOARD_FAB2(SCH_1):M_C_MA<5>
  AA58  M_C_MA<4>      DDR2_MA<4>  @BASEBOARD_FAB2_LIB.BASEBOARD_FAB2(SCH_1):M_C_MA<4>
  W58  M_C_MA<3>      DDR2_MA<3>  @BASEBOARD_FAB2_LIB.BASEBOARD_FAB2(SCH_1):M_C_MA<3>
  AD57  M_C_MA<2>      DDR2_MA<2>  @BASEBOARD_FAB2_LIB.BASEBOARD_FAB2(SCH_1):M_C_MA<2>
  AE58  M_C_MA<1>      DDR2_MA<1>  @BASEBOARD_FAB2_LIB.BASEBOARD_FAB2(SCH_1):M_C_MA<1>
  AC46  M_C_MA<17>     DDR2_MA<17>  @BASEBOARD_FAB2_LIB.BASEBOARD_FAB2(SCH_1):M_C_MA<17>
  AA52  M_C_MA<16>     DDR2_MA<16>  @BASEBOARD_FAB2_LIB.BASEBOARD_FAB2(SCH_1):M_C_MA<16>
  AE54  M_C_MA<15>     DDR2_MA<15>  @BASEBOARD_FAB2_LIB.BASEBOARD_FAB2(SCH_1):M_C_MA<15>
  W50  M_C_MA<14>     DDR2_MA<14>  @BASEBOARD_FAB2_LIB.BASEBOARD_FAB2(SCH_1):M_C_MA<14>
  AD53  M_C_MA<13>     DDR2_MA<13>  @BASEBOARD_FAB2_LIB.BASEBOARD_FAB2(SCH_1):M_C_MA<13>
  AG62  M_C_MA<12>     DDR2_MA<12>  @BASEBOARD_FAB2_LIB.BASEBOARD_FAB2(SCH_1):M_C_MA<12>
  AG60  M_C_MA<11>     DDR2_MA<11>  @BASEBOARD_FAB2_LIB.BASEBOARD_FAB2(SCH_1):M_C_MA<11>
  AD55  M_C_MA<10>     DDR2_MA<10>  @BASEBOARD_FAB2_LIB.BASEBOARD_FAB2(SCH_1):M_C_MA<10>
  AB53  M_C_MA<0>      DDR2_MA<0>  @BASEBOARD_FAB2_LIB.BASEBOARD_FAB2(SCH_1):M_C_MA<0>
  BA70  M_C_ECC<7>     DDR2_ECC<7>  @BASEBOARD_FAB2_LIB.BASEBOARD_FAB2(SCH_1):M_C_ECC<7>
  AU70  M_C_ECC<6>     DDR2_ECC<6>  @BASEBOARD_FAB2_LIB.BASEBOARD_FAB2(SCH_1):M_C_ECC<6>
  AY73  M_C_ECC<5>     DDR2_ECC<5>  @BASEBOARD_FAB2_LIB.BASEBOARD_FAB2(SCH_1):M_C_ECC<5>
  AV73  M_C_ECC<4>     DDR2_ECC<4>  @BASEBOARD_FAB2_LIB.BASEBOARD_FAB2(SCH_1):M_C_ECC<4>
  AY69  M_C_ECC<3>     DDR2_ECC<3>  @BASEBOARD_FAB2_LIB.BASEBOARD_FAB2(SCH_1):M_C_ECC<3>
  AV69  M_C_ECC<2>     DDR2_ECC<2>  @BASEBOARD_FAB2_LIB.BASEBOARD_FAB2(SCH_1):M_C_ECC<2>
  BA72  M_C_ECC<1>     DDR2_ECC<1>  @BASEBOARD_FAB2_LIB.BASEBOARD_FAB2(SCH_1):M_C_ECC<1>
  AU72  M_C_ECC<0>     DDR2_ECC<0>  @BASEBOARD_FAB2_LIB.BASEBOARD_FAB2(SCH_1):M_C_ECC<0>
  AN76  M_C_DQS_DP<9>  DDR2_DQS_DP<9>  @BASEBOARD_FAB2_LIB.BASEBOARD_FAB2(SCH_1):M_C_DQS_DP<9>
  AY71  M_C_DQS_DP<8>  DDR2_DQS_DP<8>  @BASEBOARD_FAB2_LIB.BASEBOARD_FAB2(SCH_1):M_C_DQS_DP<8>
  AG24  M_C_DQS_DP<7>  DDR2_DQS_DP<7>  @BASEBOARD_FAB2_LIB.BASEBOARD_FAB2(SCH_1):M_C_DQS_DP<7>
  AG30  M_C_DQS_DP<6>  DDR2_DQS_DP<6>  @BASEBOARD_FAB2_LIB.BASEBOARD_FAB2(SCH_1):M_C_DQS_DP<6>
  Y33  M_C_DQS_DP<5>  DDR2_DQS_DP<5>  @BASEBOARD_FAB2_LIB.BASEBOARD_FAB2(SCH_1):M_C_DQS_DP<5>
  Y39  M_C_DQS_DP<4>  DDR2_DQS_DP<4>  @BASEBOARD_FAB2_LIB.BASEBOARD_FAB2(SCH_1):M_C_DQS_DP<4>
  AR66  M_C_DQS_DP<3>  DDR2_DQS_DP<3>  @BASEBOARD_FAB2_LIB.BASEBOARD_FAB2(SCH_1):M_C_DQS_DP<3>
  W70  M_C_DQS_DP<2>  DDR2_DQS_DP<2>  @BASEBOARD_FAB2_LIB.BASEBOARD_FAB2(SCH_1):M_C_DQS_DP<2>
  AB75  M_C_DQS_DP<1>  DDR2_DQS_DP<1>  @BASEBOARD_FAB2_LIB.BASEBOARD_FAB2(SCH_1):M_C_DQS_DP<1>
  AV71  M_C_DQS_DP<17>  DDR2_DQS_DP<17>  @BASEBOARD_FAB2_LIB.BASEBOARD_FAB2(SCH_1):M_C_DQS_DP<17>
  AE24  M_C_DQS_DP<16>  DDR2_DQS_DP<16>  @BASEBOARD_FAB2_LIB.BASEBOARD_FAB2(SCH_1):M_C_DQS_DP<16>
  AE30  M_C_DQS_DP<15>  DDR2_DQS_DP<15>  @BASEBOARD_FAB2_LIB.BASEBOARD_FAB2(SCH_1):M_C_DQS_DP<15>
  V33  M_C_DQS_DP<14>  DDR2_DQS_DP<14>  @BASEBOARD_FAB2_LIB.BASEBOARD_FAB2(SCH_1):M_C_DQS_DP<14>
  V39  M_C_DQS_DP<13>  DDR2_DQS_DP<13>  @BASEBOARD_FAB2_LIB.BASEBOARD_FAB2(SCH_1):M_C_DQS_DP<13>
  AN66  M_C_DQS_DP<12>  DDR2_DQS_DP<12>  @BASEBOARD_FAB2_LIB.BASEBOARD_FAB2(SCH_1):M_C_DQS_DP<12>
  V71  M_C_DQS_DP<11>  DDR2_DQS_DP<11>  @BASEBOARD_FAB2_LIB.BASEBOARD_FAB2(SCH_1):M_C_DQS_DP<11>
  AC76  M_C_DQS_DP<10>  DDR2_DQS_DP<10>  @BASEBOARD_FAB2_LIB.BASEBOARD_FAB2(SCH_1):M_C_DQS_DP<10>
  AM75  M_C_DQS_DP<0>  DDR2_DQS_DP<0>  @BASEBOARD_FAB2_LIB.BASEBOARD_FAB2(SCH_1):M_C_DQS_DP<0>
  AP77  M_C_DQS_DN<9>  DDR2_DQS_DN<9>  @BASEBOARD_FAB2_LIB.BASEBOARD_FAB2(SCH_1):M_C_DQS_DN<9>
  BB71  M_C_DQS_DN<8>  DDR2_DQS_DN<8>  @BASEBOARD_FAB2_LIB.BASEBOARD_FAB2(SCH_1):M_C_DQS_DN<8>
  AJ24  M_C_DQS_DN<7>  DDR2_DQS_DN<7>  @BASEBOARD_FAB2_LIB.BASEBOARD_FAB2(SCH_1):M_C_DQS_DN<7>
  AJ30  M_C_DQS_DN<6>  DDR2_DQS_DN<6>  @BASEBOARD_FAB2_LIB.BASEBOARD_FAB2(SCH_1):M_C_DQS_DN<6>
  AB33  M_C_DQS_DN<5>  DDR2_DQS_DN<5>  @BASEBOARD_FAB2_LIB.BASEBOARD_FAB2(SCH_1):M_C_DQS_DN<5>
  AB39  M_C_DQS_DN<4>  DDR2_DQS_DN<4>  @BASEBOARD_FAB2_LIB.BASEBOARD_FAB2(SCH_1):M_C_DQS_DN<4>
  AU66  M_C_DQS_DN<3>  DDR2_DQS_DN<3>  @BASEBOARD_FAB2_LIB.BASEBOARD_FAB2(SCH_1):M_C_DQS_DN<3>
  Y69  M_C_DQS_DN<2>  DDR2_DQS_DN<2>  @BASEBOARD_FAB2_LIB.BASEBOARD_FAB2(SCH_1):M_C_DQS_DN<2>
  AA74  M_C_DQS_DN<1>  DDR2_DQS_DN<1>  @BASEBOARD_FAB2_LIB.BASEBOARD_FAB2(SCH_1):M_C_DQS_DN<1>
  AT71  M_C_DQS_DN<17>  DDR2_DQS_DN<17>  @BASEBOARD_FAB2_LIB.BASEBOARD_FAB2(SCH_1):M_C_DQS_DN<17>
  AC24  M_C_DQS_DN<16>  DDR2_DQS_DN<16>  @BASEBOARD_FAB2_LIB.BASEBOARD_FAB2(SCH_1):M_C_DQS_DN<16>
  AC30  M_C_DQS_DN<15>  DDR2_DQS_DN<15>  @BASEBOARD_FAB2_LIB.BASEBOARD_FAB2(SCH_1):M_C_DQS_DN<15>
  T33  M_C_DQS_DN<14>  DDR2_DQS_DN<14>  @BASEBOARD_FAB2_LIB.BASEBOARD_FAB2(SCH_1):M_C_DQS_DN<14>
  T39  M_C_DQS_DN<13>  DDR2_DQS_DN<13>  @BASEBOARD_FAB2_LIB.BASEBOARD_FAB2(SCH_1):M_C_DQS_DN<13>
  AL66  M_C_DQS_DN<12>  DDR2_DQS_DN<12>  @BASEBOARD_FAB2_LIB.BASEBOARD_FAB2(SCH_1):M_C_DQS_DN<12>
  U72  M_C_DQS_DN<11>  DDR2_DQS_DN<11>  @BASEBOARD_FAB2_LIB.BASEBOARD_FAB2(SCH_1):M_C_DQS_DN<11>
  AD77  M_C_DQS_DN<10>  DDR2_DQS_DN<10>  @BASEBOARD_FAB2_LIB.BASEBOARD_FAB2(SCH_1):M_C_DQS_DN<10>
  AL74  M_C_DQS_DN<0>  DDR2_DQS_DN<0>  @BASEBOARD_FAB2_LIB.BASEBOARD_FAB2(SCH_1):M_C_DQS_DN<0>
  AC74  M_C_DQ<9>      DDR2_DQ<9>  @BASEBOARD_FAB2_LIB.BASEBOARD_FAB2(SCH_1):M_C_DQ<9>
  AE76  M_C_DQ<8>      DDR2_DQ<8>  @BASEBOARD_FAB2_LIB.BASEBOARD_FAB2(SCH_1):M_C_DQ<8>
  AK75  M_C_DQ<7>      DDR2_DQ<7>  @BASEBOARD_FAB2_LIB.BASEBOARD_FAB2(SCH_1):M_C_DQ<7>
  AM77  M_C_DQ<6>      DDR2_DQ<6>  @BASEBOARD_FAB2_LIB.BASEBOARD_FAB2(SCH_1):M_C_DQ<6>
  AH23  M_C_DQ<63>     DDR2_DQ<63>  @BASEBOARD_FAB2_LIB.BASEBOARD_FAB2(SCH_1):M_C_DQ<63>
  AD23  M_C_DQ<62>     DDR2_DQ<62>  @BASEBOARD_FAB2_LIB.BASEBOARD_FAB2(SCH_1):M_C_DQ<62>
  AG26  M_C_DQ<61>     DDR2_DQ<61>  @BASEBOARD_FAB2_LIB.BASEBOARD_FAB2(SCH_1):M_C_DQ<61>
  AE26  M_C_DQ<60>     DDR2_DQ<60>  @BASEBOARD_FAB2_LIB.BASEBOARD_FAB2(SCH_1):M_C_DQ<60>
  AR74  M_C_DQ<5>      DDR2_DQ<5>  @BASEBOARD_FAB2_LIB.BASEBOARD_FAB2(SCH_1):M_C_DQ<5>
  AG22  M_C_DQ<59>     DDR2_DQ<59>  @BASEBOARD_FAB2_LIB.BASEBOARD_FAB2(SCH_1):M_C_DQ<59>
  AE22  M_C_DQ<58>     DDR2_DQ<58>  @BASEBOARD_FAB2_LIB.BASEBOARD_FAB2(SCH_1):M_C_DQ<58>
  AH25  M_C_DQ<57>     DDR2_DQ<57>  @BASEBOARD_FAB2_LIB.BASEBOARD_FAB2(SCH_1):M_C_DQ<57>
  AD25  M_C_DQ<56>     DDR2_DQ<56>  @BASEBOARD_FAB2_LIB.BASEBOARD_FAB2(SCH_1):M_C_DQ<56>
  AH29  M_C_DQ<55>     DDR2_DQ<55>  @BASEBOARD_FAB2_LIB.BASEBOARD_FAB2(SCH_1):M_C_DQ<55>
  AD29  M_C_DQ<54>     DDR2_DQ<54>  @BASEBOARD_FAB2_LIB.BASEBOARD_FAB2(SCH_1):M_C_DQ<54>
  AG32  M_C_DQ<53>     DDR2_DQ<53>  @BASEBOARD_FAB2_LIB.BASEBOARD_FAB2(SCH_1):M_C_DQ<53>
  AE32  M_C_DQ<52>     DDR2_DQ<52>  @BASEBOARD_FAB2_LIB.BASEBOARD_FAB2(SCH_1):M_C_DQ<52>
  AG28  M_C_DQ<51>     DDR2_DQ<51>  @BASEBOARD_FAB2_LIB.BASEBOARD_FAB2(SCH_1):M_C_DQ<51>
  AE28  M_C_DQ<50>     DDR2_DQ<50>  @BASEBOARD_FAB2_LIB.BASEBOARD_FAB2(SCH_1):M_C_DQ<50>
  AT75  M_C_DQ<4>      DDR2_DQ<4>  @BASEBOARD_FAB2_LIB.BASEBOARD_FAB2(SCH_1):M_C_DQ<4>
  AH31  M_C_DQ<49>     DDR2_DQ<49>  @BASEBOARD_FAB2_LIB.BASEBOARD_FAB2(SCH_1):M_C_DQ<49>
  AD31  M_C_DQ<48>     DDR2_DQ<48>  @BASEBOARD_FAB2_LIB.BASEBOARD_FAB2(SCH_1):M_C_DQ<48>
  AA32  M_C_DQ<47>     DDR2_DQ<47>  @BASEBOARD_FAB2_LIB.BASEBOARD_FAB2(SCH_1):M_C_DQ<47>
  U32  M_C_DQ<46>     DDR2_DQ<46>  @BASEBOARD_FAB2_LIB.BASEBOARD_FAB2(SCH_1):M_C_DQ<46>
  Y35  M_C_DQ<45>     DDR2_DQ<45>  @BASEBOARD_FAB2_LIB.BASEBOARD_FAB2(SCH_1):M_C_DQ<45>
  V35  M_C_DQ<44>     DDR2_DQ<44>  @BASEBOARD_FAB2_LIB.BASEBOARD_FAB2(SCH_1):M_C_DQ<44>
  Y31  M_C_DQ<43>     DDR2_DQ<43>  @BASEBOARD_FAB2_LIB.BASEBOARD_FAB2(SCH_1):M_C_DQ<43>
  V31  M_C_DQ<42>     DDR2_DQ<42>  @BASEBOARD_FAB2_LIB.BASEBOARD_FAB2(SCH_1):M_C_DQ<42>
  AA34  M_C_DQ<41>     DDR2_DQ<41>  @BASEBOARD_FAB2_LIB.BASEBOARD_FAB2(SCH_1):M_C_DQ<41>
  U34  M_C_DQ<40>     DDR2_DQ<40>  @BASEBOARD_FAB2_LIB.BASEBOARD_FAB2(SCH_1):M_C_DQ<40>
  AJ76  M_C_DQ<3>      DDR2_DQ<3>  @BASEBOARD_FAB2_LIB.BASEBOARD_FAB2(SCH_1):M_C_DQ<3>
  AA38  M_C_DQ<39>     DDR2_DQ<39>  @BASEBOARD_FAB2_LIB.BASEBOARD_FAB2(SCH_1):M_C_DQ<39>
  U38  M_C_DQ<38>     DDR2_DQ<38>  @BASEBOARD_FAB2_LIB.BASEBOARD_FAB2(SCH_1):M_C_DQ<38>
  Y41  M_C_DQ<37>     DDR2_DQ<37>  @BASEBOARD_FAB2_LIB.BASEBOARD_FAB2(SCH_1):M_C_DQ<37>
  V41  M_C_DQ<36>     DDR2_DQ<36>  @BASEBOARD_FAB2_LIB.BASEBOARD_FAB2(SCH_1):M_C_DQ<36>
  Y37  M_C_DQ<35>     DDR2_DQ<35>  @BASEBOARD_FAB2_LIB.BASEBOARD_FAB2(SCH_1):M_C_DQ<35>
  V37  M_C_DQ<34>     DDR2_DQ<34>  @BASEBOARD_FAB2_LIB.BASEBOARD_FAB2(SCH_1):M_C_DQ<34>
  AA40  M_C_DQ<33>     DDR2_DQ<33>  @BASEBOARD_FAB2_LIB.BASEBOARD_FAB2(SCH_1):M_C_DQ<33>
  U40  M_C_DQ<32>     DDR2_DQ<32>  @BASEBOARD_FAB2_LIB.BASEBOARD_FAB2(SCH_1):M_C_DQ<32>
  AT65  M_C_DQ<31>     DDR2_DQ<31>  @BASEBOARD_FAB2_LIB.BASEBOARD_FAB2(SCH_1):M_C_DQ<31>
  AM65  M_C_DQ<30>     DDR2_DQ<30>  @BASEBOARD_FAB2_LIB.BASEBOARD_FAB2(SCH_1):M_C_DQ<30>
  AK77  M_C_DQ<2>      DDR2_DQ<2>  @BASEBOARD_FAB2_LIB.BASEBOARD_FAB2(SCH_1):M_C_DQ<2>
  AR68  M_C_DQ<29>     DDR2_DQ<29>  @BASEBOARD_FAB2_LIB.BASEBOARD_FAB2(SCH_1):M_C_DQ<29>
  AN68  M_C_DQ<28>     DDR2_DQ<28>  @BASEBOARD_FAB2_LIB.BASEBOARD_FAB2(SCH_1):M_C_DQ<28>
  AR64  M_C_DQ<27>     DDR2_DQ<27>  @BASEBOARD_FAB2_LIB.BASEBOARD_FAB2(SCH_1):M_C_DQ<27>
  AN64  M_C_DQ<26>     DDR2_DQ<26>  @BASEBOARD_FAB2_LIB.BASEBOARD_FAB2(SCH_1):M_C_DQ<26>
  AT67  M_C_DQ<25>     DDR2_DQ<25>  @BASEBOARD_FAB2_LIB.BASEBOARD_FAB2(SCH_1):M_C_DQ<25>
  AM67  M_C_DQ<24>     DDR2_DQ<24>  @BASEBOARD_FAB2_LIB.BASEBOARD_FAB2(SCH_1):M_C_DQ<24>
  V69  M_C_DQ<23>     DDR2_DQ<23>  @BASEBOARD_FAB2_LIB.BASEBOARD_FAB2(SCH_1):M_C_DQ<23>
  T71  M_C_DQ<22>     DDR2_DQ<22>  @BASEBOARD_FAB2_LIB.BASEBOARD_FAB2(SCH_1):M_C_DQ<22>
  AB71  M_C_DQ<21>     DDR2_DQ<21>  @BASEBOARD_FAB2_LIB.BASEBOARD_FAB2(SCH_1):M_C_DQ<21>
  AA72  M_C_DQ<20>     DDR2_DQ<20>  @BASEBOARD_FAB2_LIB.BASEBOARD_FAB2(SCH_1):M_C_DQ<20>
  AN74  M_C_DQ<1>      DDR2_DQ<1>  @BASEBOARD_FAB2_LIB.BASEBOARD_FAB2(SCH_1):M_C_DQ<1>
  T69  M_C_DQ<19>     DDR2_DQ<19>  @BASEBOARD_FAB2_LIB.BASEBOARD_FAB2(SCH_1):M_C_DQ<19>
  R70  M_C_DQ<18>     DDR2_DQ<18>  @BASEBOARD_FAB2_LIB.BASEBOARD_FAB2(SCH_1):M_C_DQ<18>
  AA70  M_C_DQ<17>     DDR2_DQ<17>  @BASEBOARD_FAB2_LIB.BASEBOARD_FAB2(SCH_1):M_C_DQ<17>
  W72  M_C_DQ<16>     DDR2_DQ<16>  @BASEBOARD_FAB2_LIB.BASEBOARD_FAB2(SCH_1):M_C_DQ<16>
  Y75  M_C_DQ<15>     DDR2_DQ<15>  @BASEBOARD_FAB2_LIB.BASEBOARD_FAB2(SCH_1):M_C_DQ<15>
  AB77  M_C_DQ<14>     DDR2_DQ<14>  @BASEBOARD_FAB2_LIB.BASEBOARD_FAB2(SCH_1):M_C_DQ<14>
  AE74  M_C_DQ<13>     DDR2_DQ<13>  @BASEBOARD_FAB2_LIB.BASEBOARD_FAB2(SCH_1):M_C_DQ<13>
  AF75  M_C_DQ<12>     DDR2_DQ<12>  @BASEBOARD_FAB2_LIB.BASEBOARD_FAB2(SCH_1):M_C_DQ<12>
  W76  M_C_DQ<11>     DDR2_DQ<11>  @BASEBOARD_FAB2_LIB.BASEBOARD_FAB2(SCH_1):M_C_DQ<11>
  Y77  M_C_DQ<10>     DDR2_DQ<10>  @BASEBOARD_FAB2_LIB.BASEBOARD_FAB2(SCH_1):M_C_DQ<10>
  AR76  M_C_DQ<0>      DDR2_DQ<0>  @BASEBOARD_FAB2_LIB.BASEBOARD_FAB2(SCH_1):M_C_DQ<0>
  V45  M_C_CS_N<7>    DDR2_CS_N<7>  @BASEBOARD_FAB2_LIB.BASEBOARD_FAB2(SCH_1):M_C_CS_N<7>
  T45  M_C_CS_N<6>    DDR2_CS_N<6>  @BASEBOARD_FAB2_LIB.BASEBOARD_FAB2(SCH_1):M_C_CS_N<6>
  W48  M_C_CS_N<5>    DDR2_CS_N<5>  @BASEBOARD_FAB2_LIB.BASEBOARD_FAB2(SCH_1):M_C_CS_N<5>
  AB51  M_C_CS_N<4>    DDR2_CS_N<4>  @BASEBOARD_FAB2_LIB.BASEBOARD_FAB2(SCH_1):M_C_CS_N<4>
  AA46  M_C_CS_N<3>    DDR2_CS_N<3>  @BASEBOARD_FAB2_LIB.BASEBOARD_FAB2(SCH_1):M_C_CS_N<3>
  W46  M_C_CS_N<2>    DDR2_CS_N<2>  @BASEBOARD_FAB2_LIB.BASEBOARD_FAB2(SCH_1):M_C_CS_N<2>
  AB49  M_C_CS_N<1>    DDR2_CS_N<1>  @BASEBOARD_FAB2_LIB.BASEBOARD_FAB2(SCH_1):M_C_CS_N<1>
  V51  M_C_CS_N<0>    DDR2_CS_N<0>  @BASEBOARD_FAB2_LIB.BASEBOARD_FAB2(SCH_1):M_C_CS_N<0>
  V57  M_C_CLK_DP<3>  DDR2_CLK_DP<3>  @BASEBOARD_FAB2_LIB.BASEBOARD_FAB2(SCH_1):M_C_CLK_DP<3>
  AB57  M_C_CLK_DP<2>  DDR2_CLK_DP<2>  @BASEBOARD_FAB2_LIB.BASEBOARD_FAB2(SCH_1):M_C_CLK_DP<2>
  V55  M_C_CLK_DP<1>  DDR2_CLK_DP<1>  @BASEBOARD_FAB2_LIB.BASEBOARD_FAB2(SCH_1):M_C_CLK_DP<1>
  AB55  M_C_CLK_DP<0>  DDR2_CLK_DP<0>  @BASEBOARD_FAB2_LIB.BASEBOARD_FAB2(SCH_1):M_C_CLK_DP<0>
  W56  M_C_CLK_DN<3>  DDR2_CLK_DN<3>  @BASEBOARD_FAB2_LIB.BASEBOARD_FAB2(SCH_1):M_C_CLK_DN<3>
  AA56  M_C_CLK_DN<2>  DDR2_CLK_DN<2>  @BASEBOARD_FAB2_LIB.BASEBOARD_FAB2(SCH_1):M_C_CLK_DN<2>
  W54  M_C_CLK_DN<1>  DDR2_CLK_DN<1>  @BASEBOARD_FAB2_LIB.BASEBOARD_FAB2(SCH_1):M_C_CLK_DN<1>
  AA54  M_C_CLK_DN<0>  DDR2_CLK_DN<0>  @BASEBOARD_FAB2_LIB.BASEBOARD_FAB2(SCH_1):M_C_CLK_DN<0>
  AB63  M_C_CKE<3>     DDR2_CKE<3>  @BASEBOARD_FAB2_LIB.BASEBOARD_FAB2(SCH_1):M_C_CKE<3>
  V63  M_C_CKE<2>     DDR2_CKE<2>  @BASEBOARD_FAB2_LIB.BASEBOARD_FAB2(SCH_1):M_C_CKE<2>
  AD63  M_C_CKE<1>     DDR2_CKE<1>  @BASEBOARD_FAB2_LIB.BASEBOARD_FAB2(SCH_1):M_C_CKE<1>
  AA62  M_C_CKE<0>     DDR2_CKE<0>  @BASEBOARD_FAB2_LIB.BASEBOARD_FAB2(SCH_1):M_C_CKE<0>
  AB45  M_C_C<2>       DDR2_CID<2>  @BASEBOARD_FAB2_LIB.BASEBOARD_FAB2(SCH_1):M_C_C<2>
  AE62  M_C_BG<1>      DDR2_BG<1>  @BASEBOARD_FAB2_LIB.BASEBOARD_FAB2(SCH_1):M_C_BG<1>
  AA60  M_C_BG<0>      DDR2_BG<0>  @BASEBOARD_FAB2_LIB.BASEBOARD_FAB2(SCH_1):M_C_BG<0>
  AE56  M_C_BA<1>      DDR2_BA<1>  @BASEBOARD_FAB2_LIB.BASEBOARD_FAB2(SCH_1):M_C_BA<1>
  W52  M_C_BA<0>      DDR2_BA<0>  @BASEBOARD_FAB2_LIB.BASEBOARD_FAB2(SCH_1):M_C_BA<0>
  AD61  M_C_ALERT_N    DDR2_ALERT_N  @BASEBOARD_FAB2_LIB.BASEBOARD_FAB2(SCH_1):M_C_ALERT_N
  AB61  M_C_ACT_N      DDR2_ACT_N  @BASEBOARD_FAB2_LIB.BASEBOARD_FAB2(SCH_1):M_C_ACT_N

SKX_EXT_B_BGA1  I172  U5D1   [SKX_EXT_B_BGA1-IC,TBD]
  K53  M_B_PAR        DDR1_PAR  @BASEBOARD_FAB2_LIB.BASEBOARD_FAB2(SCH_1):M_B_PAR
  T47  M_B_ODT<3>     DDR1_ODT<3>  @BASEBOARD_FAB2_LIB.BASEBOARD_FAB2(SCH_1):M_B_ODT<3>
  M49  M_B_ODT<2>     DDR1_ODT<2>  @BASEBOARD_FAB2_LIB.BASEBOARD_FAB2(SCH_1):M_B_ODT<2>
  R48  M_B_ODT<1>     DDR1_ODT<1>  @BASEBOARD_FAB2_LIB.BASEBOARD_FAB2(SCH_1):M_B_ODT<1>
  N50  M_B_ODT<0>     DDR1_ODT<0>  @BASEBOARD_FAB2_LIB.BASEBOARD_FAB2(SCH_1):M_B_ODT<0>
  K59  M_B_MA<9>      DDR1_MA<9>  @BASEBOARD_FAB2_LIB.BASEBOARD_FAB2(SCH_1):M_B_MA<9>
  W60  M_B_MA<8>      DDR1_MA<8>  @BASEBOARD_FAB2_LIB.BASEBOARD_FAB2(SCH_1):M_B_MA<8>
  V61  M_B_MA<7>      DDR1_MA<7>  @BASEBOARD_FAB2_LIB.BASEBOARD_FAB2(SCH_1):M_B_MA<7>
  T59  M_B_MA<6>      DDR1_MA<6>  @BASEBOARD_FAB2_LIB.BASEBOARD_FAB2(SCH_1):M_B_MA<6>
  R58  M_B_MA<5>      DDR1_MA<5>  @BASEBOARD_FAB2_LIB.BASEBOARD_FAB2(SCH_1):M_B_MA<5>
  M59  M_B_MA<4>      DDR1_MA<4>  @BASEBOARD_FAB2_LIB.BASEBOARD_FAB2(SCH_1):M_B_MA<4>
  N58  M_B_MA<3>      DDR1_MA<3>  @BASEBOARD_FAB2_LIB.BASEBOARD_FAB2(SCH_1):M_B_MA<3>
  K57  M_B_MA<2>      DDR1_MA<2>  @BASEBOARD_FAB2_LIB.BASEBOARD_FAB2(SCH_1):M_B_MA<2>
  J58  M_B_MA<1>      DDR1_MA<1>  @BASEBOARD_FAB2_LIB.BASEBOARD_FAB2(SCH_1):M_B_MA<1>
  N48  M_B_MA<17>     DDR1_MA<17>  @BASEBOARD_FAB2_LIB.BASEBOARD_FAB2(SCH_1):M_B_MA<17>
  R52  M_B_MA<16>     DDR1_MA<16>  @BASEBOARD_FAB2_LIB.BASEBOARD_FAB2(SCH_1):M_B_MA<16>
  N52  M_B_MA<15>     DDR1_MA<15>  @BASEBOARD_FAB2_LIB.BASEBOARD_FAB2(SCH_1):M_B_MA<15>
  T51  M_B_MA<14>     DDR1_MA<14>  @BASEBOARD_FAB2_LIB.BASEBOARD_FAB2(SCH_1):M_B_MA<14>
  M51  M_B_MA<13>     DDR1_MA<13>  @BASEBOARD_FAB2_LIB.BASEBOARD_FAB2(SCH_1):M_B_MA<13>
  T61  M_B_MA<12>     DDR1_MA<12>  @BASEBOARD_FAB2_LIB.BASEBOARD_FAB2(SCH_1):M_B_MA<12>
  R60  M_B_MA<11>     DDR1_MA<11>  @BASEBOARD_FAB2_LIB.BASEBOARD_FAB2(SCH_1):M_B_MA<11>
  M55  M_B_MA<10>     DDR1_MA<10>  @BASEBOARD_FAB2_LIB.BASEBOARD_FAB2(SCH_1):M_B_MA<10>
  J52  M_B_MA<0>      DDR1_MA<0>  @BASEBOARD_FAB2_LIB.BASEBOARD_FAB2(SCH_1):M_B_MA<0>
  M67  M_B_ECC<7>     DDR1_ECC<7>  @BASEBOARD_FAB2_LIB.BASEBOARD_FAB2(SCH_1):M_B_ECC<7>
  H67  M_B_ECC<6>     DDR1_ECC<6>  @BASEBOARD_FAB2_LIB.BASEBOARD_FAB2(SCH_1):M_B_ECC<6>
  M69  M_B_ECC<5>     DDR1_ECC<5>  @BASEBOARD_FAB2_LIB.BASEBOARD_FAB2(SCH_1):M_B_ECC<5>
  L70  M_B_ECC<4>     DDR1_ECC<4>  @BASEBOARD_FAB2_LIB.BASEBOARD_FAB2(SCH_1):M_B_ECC<4>
  L66  M_B_ECC<3>     DDR1_ECC<3>  @BASEBOARD_FAB2_LIB.BASEBOARD_FAB2(SCH_1):M_B_ECC<3>
  J66  M_B_ECC<2>     DDR1_ECC<2>  @BASEBOARD_FAB2_LIB.BASEBOARD_FAB2(SCH_1):M_B_ECC<2>
  H69  M_B_ECC<1>     DDR1_ECC<1>  @BASEBOARD_FAB2_LIB.BASEBOARD_FAB2(SCH_1):M_B_ECC<1>
  J70  M_B_ECC<0>     DDR1_ECC<0>  @BASEBOARD_FAB2_LIB.BASEBOARD_FAB2(SCH_1):M_B_ECC<0>
  AT81  M_B_DQS_DP<9>  DDR1_DQS_DP<9>  @BASEBOARD_FAB2_LIB.BASEBOARD_FAB2(SCH_1):M_B_DQS_DP<9>
  L68  M_B_DQS_DP<8>  DDR1_DQS_DP<8>  @BASEBOARD_FAB2_LIB.BASEBOARD_FAB2(SCH_1):M_B_DQS_DP<8>
  Y27  M_B_DQS_DP<7>  DDR1_DQS_DP<7>  @BASEBOARD_FAB2_LIB.BASEBOARD_FAB2(SCH_1):M_B_DQS_DP<7>
  E28  M_B_DQS_DP<6>  DDR1_DQS_DP<6>  @BASEBOARD_FAB2_LIB.BASEBOARD_FAB2(SCH_1):M_B_DQS_DP<6>
  E34  M_B_DQS_DP<5>  DDR1_DQS_DP<5>  @BASEBOARD_FAB2_LIB.BASEBOARD_FAB2(SCH_1):M_B_DQS_DP<5>
  R42  M_B_DQS_DP<4>  DDR1_DQS_DP<4>  @BASEBOARD_FAB2_LIB.BASEBOARD_FAB2(SCH_1):M_B_DQS_DP<4>
  F73  M_B_DQS_DP<3>  DDR1_DQS_DP<3>  @BASEBOARD_FAB2_LIB.BASEBOARD_FAB2(SCH_1):M_B_DQS_DP<3>
  H79  M_B_DQS_DP<2>  DDR1_DQS_DP<2>  @BASEBOARD_FAB2_LIB.BASEBOARD_FAB2(SCH_1):M_B_DQS_DP<2>
  AE80  M_B_DQS_DP<1>  DDR1_DQS_DP<1>  @BASEBOARD_FAB2_LIB.BASEBOARD_FAB2(SCH_1):M_B_DQS_DP<1>
  J68  M_B_DQS_DP<17>  DDR1_DQS_DP<17>  @BASEBOARD_FAB2_LIB.BASEBOARD_FAB2(SCH_1):M_B_DQS_DP<17>
  V27  M_B_DQS_DP<16>  DDR1_DQS_DP<16>  @BASEBOARD_FAB2_LIB.BASEBOARD_FAB2(SCH_1):M_B_DQS_DP<16>
  C28  M_B_DQS_DP<15>  DDR1_DQS_DP<15>  @BASEBOARD_FAB2_LIB.BASEBOARD_FAB2(SCH_1):M_B_DQS_DP<15>
  C34  M_B_DQS_DP<14>  DDR1_DQS_DP<14>  @BASEBOARD_FAB2_LIB.BASEBOARD_FAB2(SCH_1):M_B_DQS_DP<14>
  L42  M_B_DQS_DP<13>  DDR1_DQS_DP<13>  @BASEBOARD_FAB2_LIB.BASEBOARD_FAB2(SCH_1):M_B_DQS_DP<13>
  D73  M_B_DQS_DP<12>  DDR1_DQS_DP<12>  @BASEBOARD_FAB2_LIB.BASEBOARD_FAB2(SCH_1):M_B_DQS_DP<12>
  F79  M_B_DQS_DP<11>  DDR1_DQS_DP<11>  @BASEBOARD_FAB2_LIB.BASEBOARD_FAB2(SCH_1):M_B_DQS_DP<11>
  AF81  M_B_DQS_DP<10>  DDR1_DQS_DP<10>  @BASEBOARD_FAB2_LIB.BASEBOARD_FAB2(SCH_1):M_B_DQS_DP<10>
  AR80  M_B_DQS_DP<0>  DDR1_DQS_DP<0>  @BASEBOARD_FAB2_LIB.BASEBOARD_FAB2(SCH_1):M_B_DQS_DP<0>
  AU82  M_B_DQS_DN<9>  DDR1_DQS_DN<9>  @BASEBOARD_FAB2_LIB.BASEBOARD_FAB2(SCH_1):M_B_DQS_DN<9>
  N68  M_B_DQS_DN<8>  DDR1_DQS_DN<8>  @BASEBOARD_FAB2_LIB.BASEBOARD_FAB2(SCH_1):M_B_DQS_DN<8>
  AB27  M_B_DQS_DN<7>  DDR1_DQS_DN<7>  @BASEBOARD_FAB2_LIB.BASEBOARD_FAB2(SCH_1):M_B_DQS_DN<7>
  G28  M_B_DQS_DN<6>  DDR1_DQS_DN<6>  @BASEBOARD_FAB2_LIB.BASEBOARD_FAB2(SCH_1):M_B_DQS_DN<6>
  G34  M_B_DQS_DN<5>  DDR1_DQS_DN<5>  @BASEBOARD_FAB2_LIB.BASEBOARD_FAB2(SCH_1):M_B_DQS_DN<5>
  N42  M_B_DQS_DN<4>  DDR1_DQS_DN<4>  @BASEBOARD_FAB2_LIB.BASEBOARD_FAB2(SCH_1):M_B_DQS_DN<4>
  H73  M_B_DQS_DN<3>  DDR1_DQS_DN<3>  @BASEBOARD_FAB2_LIB.BASEBOARD_FAB2(SCH_1):M_B_DQS_DN<3>
  K79  M_B_DQS_DN<2>  DDR1_DQS_DN<2>  @BASEBOARD_FAB2_LIB.BASEBOARD_FAB2(SCH_1):M_B_DQS_DN<2>
  AD79  M_B_DQS_DN<1>  DDR1_DQS_DN<1>  @BASEBOARD_FAB2_LIB.BASEBOARD_FAB2(SCH_1):M_B_DQS_DN<1>
  G68  M_B_DQS_DN<17>  DDR1_DQS_DN<17>  @BASEBOARD_FAB2_LIB.BASEBOARD_FAB2(SCH_1):M_B_DQS_DN<17>
  T27  M_B_DQS_DN<16>  DDR1_DQS_DN<16>  @BASEBOARD_FAB2_LIB.BASEBOARD_FAB2(SCH_1):M_B_DQS_DN<16>
  A28  M_B_DQS_DN<15>  DDR1_DQS_DN<15>  @BASEBOARD_FAB2_LIB.BASEBOARD_FAB2(SCH_1):M_B_DQS_DN<15>
  A34  M_B_DQS_DN<14>  DDR1_DQS_DN<14>  @BASEBOARD_FAB2_LIB.BASEBOARD_FAB2(SCH_1):M_B_DQS_DN<14>
  J42  M_B_DQS_DN<13>  DDR1_DQS_DN<13>  @BASEBOARD_FAB2_LIB.BASEBOARD_FAB2(SCH_1):M_B_DQS_DN<13>
  B73  M_B_DQS_DN<12>  DDR1_DQS_DN<12>  @BASEBOARD_FAB2_LIB.BASEBOARD_FAB2(SCH_1):M_B_DQS_DN<12>
  D79  M_B_DQS_DN<11>  DDR1_DQS_DN<11>  @BASEBOARD_FAB2_LIB.BASEBOARD_FAB2(SCH_1):M_B_DQS_DN<11>
  AG82  M_B_DQS_DN<10>  DDR1_DQS_DN<10>  @BASEBOARD_FAB2_LIB.BASEBOARD_FAB2(SCH_1):M_B_DQS_DN<10>
  AP79  M_B_DQS_DN<0>  DDR1_DQS_DN<0>  @BASEBOARD_FAB2_LIB.BASEBOARD_FAB2(SCH_1):M_B_DQS_DN<0>
  AF79  M_B_DQ<9>      DDR1_DQ<9>  @BASEBOARD_FAB2_LIB.BASEBOARD_FAB2(SCH_1):M_B_DQ<9>
  AH81  M_B_DQ<8>      DDR1_DQ<8>  @BASEBOARD_FAB2_LIB.BASEBOARD_FAB2(SCH_1):M_B_DQ<8>
  AN80  M_B_DQ<7>      DDR1_DQ<7>  @BASEBOARD_FAB2_LIB.BASEBOARD_FAB2(SCH_1):M_B_DQ<7>
  AR82  M_B_DQ<6>      DDR1_DQ<6>  @BASEBOARD_FAB2_LIB.BASEBOARD_FAB2(SCH_1):M_B_DQ<6>
  AA26  M_B_DQ<63>     DDR1_DQ<63>  @BASEBOARD_FAB2_LIB.BASEBOARD_FAB2(SCH_1):M_B_DQ<63>
  U26  M_B_DQ<62>     DDR1_DQ<62>  @BASEBOARD_FAB2_LIB.BASEBOARD_FAB2(SCH_1):M_B_DQ<62>
  Y29  M_B_DQ<61>     DDR1_DQ<61>  @BASEBOARD_FAB2_LIB.BASEBOARD_FAB2(SCH_1):M_B_DQ<61>
  V29  M_B_DQ<60>     DDR1_DQ<60>  @BASEBOARD_FAB2_LIB.BASEBOARD_FAB2(SCH_1):M_B_DQ<60>
  AV79  M_B_DQ<5>      DDR1_DQ<5>  @BASEBOARD_FAB2_LIB.BASEBOARD_FAB2(SCH_1):M_B_DQ<5>
  Y25  M_B_DQ<59>     DDR1_DQ<59>  @BASEBOARD_FAB2_LIB.BASEBOARD_FAB2(SCH_1):M_B_DQ<59>
  V25  M_B_DQ<58>     DDR1_DQ<58>  @BASEBOARD_FAB2_LIB.BASEBOARD_FAB2(SCH_1):M_B_DQ<58>
  AA28  M_B_DQ<57>     DDR1_DQ<57>  @BASEBOARD_FAB2_LIB.BASEBOARD_FAB2(SCH_1):M_B_DQ<57>
  U28  M_B_DQ<56>     DDR1_DQ<56>  @BASEBOARD_FAB2_LIB.BASEBOARD_FAB2(SCH_1):M_B_DQ<56>
  F27  M_B_DQ<55>     DDR1_DQ<55>  @BASEBOARD_FAB2_LIB.BASEBOARD_FAB2(SCH_1):M_B_DQ<55>
  B27  M_B_DQ<54>     DDR1_DQ<54>  @BASEBOARD_FAB2_LIB.BASEBOARD_FAB2(SCH_1):M_B_DQ<54>
  F29  M_B_DQ<53>     DDR1_DQ<53>  @BASEBOARD_FAB2_LIB.BASEBOARD_FAB2(SCH_1):M_B_DQ<53>
  E30  M_B_DQ<52>     DDR1_DQ<52>  @BASEBOARD_FAB2_LIB.BASEBOARD_FAB2(SCH_1):M_B_DQ<52>
  E26  M_B_DQ<51>     DDR1_DQ<51>  @BASEBOARD_FAB2_LIB.BASEBOARD_FAB2(SCH_1):M_B_DQ<51>
  C26  M_B_DQ<50>     DDR1_DQ<50>  @BASEBOARD_FAB2_LIB.BASEBOARD_FAB2(SCH_1):M_B_DQ<50>
  AW80  M_B_DQ<4>      DDR1_DQ<4>  @BASEBOARD_FAB2_LIB.BASEBOARD_FAB2(SCH_1):M_B_DQ<4>
  B29  M_B_DQ<49>     DDR1_DQ<49>  @BASEBOARD_FAB2_LIB.BASEBOARD_FAB2(SCH_1):M_B_DQ<49>
  C30  M_B_DQ<48>     DDR1_DQ<48>  @BASEBOARD_FAB2_LIB.BASEBOARD_FAB2(SCH_1):M_B_DQ<48>
  F33  M_B_DQ<47>     DDR1_DQ<47>  @BASEBOARD_FAB2_LIB.BASEBOARD_FAB2(SCH_1):M_B_DQ<47>
  B33  M_B_DQ<46>     DDR1_DQ<46>  @BASEBOARD_FAB2_LIB.BASEBOARD_FAB2(SCH_1):M_B_DQ<46>
  F35  M_B_DQ<45>     DDR1_DQ<45>  @BASEBOARD_FAB2_LIB.BASEBOARD_FAB2(SCH_1):M_B_DQ<45>
  E36  M_B_DQ<44>     DDR1_DQ<44>  @BASEBOARD_FAB2_LIB.BASEBOARD_FAB2(SCH_1):M_B_DQ<44>
  E32  M_B_DQ<43>     DDR1_DQ<43>  @BASEBOARD_FAB2_LIB.BASEBOARD_FAB2(SCH_1):M_B_DQ<43>
  C32  M_B_DQ<42>     DDR1_DQ<42>  @BASEBOARD_FAB2_LIB.BASEBOARD_FAB2(SCH_1):M_B_DQ<42>
  B35  M_B_DQ<41>     DDR1_DQ<41>  @BASEBOARD_FAB2_LIB.BASEBOARD_FAB2(SCH_1):M_B_DQ<41>
  C36  M_B_DQ<40>     DDR1_DQ<40>  @BASEBOARD_FAB2_LIB.BASEBOARD_FAB2(SCH_1):M_B_DQ<40>
  AM81  M_B_DQ<3>      DDR1_DQ<3>  @BASEBOARD_FAB2_LIB.BASEBOARD_FAB2(SCH_1):M_B_DQ<3>
  P41  M_B_DQ<39>     DDR1_DQ<39>  @BASEBOARD_FAB2_LIB.BASEBOARD_FAB2(SCH_1):M_B_DQ<39>
  K41  M_B_DQ<38>     DDR1_DQ<38>  @BASEBOARD_FAB2_LIB.BASEBOARD_FAB2(SCH_1):M_B_DQ<38>
  T43  M_B_DQ<37>     DDR1_DQ<37>  @BASEBOARD_FAB2_LIB.BASEBOARD_FAB2(SCH_1):M_B_DQ<37>
  P43  M_B_DQ<36>     DDR1_DQ<36>  @BASEBOARD_FAB2_LIB.BASEBOARD_FAB2(SCH_1):M_B_DQ<36>
  N40  M_B_DQ<35>     DDR1_DQ<35>  @BASEBOARD_FAB2_LIB.BASEBOARD_FAB2(SCH_1):M_B_DQ<35>
  L40  M_B_DQ<34>     DDR1_DQ<34>  @BASEBOARD_FAB2_LIB.BASEBOARD_FAB2(SCH_1):M_B_DQ<34>
  H43  M_B_DQ<33>     DDR1_DQ<33>  @BASEBOARD_FAB2_LIB.BASEBOARD_FAB2(SCH_1):M_B_DQ<33>
  K43  M_B_DQ<32>     DDR1_DQ<32>  @BASEBOARD_FAB2_LIB.BASEBOARD_FAB2(SCH_1):M_B_DQ<32>
  G72  M_B_DQ<31>     DDR1_DQ<31>  @BASEBOARD_FAB2_LIB.BASEBOARD_FAB2(SCH_1):M_B_DQ<31>
  C72  M_B_DQ<30>     DDR1_DQ<30>  @BASEBOARD_FAB2_LIB.BASEBOARD_FAB2(SCH_1):M_B_DQ<30>
  AN82  M_B_DQ<2>      DDR1_DQ<2>  @BASEBOARD_FAB2_LIB.BASEBOARD_FAB2(SCH_1):M_B_DQ<2>
  G74  M_B_DQ<29>     DDR1_DQ<29>  @BASEBOARD_FAB2_LIB.BASEBOARD_FAB2(SCH_1):M_B_DQ<29>
  F75  M_B_DQ<28>     DDR1_DQ<28>  @BASEBOARD_FAB2_LIB.BASEBOARD_FAB2(SCH_1):M_B_DQ<28>
  F71  M_B_DQ<27>     DDR1_DQ<27>  @BASEBOARD_FAB2_LIB.BASEBOARD_FAB2(SCH_1):M_B_DQ<27>
  D71  M_B_DQ<26>     DDR1_DQ<26>  @BASEBOARD_FAB2_LIB.BASEBOARD_FAB2(SCH_1):M_B_DQ<26>
  C74  M_B_DQ<25>     DDR1_DQ<25>  @BASEBOARD_FAB2_LIB.BASEBOARD_FAB2(SCH_1):M_B_DQ<25>
  D75  M_B_DQ<24>     DDR1_DQ<24>  @BASEBOARD_FAB2_LIB.BASEBOARD_FAB2(SCH_1):M_B_DQ<24>
  J78  M_B_DQ<23>     DDR1_DQ<23>  @BASEBOARD_FAB2_LIB.BASEBOARD_FAB2(SCH_1):M_B_DQ<23>
  E78  M_B_DQ<22>     DDR1_DQ<22>  @BASEBOARD_FAB2_LIB.BASEBOARD_FAB2(SCH_1):M_B_DQ<22>
  H81  M_B_DQ<21>     DDR1_DQ<21>  @BASEBOARD_FAB2_LIB.BASEBOARD_FAB2(SCH_1):M_B_DQ<21>
  F81  M_B_DQ<20>     DDR1_DQ<20>  @BASEBOARD_FAB2_LIB.BASEBOARD_FAB2(SCH_1):M_B_DQ<20>
  AT79  M_B_DQ<1>      DDR1_DQ<1>  @BASEBOARD_FAB2_LIB.BASEBOARD_FAB2(SCH_1):M_B_DQ<1>
  H77  M_B_DQ<19>     DDR1_DQ<19>  @BASEBOARD_FAB2_LIB.BASEBOARD_FAB2(SCH_1):M_B_DQ<19>
  F77  M_B_DQ<18>     DDR1_DQ<18>  @BASEBOARD_FAB2_LIB.BASEBOARD_FAB2(SCH_1):M_B_DQ<18>
  J80  M_B_DQ<17>     DDR1_DQ<17>  @BASEBOARD_FAB2_LIB.BASEBOARD_FAB2(SCH_1):M_B_DQ<17>
  E80  M_B_DQ<16>     DDR1_DQ<16>  @BASEBOARD_FAB2_LIB.BASEBOARD_FAB2(SCH_1):M_B_DQ<16>
  AC80  M_B_DQ<15>     DDR1_DQ<15>  @BASEBOARD_FAB2_LIB.BASEBOARD_FAB2(SCH_1):M_B_DQ<15>
  AE82  M_B_DQ<14>     DDR1_DQ<14>  @BASEBOARD_FAB2_LIB.BASEBOARD_FAB2(SCH_1):M_B_DQ<14>
  AH79  M_B_DQ<13>     DDR1_DQ<13>  @BASEBOARD_FAB2_LIB.BASEBOARD_FAB2(SCH_1):M_B_DQ<13>
  AJ80  M_B_DQ<12>     DDR1_DQ<12>  @BASEBOARD_FAB2_LIB.BASEBOARD_FAB2(SCH_1):M_B_DQ<12>
  AB81  M_B_DQ<11>     DDR1_DQ<11>  @BASEBOARD_FAB2_LIB.BASEBOARD_FAB2(SCH_1):M_B_DQ<11>
  AC82  M_B_DQ<10>     DDR1_DQ<10>  @BASEBOARD_FAB2_LIB.BASEBOARD_FAB2(SCH_1):M_B_DQ<10>
  AV81  M_B_DQ<0>      DDR1_DQ<0>  @BASEBOARD_FAB2_LIB.BASEBOARD_FAB2(SCH_1):M_B_DQ<0>
  R46  M_B_CS_N<7>    DDR1_CS_N<7>  @BASEBOARD_FAB2_LIB.BASEBOARD_FAB2(SCH_1):M_B_CS_N<7>
  M45  M_B_CS_N<6>    DDR1_CS_N<6>  @BASEBOARD_FAB2_LIB.BASEBOARD_FAB2(SCH_1):M_B_CS_N<6>
  T49  M_B_CS_N<5>    DDR1_CS_N<5>  @BASEBOARD_FAB2_LIB.BASEBOARD_FAB2(SCH_1):M_B_CS_N<5>
  J50  M_B_CS_N<4>    DDR1_CS_N<4>  @BASEBOARD_FAB2_LIB.BASEBOARD_FAB2(SCH_1):M_B_CS_N<4>
  V47  M_B_CS_N<3>    DDR1_CS_N<3>  @BASEBOARD_FAB2_LIB.BASEBOARD_FAB2(SCH_1):M_B_CS_N<3>
  N46  M_B_CS_N<2>    DDR1_CS_N<2>  @BASEBOARD_FAB2_LIB.BASEBOARD_FAB2(SCH_1):M_B_CS_N<2>
  R50  M_B_CS_N<1>    DDR1_CS_N<1>  @BASEBOARD_FAB2_LIB.BASEBOARD_FAB2(SCH_1):M_B_CS_N<1>
  K51  M_B_CS_N<0>    DDR1_CS_N<0>  @BASEBOARD_FAB2_LIB.BASEBOARD_FAB2(SCH_1):M_B_CS_N<0>
  T57  M_B_CLK_DP<3>  DDR1_CLK_DP<3>  @BASEBOARD_FAB2_LIB.BASEBOARD_FAB2(SCH_1):M_B_CLK_DP<3>
  M57  M_B_CLK_DP<2>  DDR1_CLK_DP<2>  @BASEBOARD_FAB2_LIB.BASEBOARD_FAB2(SCH_1):M_B_CLK_DP<2>
  T55  M_B_CLK_DP<1>  DDR1_CLK_DP<1>  @BASEBOARD_FAB2_LIB.BASEBOARD_FAB2(SCH_1):M_B_CLK_DP<1>
  N54  M_B_CLK_DP<0>  DDR1_CLK_DP<0>  @BASEBOARD_FAB2_LIB.BASEBOARD_FAB2(SCH_1):M_B_CLK_DP<0>
  R56  M_B_CLK_DN<3>  DDR1_CLK_DN<3>  @BASEBOARD_FAB2_LIB.BASEBOARD_FAB2(SCH_1):M_B_CLK_DN<3>
  N56  M_B_CLK_DN<2>  DDR1_CLK_DN<2>  @BASEBOARD_FAB2_LIB.BASEBOARD_FAB2(SCH_1):M_B_CLK_DN<2>
  R54  M_B_CLK_DN<1>  DDR1_CLK_DN<1>  @BASEBOARD_FAB2_LIB.BASEBOARD_FAB2(SCH_1):M_B_CLK_DN<1>
  M53  M_B_CLK_DN<0>  DDR1_CLK_DN<0>  @BASEBOARD_FAB2_LIB.BASEBOARD_FAB2(SCH_1):M_B_CLK_DN<0>
  L64  M_B_CKE<3>     DDR1_CKE<3>  @BASEBOARD_FAB2_LIB.BASEBOARD_FAB2(SCH_1):M_B_CKE<3>
  K63  M_B_CKE<2>     DDR1_CKE<2>  @BASEBOARD_FAB2_LIB.BASEBOARD_FAB2(SCH_1):M_B_CKE<2>
  R64  M_B_CKE<1>     DDR1_CKE<1>  @BASEBOARD_FAB2_LIB.BASEBOARD_FAB2(SCH_1):M_B_CKE<1>
  N62  M_B_CKE<0>     DDR1_CKE<0>  @BASEBOARD_FAB2_LIB.BASEBOARD_FAB2(SCH_1):M_B_CKE<0>
  M47  M_B_C<2>       DDR1_CID<2>  @BASEBOARD_FAB2_LIB.BASEBOARD_FAB2(SCH_1):M_B_C<2>
  N60  M_B_BG<1>      DDR1_BG<1>  @BASEBOARD_FAB2_LIB.BASEBOARD_FAB2(SCH_1):M_B_BG<1>
  M61  M_B_BG<0>      DDR1_BG<0>  @BASEBOARD_FAB2_LIB.BASEBOARD_FAB2(SCH_1):M_B_BG<0>
  K55  M_B_BA<1>      DDR1_BA<1>  @BASEBOARD_FAB2_LIB.BASEBOARD_FAB2(SCH_1):M_B_BA<1>
  T53  M_B_BA<0>      DDR1_BA<0>  @BASEBOARD_FAB2_LIB.BASEBOARD_FAB2(SCH_1):M_B_BA<0>
  W62  M_B_ALERT_N    DDR1_ALERT_N  @BASEBOARD_FAB2_LIB.BASEBOARD_FAB2(SCH_1):M_B_ALERT_N
  T63  M_B_ACT_N      DDR1_ACT_N  @BASEBOARD_FAB2_LIB.BASEBOARD_FAB2(SCH_1):M_B_ACT_N

SKX_EXT_B_BGA1  I172  U5D1   [SKX_EXT_B_BGA1-IC,TBD]
  D53  M_A_PAR        DDR0_PAR  @BASEBOARD_FAB2_LIB.BASEBOARD_FAB2(SCH_1):M_A_PAR
  G48  M_A_ODT<3>     DDR0_ODT<3>  @BASEBOARD_FAB2_LIB.BASEBOARD_FAB2(SCH_1):M_A_ODT<3>
  G50  M_A_ODT<2>     DDR0_ODT<2>  @BASEBOARD_FAB2_LIB.BASEBOARD_FAB2(SCH_1):M_A_ODT<2>
  C48  M_A_ODT<1>     DDR0_ODT<1>  @BASEBOARD_FAB2_LIB.BASEBOARD_FAB2(SCH_1):M_A_ODT<1>
  C50  M_A_ODT<0>     DDR0_ODT<0>  @BASEBOARD_FAB2_LIB.BASEBOARD_FAB2(SCH_1):M_A_ODT<0>
  F61  M_A_MA<9>      DDR0_MA<9>  @BASEBOARD_FAB2_LIB.BASEBOARD_FAB2(SCH_1):M_A_MA<9>
  C60  M_A_MA<8>      DDR0_MA<8>  @BASEBOARD_FAB2_LIB.BASEBOARD_FAB2(SCH_1):M_A_MA<8>
  G60  M_A_MA<7>      DDR0_MA<7>  @BASEBOARD_FAB2_LIB.BASEBOARD_FAB2(SCH_1):M_A_MA<7>
  D59  M_A_MA<6>      DDR0_MA<6>  @BASEBOARD_FAB2_LIB.BASEBOARD_FAB2(SCH_1):M_A_MA<6>
  F59  M_A_MA<5>      DDR0_MA<5>  @BASEBOARD_FAB2_LIB.BASEBOARD_FAB2(SCH_1):M_A_MA<5>
  G58  M_A_MA<4>      DDR0_MA<4>  @BASEBOARD_FAB2_LIB.BASEBOARD_FAB2(SCH_1):M_A_MA<4>
  C58  M_A_MA<3>      DDR0_MA<3>  @BASEBOARD_FAB2_LIB.BASEBOARD_FAB2(SCH_1):M_A_MA<3>
  D57  M_A_MA<2>      DDR0_MA<2>  @BASEBOARD_FAB2_LIB.BASEBOARD_FAB2(SCH_1):M_A_MA<2>
  F57  M_A_MA<1>      DDR0_MA<1>  @BASEBOARD_FAB2_LIB.BASEBOARD_FAB2(SCH_1):M_A_MA<1>
  K47  M_A_MA<17>     DDR0_MA<17>  @BASEBOARD_FAB2_LIB.BASEBOARD_FAB2(SCH_1):M_A_MA<17>
  D51  M_A_MA<16>     DDR0_MA<16>  @BASEBOARD_FAB2_LIB.BASEBOARD_FAB2(SCH_1):M_A_MA<16>
  K49  M_A_MA<15>     DDR0_MA<15>  @BASEBOARD_FAB2_LIB.BASEBOARD_FAB2(SCH_1):M_A_MA<15>
  F51  M_A_MA<14>     DDR0_MA<14>  @BASEBOARD_FAB2_LIB.BASEBOARD_FAB2(SCH_1):M_A_MA<14>
  J48  M_A_MA<13>     DDR0_MA<13>  @BASEBOARD_FAB2_LIB.BASEBOARD_FAB2(SCH_1):M_A_MA<13>
  J64  M_A_MA<12>     DDR0_MA<12>  @BASEBOARD_FAB2_LIB.BASEBOARD_FAB2(SCH_1):M_A_MA<12>
  G62  M_A_MA<11>     DDR0_MA<11>  @BASEBOARD_FAB2_LIB.BASEBOARD_FAB2(SCH_1):M_A_MA<11>
  J54  M_A_MA<10>     DDR0_MA<10>  @BASEBOARD_FAB2_LIB.BASEBOARD_FAB2(SCH_1):M_A_MA<10>
  F53  M_A_MA<0>      DDR0_MA<0>  @BASEBOARD_FAB2_LIB.BASEBOARD_FAB2(SCH_1):M_A_MA<0>
  AG66  M_A_ECC<7>     DDR0_ECC<7>  @BASEBOARD_FAB2_LIB.BASEBOARD_FAB2(SCH_1):M_A_ECC<7>
  AC66  M_A_ECC<6>     DDR0_ECC<6>  @BASEBOARD_FAB2_LIB.BASEBOARD_FAB2(SCH_1):M_A_ECC<6>
  AF69  M_A_ECC<5>     DDR0_ECC<5>  @BASEBOARD_FAB2_LIB.BASEBOARD_FAB2(SCH_1):M_A_ECC<5>
  AD69  M_A_ECC<4>     DDR0_ECC<4>  @BASEBOARD_FAB2_LIB.BASEBOARD_FAB2(SCH_1):M_A_ECC<4>
  AF65  M_A_ECC<3>     DDR0_ECC<3>  @BASEBOARD_FAB2_LIB.BASEBOARD_FAB2(SCH_1):M_A_ECC<3>
  AD65  M_A_ECC<2>     DDR0_ECC<2>  @BASEBOARD_FAB2_LIB.BASEBOARD_FAB2(SCH_1):M_A_ECC<2>
  AG68  M_A_ECC<1>     DDR0_ECC<1>  @BASEBOARD_FAB2_LIB.BASEBOARD_FAB2(SCH_1):M_A_ECC<1>
  AC68  M_A_ECC<0>     DDR0_ECC<0>  @BASEBOARD_FAB2_LIB.BASEBOARD_FAB2(SCH_1):M_A_ECC<0>
  AM85  M_A_DQS_DP<9>  DDR0_DQS_DP<9>  @BASEBOARD_FAB2_LIB.BASEBOARD_FAB2(SCH_1):M_A_DQS_DP<9>
  AF67  M_A_DQS_DP<8>  DDR0_DQS_DP<8>  @BASEBOARD_FAB2_LIB.BASEBOARD_FAB2(SCH_1):M_A_DQS_DP<8>
  R24  M_A_DQS_DP<7>  DDR0_DQS_DP<7>  @BASEBOARD_FAB2_LIB.BASEBOARD_FAB2(SCH_1):M_A_DQS_DP<7>
  N30  M_A_DQS_DP<6>  DDR0_DQS_DP<6>  @BASEBOARD_FAB2_LIB.BASEBOARD_FAB2(SCH_1):M_A_DQS_DP<6>
  N36  M_A_DQS_DP<5>  DDR0_DQS_DP<5>  @BASEBOARD_FAB2_LIB.BASEBOARD_FAB2(SCH_1):M_A_DQS_DP<5>
  E40  M_A_DQS_DP<4>  DDR0_DQS_DP<4>  @BASEBOARD_FAB2_LIB.BASEBOARD_FAB2(SCH_1):M_A_DQS_DP<4>
  P75  M_A_DQS_DP<3>  DDR0_DQS_DP<3>  @BASEBOARD_FAB2_LIB.BASEBOARD_FAB2(SCH_1):M_A_DQS_DP<3>
  R80  M_A_DQS_DP<2>  DDR0_DQS_DP<2>  @BASEBOARD_FAB2_LIB.BASEBOARD_FAB2(SCH_1):M_A_DQS_DP<2>
  P85  M_A_DQS_DP<1>  DDR0_DQS_DP<1>  @BASEBOARD_FAB2_LIB.BASEBOARD_FAB2(SCH_1):M_A_DQS_DP<1>
  AD67  M_A_DQS_DP<17>  DDR0_DQS_DP<17>  @BASEBOARD_FAB2_LIB.BASEBOARD_FAB2(SCH_1):M_A_DQS_DP<17>
  L24  M_A_DQS_DP<16>  DDR0_DQS_DP<16>  @BASEBOARD_FAB2_LIB.BASEBOARD_FAB2(SCH_1):M_A_DQS_DP<16>
  L30  M_A_DQS_DP<15>  DDR0_DQS_DP<15>  @BASEBOARD_FAB2_LIB.BASEBOARD_FAB2(SCH_1):M_A_DQS_DP<15>
  L36  M_A_DQS_DP<14>  DDR0_DQS_DP<14>  @BASEBOARD_FAB2_LIB.BASEBOARD_FAB2(SCH_1):M_A_DQS_DP<14>
  C40  M_A_DQS_DP<13>  DDR0_DQS_DP<13>  @BASEBOARD_FAB2_LIB.BASEBOARD_FAB2(SCH_1):M_A_DQS_DP<13>
  M75  M_A_DQS_DP<12>  DDR0_DQS_DP<12>  @BASEBOARD_FAB2_LIB.BASEBOARD_FAB2(SCH_1):M_A_DQS_DP<12>
  T81  M_A_DQS_DP<11>  DDR0_DQS_DP<11>  @BASEBOARD_FAB2_LIB.BASEBOARD_FAB2(SCH_1):M_A_DQS_DP<11>
  V85  M_A_DQS_DP<10>  DDR0_DQS_DP<10>  @BASEBOARD_FAB2_LIB.BASEBOARD_FAB2(SCH_1):M_A_DQS_DP<10>
  AH85  M_A_DQS_DP<0>  DDR0_DQS_DP<0>  @BASEBOARD_FAB2_LIB.BASEBOARD_FAB2(SCH_1):M_A_DQS_DP<0>
  AL84  M_A_DQS_DN<9>  DDR0_DQS_DN<9>  @BASEBOARD_FAB2_LIB.BASEBOARD_FAB2(SCH_1):M_A_DQS_DN<9>
  AH67  M_A_DQS_DN<8>  DDR0_DQS_DN<8>  @BASEBOARD_FAB2_LIB.BASEBOARD_FAB2(SCH_1):M_A_DQS_DN<8>
  N24  M_A_DQS_DN<7>  DDR0_DQS_DN<7>  @BASEBOARD_FAB2_LIB.BASEBOARD_FAB2(SCH_1):M_A_DQS_DN<7>
  R30  M_A_DQS_DN<6>  DDR0_DQS_DN<6>  @BASEBOARD_FAB2_LIB.BASEBOARD_FAB2(SCH_1):M_A_DQS_DN<6>
  R36  M_A_DQS_DN<5>  DDR0_DQS_DN<5>  @BASEBOARD_FAB2_LIB.BASEBOARD_FAB2(SCH_1):M_A_DQS_DN<5>
  G40  M_A_DQS_DN<4>  DDR0_DQS_DN<4>  @BASEBOARD_FAB2_LIB.BASEBOARD_FAB2(SCH_1):M_A_DQS_DN<4>
  T75  M_A_DQS_DN<3>  DDR0_DQS_DN<3>  @BASEBOARD_FAB2_LIB.BASEBOARD_FAB2(SCH_1):M_A_DQS_DN<3>
  P79  M_A_DQS_DN<2>  DDR0_DQS_DN<2>  @BASEBOARD_FAB2_LIB.BASEBOARD_FAB2(SCH_1):M_A_DQS_DN<2>
  R84  M_A_DQS_DN<1>  DDR0_DQS_DN<1>  @BASEBOARD_FAB2_LIB.BASEBOARD_FAB2(SCH_1):M_A_DQS_DN<1>
  AB67  M_A_DQS_DN<17>  DDR0_DQS_DN<17>  @BASEBOARD_FAB2_LIB.BASEBOARD_FAB2(SCH_1):M_A_DQS_DN<17>
  J24  M_A_DQS_DN<16>  DDR0_DQS_DN<16>  @BASEBOARD_FAB2_LIB.BASEBOARD_FAB2(SCH_1):M_A_DQS_DN<16>
  J30  M_A_DQS_DN<15>  DDR0_DQS_DN<15>  @BASEBOARD_FAB2_LIB.BASEBOARD_FAB2(SCH_1):M_A_DQS_DN<15>
  J36  M_A_DQS_DN<14>  DDR0_DQS_DN<14>  @BASEBOARD_FAB2_LIB.BASEBOARD_FAB2(SCH_1):M_A_DQS_DN<14>
  A40  M_A_DQS_DN<13>  DDR0_DQS_DN<13>  @BASEBOARD_FAB2_LIB.BASEBOARD_FAB2(SCH_1):M_A_DQS_DN<13>
  K75  M_A_DQS_DN<12>  DDR0_DQS_DN<12>  @BASEBOARD_FAB2_LIB.BASEBOARD_FAB2(SCH_1):M_A_DQS_DN<12>
  U82  M_A_DQS_DN<11>  DDR0_DQS_DN<11>  @BASEBOARD_FAB2_LIB.BASEBOARD_FAB2(SCH_1):M_A_DQS_DN<11>
  U84  M_A_DQS_DN<10>  DDR0_DQS_DN<10>  @BASEBOARD_FAB2_LIB.BASEBOARD_FAB2(SCH_1):M_A_DQS_DN<10>
  AJ84  M_A_DQS_DN<0>  DDR0_DQS_DN<0>  @BASEBOARD_FAB2_LIB.BASEBOARD_FAB2(SCH_1):M_A_DQS_DN<0>
  W84  M_A_DQ<9>      DDR0_DQ<9>  @BASEBOARD_FAB2_LIB.BASEBOARD_FAB2(SCH_1):M_A_DQ<9>
  W86  M_A_DQ<8>      DDR0_DQ<8>  @BASEBOARD_FAB2_LIB.BASEBOARD_FAB2(SCH_1):M_A_DQ<8>
  AG84  M_A_DQ<7>      DDR0_DQ<7>  @BASEBOARD_FAB2_LIB.BASEBOARD_FAB2(SCH_1):M_A_DQ<7>
  AG86  M_A_DQ<6>      DDR0_DQ<6>  @BASEBOARD_FAB2_LIB.BASEBOARD_FAB2(SCH_1):M_A_DQ<6>
  K23  M_A_DQ<63>     DDR0_DQ<63>  @BASEBOARD_FAB2_LIB.BASEBOARD_FAB2(SCH_1):M_A_DQ<63>
  H23  M_A_DQ<62>     DDR0_DQ<62>  @BASEBOARD_FAB2_LIB.BASEBOARD_FAB2(SCH_1):M_A_DQ<62>
  N26  M_A_DQ<61>     DDR0_DQ<61>  @BASEBOARD_FAB2_LIB.BASEBOARD_FAB2(SCH_1):M_A_DQ<61>
  L26  M_A_DQ<60>     DDR0_DQ<60>  @BASEBOARD_FAB2_LIB.BASEBOARD_FAB2(SCH_1):M_A_DQ<60>
  AR84  M_A_DQ<5>      DDR0_DQ<5>  @BASEBOARD_FAB2_LIB.BASEBOARD_FAB2(SCH_1):M_A_DQ<5>
  T23  M_A_DQ<59>     DDR0_DQ<59>  @BASEBOARD_FAB2_LIB.BASEBOARD_FAB2(SCH_1):M_A_DQ<59>
  P23  M_A_DQ<58>     DDR0_DQ<58>  @BASEBOARD_FAB2_LIB.BASEBOARD_FAB2(SCH_1):M_A_DQ<58>
  P25  M_A_DQ<57>     DDR0_DQ<57>  @BASEBOARD_FAB2_LIB.BASEBOARD_FAB2(SCH_1):M_A_DQ<57>
  K25  M_A_DQ<56>     DDR0_DQ<56>  @BASEBOARD_FAB2_LIB.BASEBOARD_FAB2(SCH_1):M_A_DQ<56>
  P29  M_A_DQ<55>     DDR0_DQ<55>  @BASEBOARD_FAB2_LIB.BASEBOARD_FAB2(SCH_1):M_A_DQ<55>
  K29  M_A_DQ<54>     DDR0_DQ<54>  @BASEBOARD_FAB2_LIB.BASEBOARD_FAB2(SCH_1):M_A_DQ<54>
  N32  M_A_DQ<53>     DDR0_DQ<53>  @BASEBOARD_FAB2_LIB.BASEBOARD_FAB2(SCH_1):M_A_DQ<53>
  L32  M_A_DQ<52>     DDR0_DQ<52>  @BASEBOARD_FAB2_LIB.BASEBOARD_FAB2(SCH_1):M_A_DQ<52>
  N28  M_A_DQ<51>     DDR0_DQ<51>  @BASEBOARD_FAB2_LIB.BASEBOARD_FAB2(SCH_1):M_A_DQ<51>
  L28  M_A_DQ<50>     DDR0_DQ<50>  @BASEBOARD_FAB2_LIB.BASEBOARD_FAB2(SCH_1):M_A_DQ<50>
  AR86  M_A_DQ<4>      DDR0_DQ<4>  @BASEBOARD_FAB2_LIB.BASEBOARD_FAB2(SCH_1):M_A_DQ<4>
  P31  M_A_DQ<49>     DDR0_DQ<49>  @BASEBOARD_FAB2_LIB.BASEBOARD_FAB2(SCH_1):M_A_DQ<49>
  K31  M_A_DQ<48>     DDR0_DQ<48>  @BASEBOARD_FAB2_LIB.BASEBOARD_FAB2(SCH_1):M_A_DQ<48>
  P35  M_A_DQ<47>     DDR0_DQ<47>  @BASEBOARD_FAB2_LIB.BASEBOARD_FAB2(SCH_1):M_A_DQ<47>
  K35  M_A_DQ<46>     DDR0_DQ<46>  @BASEBOARD_FAB2_LIB.BASEBOARD_FAB2(SCH_1):M_A_DQ<46>
  N38  M_A_DQ<45>     DDR0_DQ<45>  @BASEBOARD_FAB2_LIB.BASEBOARD_FAB2(SCH_1):M_A_DQ<45>
  L38  M_A_DQ<44>     DDR0_DQ<44>  @BASEBOARD_FAB2_LIB.BASEBOARD_FAB2(SCH_1):M_A_DQ<44>
  N34  M_A_DQ<43>     DDR0_DQ<43>  @BASEBOARD_FAB2_LIB.BASEBOARD_FAB2(SCH_1):M_A_DQ<43>
  L34  M_A_DQ<42>     DDR0_DQ<42>  @BASEBOARD_FAB2_LIB.BASEBOARD_FAB2(SCH_1):M_A_DQ<42>
  P37  M_A_DQ<41>     DDR0_DQ<41>  @BASEBOARD_FAB2_LIB.BASEBOARD_FAB2(SCH_1):M_A_DQ<41>
  K37  M_A_DQ<40>     DDR0_DQ<40>  @BASEBOARD_FAB2_LIB.BASEBOARD_FAB2(SCH_1):M_A_DQ<40>
  AE84  M_A_DQ<3>      DDR0_DQ<3>  @BASEBOARD_FAB2_LIB.BASEBOARD_FAB2(SCH_1):M_A_DQ<3>
  F39  M_A_DQ<39>     DDR0_DQ<39>  @BASEBOARD_FAB2_LIB.BASEBOARD_FAB2(SCH_1):M_A_DQ<39>
  B39  M_A_DQ<38>     DDR0_DQ<38>  @BASEBOARD_FAB2_LIB.BASEBOARD_FAB2(SCH_1):M_A_DQ<38>
  F41  M_A_DQ<37>     DDR0_DQ<37>  @BASEBOARD_FAB2_LIB.BASEBOARD_FAB2(SCH_1):M_A_DQ<37>
  E42  M_A_DQ<36>     DDR0_DQ<36>  @BASEBOARD_FAB2_LIB.BASEBOARD_FAB2(SCH_1):M_A_DQ<36>
  E38  M_A_DQ<35>     DDR0_DQ<35>  @BASEBOARD_FAB2_LIB.BASEBOARD_FAB2(SCH_1):M_A_DQ<35>
  C38  M_A_DQ<34>     DDR0_DQ<34>  @BASEBOARD_FAB2_LIB.BASEBOARD_FAB2(SCH_1):M_A_DQ<34>
  B41  M_A_DQ<33>     DDR0_DQ<33>  @BASEBOARD_FAB2_LIB.BASEBOARD_FAB2(SCH_1):M_A_DQ<33>
  C42  M_A_DQ<32>     DDR0_DQ<32>  @BASEBOARD_FAB2_LIB.BASEBOARD_FAB2(SCH_1):M_A_DQ<32>
  R74  M_A_DQ<31>     DDR0_DQ<31>  @BASEBOARD_FAB2_LIB.BASEBOARD_FAB2(SCH_1):M_A_DQ<31>
  L74  M_A_DQ<30>     DDR0_DQ<30>  @BASEBOARD_FAB2_LIB.BASEBOARD_FAB2(SCH_1):M_A_DQ<30>
  AE86  M_A_DQ<2>      DDR0_DQ<2>  @BASEBOARD_FAB2_LIB.BASEBOARD_FAB2(SCH_1):M_A_DQ<2>
  P77  M_A_DQ<29>     DDR0_DQ<29>  @BASEBOARD_FAB2_LIB.BASEBOARD_FAB2(SCH_1):M_A_DQ<29>
  M77  M_A_DQ<28>     DDR0_DQ<28>  @BASEBOARD_FAB2_LIB.BASEBOARD_FAB2(SCH_1):M_A_DQ<28>
  P73  M_A_DQ<27>     DDR0_DQ<27>  @BASEBOARD_FAB2_LIB.BASEBOARD_FAB2(SCH_1):M_A_DQ<27>
  M73  M_A_DQ<26>     DDR0_DQ<26>  @BASEBOARD_FAB2_LIB.BASEBOARD_FAB2(SCH_1):M_A_DQ<26>
  R76  M_A_DQ<25>     DDR0_DQ<25>  @BASEBOARD_FAB2_LIB.BASEBOARD_FAB2(SCH_1):M_A_DQ<25>
  L76  M_A_DQ<24>     DDR0_DQ<24>  @BASEBOARD_FAB2_LIB.BASEBOARD_FAB2(SCH_1):M_A_DQ<24>
  N80  M_A_DQ<23>     DDR0_DQ<23>  @BASEBOARD_FAB2_LIB.BASEBOARD_FAB2(SCH_1):M_A_DQ<23>
  R82  M_A_DQ<22>     DDR0_DQ<22>  @BASEBOARD_FAB2_LIB.BASEBOARD_FAB2(SCH_1):M_A_DQ<22>
  V79  M_A_DQ<21>     DDR0_DQ<21>  @BASEBOARD_FAB2_LIB.BASEBOARD_FAB2(SCH_1):M_A_DQ<21>
  W80  M_A_DQ<20>     DDR0_DQ<20>  @BASEBOARD_FAB2_LIB.BASEBOARD_FAB2(SCH_1):M_A_DQ<20>
  AN84  M_A_DQ<1>      DDR0_DQ<1>  @BASEBOARD_FAB2_LIB.BASEBOARD_FAB2(SCH_1):M_A_DQ<1>
  M81  M_A_DQ<19>     DDR0_DQ<19>  @BASEBOARD_FAB2_LIB.BASEBOARD_FAB2(SCH_1):M_A_DQ<19>
  N82  M_A_DQ<18>     DDR0_DQ<18>  @BASEBOARD_FAB2_LIB.BASEBOARD_FAB2(SCH_1):M_A_DQ<18>
  T79  M_A_DQ<17>     DDR0_DQ<17>  @BASEBOARD_FAB2_LIB.BASEBOARD_FAB2(SCH_1):M_A_DQ<17>
  V81  M_A_DQ<16>     DDR0_DQ<16>  @BASEBOARD_FAB2_LIB.BASEBOARD_FAB2(SCH_1):M_A_DQ<16>
  N84  M_A_DQ<15>     DDR0_DQ<15>  @BASEBOARD_FAB2_LIB.BASEBOARD_FAB2(SCH_1):M_A_DQ<15>
  N86  M_A_DQ<14>     DDR0_DQ<14>  @BASEBOARD_FAB2_LIB.BASEBOARD_FAB2(SCH_1):M_A_DQ<14>
  AA84  M_A_DQ<13>     DDR0_DQ<13>  @BASEBOARD_FAB2_LIB.BASEBOARD_FAB2(SCH_1):M_A_DQ<13>
  AA86  M_A_DQ<12>     DDR0_DQ<12>  @BASEBOARD_FAB2_LIB.BASEBOARD_FAB2(SCH_1):M_A_DQ<12>
  L84  M_A_DQ<11>     DDR0_DQ<11>  @BASEBOARD_FAB2_LIB.BASEBOARD_FAB2(SCH_1):M_A_DQ<11>
  L86  M_A_DQ<10>     DDR0_DQ<10>  @BASEBOARD_FAB2_LIB.BASEBOARD_FAB2(SCH_1):M_A_DQ<10>
  AN86  M_A_DQ<0>      DDR0_DQ<0>  @BASEBOARD_FAB2_LIB.BASEBOARD_FAB2(SCH_1):M_A_DQ<0>
  K45  M_A_CS_N<7>    DDR0_CS_N<7>  @BASEBOARD_FAB2_LIB.BASEBOARD_FAB2(SCH_1):M_A_CS_N<7>
  F45  M_A_CS_N<6>    DDR0_CS_N<6>  @BASEBOARD_FAB2_LIB.BASEBOARD_FAB2(SCH_1):M_A_CS_N<6>
  D49  M_A_CS_N<5>    DDR0_CS_N<5>  @BASEBOARD_FAB2_LIB.BASEBOARD_FAB2(SCH_1):M_A_CS_N<5>
  B51  M_A_CS_N<4>    DDR0_CS_N<4>  @BASEBOARD_FAB2_LIB.BASEBOARD_FAB2(SCH_1):M_A_CS_N<4>
  F47  M_A_CS_N<3>    DDR0_CS_N<3>  @BASEBOARD_FAB2_LIB.BASEBOARD_FAB2(SCH_1):M_A_CS_N<3>
  D47  M_A_CS_N<2>    DDR0_CS_N<2>  @BASEBOARD_FAB2_LIB.BASEBOARD_FAB2(SCH_1):M_A_CS_N<2>
  F49  M_A_CS_N<1>    DDR0_CS_N<1>  @BASEBOARD_FAB2_LIB.BASEBOARD_FAB2(SCH_1):M_A_CS_N<1>
  G52  M_A_CS_N<0>    DDR0_CS_N<0>  @BASEBOARD_FAB2_LIB.BASEBOARD_FAB2(SCH_1):M_A_CS_N<0>
  B57  M_A_CLK_DP<3>  DDR0_CLK_DP<3>  @BASEBOARD_FAB2_LIB.BASEBOARD_FAB2(SCH_1):M_A_CLK_DP<3>
  G56  M_A_CLK_DP<2>  DDR0_CLK_DP<2>  @BASEBOARD_FAB2_LIB.BASEBOARD_FAB2(SCH_1):M_A_CLK_DP<2>
  B55  M_A_CLK_DP<1>  DDR0_CLK_DP<1>  @BASEBOARD_FAB2_LIB.BASEBOARD_FAB2(SCH_1):M_A_CLK_DP<1>
  D55  M_A_CLK_DP<0>  DDR0_CLK_DP<0>  @BASEBOARD_FAB2_LIB.BASEBOARD_FAB2(SCH_1):M_A_CLK_DP<0>
  C56  M_A_CLK_DN<3>  DDR0_CLK_DN<3>  @BASEBOARD_FAB2_LIB.BASEBOARD_FAB2(SCH_1):M_A_CLK_DN<3>
  J56  M_A_CLK_DN<2>  DDR0_CLK_DN<2>  @BASEBOARD_FAB2_LIB.BASEBOARD_FAB2(SCH_1):M_A_CLK_DN<2>
  C54  M_A_CLK_DN<1>  DDR0_CLK_DN<1>  @BASEBOARD_FAB2_LIB.BASEBOARD_FAB2(SCH_1):M_A_CLK_DN<1>
  F55  M_A_CLK_DN<0>  DDR0_CLK_DN<0>  @BASEBOARD_FAB2_LIB.BASEBOARD_FAB2(SCH_1):M_A_CLK_DN<0>
  D63  M_A_CKE<3>     DDR0_CKE<3>  @BASEBOARD_FAB2_LIB.BASEBOARD_FAB2(SCH_1):M_A_CKE<3>
  B63  M_A_CKE<2>     DDR0_CKE<2>  @BASEBOARD_FAB2_LIB.BASEBOARD_FAB2(SCH_1):M_A_CKE<2>
  C64  M_A_CKE<1>     DDR0_CKE<1>  @BASEBOARD_FAB2_LIB.BASEBOARD_FAB2(SCH_1):M_A_CKE<1>
  C62  M_A_CKE<0>     DDR0_CKE<0>  @BASEBOARD_FAB2_LIB.BASEBOARD_FAB2(SCH_1):M_A_CKE<0>
  G46  M_A_C<2>       DDR0_CID<2>  @BASEBOARD_FAB2_LIB.BASEBOARD_FAB2(SCH_1):M_A_C<2>
  F63  M_A_BG<1>      DDR0_BG<1>  @BASEBOARD_FAB2_LIB.BASEBOARD_FAB2(SCH_1):M_A_BG<1>
  D61  M_A_BG<0>      DDR0_BG<0>  @BASEBOARD_FAB2_LIB.BASEBOARD_FAB2(SCH_1):M_A_BG<0>
  G54  M_A_BA<1>      DDR0_BA<1>  @BASEBOARD_FAB2_LIB.BASEBOARD_FAB2(SCH_1):M_A_BA<1>
  C52  M_A_BA<0>      DDR0_BA<0>  @BASEBOARD_FAB2_LIB.BASEBOARD_FAB2(SCH_1):M_A_BA<0>
  B61  M_A_ALERT_N    DDR0_ALERT_N  @BASEBOARD_FAB2_LIB.BASEBOARD_FAB2(SCH_1):M_A_ALERT_N
  J60  M_A_ACT_N      DDR0_ACT_N  @BASEBOARD_FAB2_LIB.BASEBOARD_FAB2(SCH_1):M_A_ACT_N

SKX_EXT_B_BGA1  I204  U5D1   [SKX_EXT_B_BGA1-IC,TBD]
  AV21  XDP_PRESENT_N  DEBUG_EN_N  @BASEBOARD_FAB2_LIB.BASEBOARD_FAB2(SCH_1):XDP_PRESENT_N
  AP17  XDP_CPU_PWR_DEBUG_N  PWR_DEBUG_N  @BASEBOARD_FAB2_LIB.BASEBOARD_FAB2(SCH_1):XDP_CPU_PWR_DEBUG_N
  AK21  VSENSE_P1V8MCP_CPU0_SKT_VSEN  RSVD<221>  @BASEBOARD_FAB2_LIB.BASEBOARD_FAB2(SCH_1):VSENSE_P1V8MCP_CPU0_SKT_VSEN
  AL20  VSENSE_P1V8MCP_CPU0_SKT_VRTN  RSVD<215>  @BASEBOARD_FAB2_LIB.BASEBOARD_FAB2(SCH_1):VSENSE_P1V8MCP_CPU0_SKT_VRTN
  AN14  TP_CPU0_RSVD_TEST_5  TEST_5  @BASEBOARD_FAB2_LIB.BASEBOARD_FAB2(SCH_1):TP_CPU0_RSVD_TEST_5
  AN12  TP_CPU0_RSVD_TEST_4  TEST_4  @BASEBOARD_FAB2_LIB.BASEBOARD_FAB2(SCH_1):TP_CPU0_RSVD_TEST_4
  AM13  TP_CPU0_RSVD_TEST_3  TEST_3  @BASEBOARD_FAB2_LIB.BASEBOARD_FAB2(SCH_1):TP_CPU0_RSVD_TEST_3
  AY13  TP_CPU0_RSVD_TEST_11  TEST_11  @BASEBOARD_FAB2_LIB.BASEBOARD_FAB2(SCH_1):TP_CPU0_RSVD_TEST_11
   A4  TP_CPU0_RSVD_304  RSVD<304>  @BASEBOARD_FAB2_LIB.BASEBOARD_FAB2(SCH_1):TP_CPU0_RSVD_304
   A6  TP_CPU0_RSVD_303  RSVD<303>  @BASEBOARD_FAB2_LIB.BASEBOARD_FAB2(SCH_1):TP_CPU0_RSVD_303
  A24  TP_CPU0_RSVD_300  RSVD<300>  @BASEBOARD_FAB2_LIB.BASEBOARD_FAB2(SCH_1):TP_CPU0_RSVD_300
   B3  TP_CPU0_RSVD_299  RSVD<299>  @BASEBOARD_FAB2_LIB.BASEBOARD_FAB2(SCH_1):TP_CPU0_RSVD_299
   B7  TP_CPU0_RSVD_298  RSVD<298>  @BASEBOARD_FAB2_LIB.BASEBOARD_FAB2(SCH_1):TP_CPU0_RSVD_298
  B77  TP_CPU0_RSVD_293  RSVD<293>  @BASEBOARD_FAB2_LIB.BASEBOARD_FAB2(SCH_1):TP_CPU0_RSVD_293
  B81  TP_CPU0_RSVD_292  RSVD<292>  @BASEBOARD_FAB2_LIB.BASEBOARD_FAB2(SCH_1):TP_CPU0_RSVD_292
   C6  TP_CPU0_RSVD_291  RSVD<291>  @BASEBOARD_FAB2_LIB.BASEBOARD_FAB2(SCH_1):TP_CPU0_RSVD_291
  C18  TP_CPU0_RSVD_290  RSVD<290>  @BASEBOARD_FAB2_LIB.BASEBOARD_FAB2(SCH_1):TP_CPU0_RSVD_290
  C24  TP_CPU0_RSVD_289  RSVD<289>  @BASEBOARD_FAB2_LIB.BASEBOARD_FAB2(SCH_1):TP_CPU0_RSVD_289
  C82  TP_CPU0_RSVD_288  RSVD<288>  @BASEBOARD_FAB2_LIB.BASEBOARD_FAB2(SCH_1):TP_CPU0_RSVD_288
   D5  TP_CPU0_RSVD_287  RSVD<287>  @BASEBOARD_FAB2_LIB.BASEBOARD_FAB2(SCH_1):TP_CPU0_RSVD_287
  D17  TP_CPU0_RSVD_286  RSVD<286>  @BASEBOARD_FAB2_LIB.BASEBOARD_FAB2(SCH_1):TP_CPU0_RSVD_286
  D65  TP_CPU0_RSVD_285  RSVD<285>  @BASEBOARD_FAB2_LIB.BASEBOARD_FAB2(SCH_1):TP_CPU0_RSVD_285
  D83  TP_CPU0_RSVD_284  RSVD<284>  @BASEBOARD_FAB2_LIB.BASEBOARD_FAB2(SCH_1):TP_CPU0_RSVD_284
   E2  TP_CPU0_RSVD_283  RSVD<283>  @BASEBOARD_FAB2_LIB.BASEBOARD_FAB2(SCH_1):TP_CPU0_RSVD_283
   E4  TP_CPU0_RSVD_282  RSVD<282>  @BASEBOARD_FAB2_LIB.BASEBOARD_FAB2(SCH_1):TP_CPU0_RSVD_282
  E24  TP_CPU0_RSVD_281  RSVD<281>  @BASEBOARD_FAB2_LIB.BASEBOARD_FAB2(SCH_1):TP_CPU0_RSVD_281
  E84  TP_CPU0_RSVD_280  RSVD<280>  @BASEBOARD_FAB2_LIB.BASEBOARD_FAB2(SCH_1):TP_CPU0_RSVD_280
   F3  TP_CPU0_RSVD_279  RSVD<279>  @BASEBOARD_FAB2_LIB.BASEBOARD_FAB2(SCH_1):TP_CPU0_RSVD_279
  F23  TP_CPU0_RSVD_278  RSVD<278>  @BASEBOARD_FAB2_LIB.BASEBOARD_FAB2(SCH_1):TP_CPU0_RSVD_278
  F65  TP_CPU0_RSVD_277  RSVD<277>  @BASEBOARD_FAB2_LIB.BASEBOARD_FAB2(SCH_1):TP_CPU0_RSVD_277
  F83  TP_CPU0_RSVD_276  RSVD<276>  @BASEBOARD_FAB2_LIB.BASEBOARD_FAB2(SCH_1):TP_CPU0_RSVD_276
   G2  TP_CPU0_RSVD_275  RSVD<275>  @BASEBOARD_FAB2_LIB.BASEBOARD_FAB2(SCH_1):TP_CPU0_RSVD_275
  G64  TP_CPU0_RSVD_274  RSVD<274>  @BASEBOARD_FAB2_LIB.BASEBOARD_FAB2(SCH_1):TP_CPU0_RSVD_274
  G84  TP_CPU0_RSVD_273  RSVD<273>  @BASEBOARD_FAB2_LIB.BASEBOARD_FAB2(SCH_1):TP_CPU0_RSVD_273
   H1  TP_CPU0_RSVD_272  RSVD<272>  @BASEBOARD_FAB2_LIB.BASEBOARD_FAB2(SCH_1):TP_CPU0_RSVD_272
  H83  TP_CPU0_RSVD_271  RSVD<271>  @BASEBOARD_FAB2_LIB.BASEBOARD_FAB2(SCH_1):TP_CPU0_RSVD_271
  H85  TP_CPU0_RSVD_270  RSVD<270>  @BASEBOARD_FAB2_LIB.BASEBOARD_FAB2(SCH_1):TP_CPU0_RSVD_270
  J46  TP_CPU0_RSVD_269  RSVD<269>  @BASEBOARD_FAB2_LIB.BASEBOARD_FAB2(SCH_1):TP_CPU0_RSVD_269
  J62  TP_CPU0_RSVD_268  RSVD<268>  @BASEBOARD_FAB2_LIB.BASEBOARD_FAB2(SCH_1):TP_CPU0_RSVD_268
  K61  TP_CPU0_RSVD_267  RSVD<267>  @BASEBOARD_FAB2_LIB.BASEBOARD_FAB2(SCH_1):TP_CPU0_RSVD_267
  M63  TP_CPU0_RSVD_266  RSVD<266>  @BASEBOARD_FAB2_LIB.BASEBOARD_FAB2(SCH_1):TP_CPU0_RSVD_266
  P65  TP_CPU0_RSVD_265  RSVD<265>  @BASEBOARD_FAB2_LIB.BASEBOARD_FAB2(SCH_1):TP_CPU0_RSVD_265
  R62  TP_CPU0_RSVD_264  RSVD<264>  @BASEBOARD_FAB2_LIB.BASEBOARD_FAB2(SCH_1):TP_CPU0_RSVD_264
  R66  TP_CPU0_RSVD_263  RSVD<263>  @BASEBOARD_FAB2_LIB.BASEBOARD_FAB2(SCH_1):TP_CPU0_RSVD_263
  T67  TP_CPU0_RSVD_262  RSVD<262>  @BASEBOARD_FAB2_LIB.BASEBOARD_FAB2(SCH_1):TP_CPU0_RSVD_262
  U66  TP_CPU0_RSVD_261  RSVD<261>  @BASEBOARD_FAB2_LIB.BASEBOARD_FAB2(SCH_1):TP_CPU0_RSVD_261
  V65  TP_CPU0_RSVD_260  RSVD<260>  @BASEBOARD_FAB2_LIB.BASEBOARD_FAB2(SCH_1):TP_CPU0_RSVD_260
  V67  TP_CPU0_RSVD_259  RSVD<259>  @BASEBOARD_FAB2_LIB.BASEBOARD_FAB2(SCH_1):TP_CPU0_RSVD_259
  W66  TP_CPU0_RSVD_258  RSVD<258>  @BASEBOARD_FAB2_LIB.BASEBOARD_FAB2(SCH_1):TP_CPU0_RSVD_258
  Y65  TP_CPU0_RSVD_256  RSVD<256>  @BASEBOARD_FAB2_LIB.BASEBOARD_FAB2(SCH_1):TP_CPU0_RSVD_256
  AD47  TP_CPU0_RSVD_254  RSVD<254>  @BASEBOARD_FAB2_LIB.BASEBOARD_FAB2(SCH_1):TP_CPU0_RSVD_254
  AD49  TP_CPU0_RSVD_253  RSVD<253>  @BASEBOARD_FAB2_LIB.BASEBOARD_FAB2(SCH_1):TP_CPU0_RSVD_253
  AD51  TP_CPU0_RSVD_252  RSVD<252>  @BASEBOARD_FAB2_LIB.BASEBOARD_FAB2(SCH_1):TP_CPU0_RSVD_252
  AE46  TP_CPU0_RSVD_251  RSVD<251>  @BASEBOARD_FAB2_LIB.BASEBOARD_FAB2(SCH_1):TP_CPU0_RSVD_251
  AE48  TP_CPU0_RSVD_250  RSVD<250>  @BASEBOARD_FAB2_LIB.BASEBOARD_FAB2(SCH_1):TP_CPU0_RSVD_250
  AE50  TP_CPU0_RSVD_249  RSVD<249>  @BASEBOARD_FAB2_LIB.BASEBOARD_FAB2(SCH_1):TP_CPU0_RSVD_249
  AE52  TP_CPU0_RSVD_248  RSVD<248>  @BASEBOARD_FAB2_LIB.BASEBOARD_FAB2(SCH_1):TP_CPU0_RSVD_248
  AE72  TP_CPU0_RSVD_247  RSVD<247>  @BASEBOARD_FAB2_LIB.BASEBOARD_FAB2(SCH_1):TP_CPU0_RSVD_247
  AF19  TP_CPU0_RSVD_246  RSVD<246>  @BASEBOARD_FAB2_LIB.BASEBOARD_FAB2(SCH_1):TP_CPU0_RSVD_246
  AF47  TP_CPU0_RSVD_245  RSVD<245>  @BASEBOARD_FAB2_LIB.BASEBOARD_FAB2(SCH_1):TP_CPU0_RSVD_245
  AF49  TP_CPU0_RSVD_244  RSVD<244>  @BASEBOARD_FAB2_LIB.BASEBOARD_FAB2(SCH_1):TP_CPU0_RSVD_244
  AF51  TP_CPU0_RSVD_243  RSVD<243>  @BASEBOARD_FAB2_LIB.BASEBOARD_FAB2(SCH_1):TP_CPU0_RSVD_243
  AF53  TP_CPU0_RSVD_242  RSVD<242>  @BASEBOARD_FAB2_LIB.BASEBOARD_FAB2(SCH_1):TP_CPU0_RSVD_242
  AF71  TP_CPU0_RSVD_241  RSVD<241>  @BASEBOARD_FAB2_LIB.BASEBOARD_FAB2(SCH_1):TP_CPU0_RSVD_241
  AG20  TP_CPU0_RSVD_240  RSVD<240>  @BASEBOARD_FAB2_LIB.BASEBOARD_FAB2(SCH_1):TP_CPU0_RSVD_240
  AG48  TP_CPU0_RSVD_239  RSVD<239>  @BASEBOARD_FAB2_LIB.BASEBOARD_FAB2(SCH_1):TP_CPU0_RSVD_239
  AG50  TP_CPU0_RSVD_238  RSVD<238>  @BASEBOARD_FAB2_LIB.BASEBOARD_FAB2(SCH_1):TP_CPU0_RSVD_238
  AG52  TP_CPU0_RSVD_237  RSVD<237>  @BASEBOARD_FAB2_LIB.BASEBOARD_FAB2(SCH_1):TP_CPU0_RSVD_237
  AG54  TP_CPU0_RSVD_236  RSVD<236>  @BASEBOARD_FAB2_LIB.BASEBOARD_FAB2(SCH_1):TP_CPU0_RSVD_236
  AG56  TP_CPU0_RSVD_235  RSVD<235>  @BASEBOARD_FAB2_LIB.BASEBOARD_FAB2(SCH_1):TP_CPU0_RSVD_235
  AG72  TP_CPU0_RSVD_234  RSVD<234>  @BASEBOARD_FAB2_LIB.BASEBOARD_FAB2(SCH_1):TP_CPU0_RSVD_234
  AH15  TP_CPU0_RSVD_233  RSVD<233>  @BASEBOARD_FAB2_LIB.BASEBOARD_FAB2(SCH_1):TP_CPU0_RSVD_233
  AH19  TP_CPU0_RSVD_232  RSVD<232>  @BASEBOARD_FAB2_LIB.BASEBOARD_FAB2(SCH_1):TP_CPU0_RSVD_232
  AH55  TP_CPU0_RSVD_231  RSVD<231>  @BASEBOARD_FAB2_LIB.BASEBOARD_FAB2(SCH_1):TP_CPU0_RSVD_231
  AH57  TP_CPU0_RSVD_230  RSVD<230>  @BASEBOARD_FAB2_LIB.BASEBOARD_FAB2(SCH_1):TP_CPU0_RSVD_230
  AH71  TP_CPU0_RSVD_229  RSVD<229>  @BASEBOARD_FAB2_LIB.BASEBOARD_FAB2(SCH_1):TP_CPU0_RSVD_229
  AH73  TP_CPU0_RSVD_228  RSVD<228>  @BASEBOARD_FAB2_LIB.BASEBOARD_FAB2(SCH_1):TP_CPU0_RSVD_228
  AJ20  TP_CPU0_RSVD_227  RSVD<227>  @BASEBOARD_FAB2_LIB.BASEBOARD_FAB2(SCH_1):TP_CPU0_RSVD_227
  AJ56  TP_CPU0_RSVD_226  RSVD<226>  @BASEBOARD_FAB2_LIB.BASEBOARD_FAB2(SCH_1):TP_CPU0_RSVD_226
  AJ58  TP_CPU0_RSVD_225  RSVD<225>  @BASEBOARD_FAB2_LIB.BASEBOARD_FAB2(SCH_1):TP_CPU0_RSVD_225
  AJ60  TP_CPU0_RSVD_224  RSVD<224>  @BASEBOARD_FAB2_LIB.BASEBOARD_FAB2(SCH_1):TP_CPU0_RSVD_224
  AJ62  TP_CPU0_RSVD_223  RSVD<223>  @BASEBOARD_FAB2_LIB.BASEBOARD_FAB2(SCH_1):TP_CPU0_RSVD_223
  AJ70  TP_CPU0_RSVD_222  RSVD<222>  @BASEBOARD_FAB2_LIB.BASEBOARD_FAB2(SCH_1):TP_CPU0_RSVD_222
  AK57  TP_CPU0_RSVD_219  RSVD<219>  @BASEBOARD_FAB2_LIB.BASEBOARD_FAB2(SCH_1):TP_CPU0_RSVD_219
  AK59  TP_CPU0_RSVD_218  RSVD<218>  @BASEBOARD_FAB2_LIB.BASEBOARD_FAB2(SCH_1):TP_CPU0_RSVD_218
  AK61  TP_CPU0_RSVD_217  RSVD<217>  @BASEBOARD_FAB2_LIB.BASEBOARD_FAB2(SCH_1):TP_CPU0_RSVD_217
  AK69  TP_CPU0_RSVD_216  RSVD<216>  @BASEBOARD_FAB2_LIB.BASEBOARD_FAB2(SCH_1):TP_CPU0_RSVD_216
  AL22  TP_CPU0_RSVD_214  RSVD<214>  @BASEBOARD_FAB2_LIB.BASEBOARD_FAB2(SCH_1):TP_CPU0_RSVD_214
  AL58  TP_CPU0_RSVD_212  RSVD<212>  @BASEBOARD_FAB2_LIB.BASEBOARD_FAB2(SCH_1):TP_CPU0_RSVD_212
  AL60  TP_CPU0_RSVD_211  RSVD<211>  @BASEBOARD_FAB2_LIB.BASEBOARD_FAB2(SCH_1):TP_CPU0_RSVD_211
  AL62  TP_CPU0_RSVD_210  RSVD<210>  @BASEBOARD_FAB2_LIB.BASEBOARD_FAB2(SCH_1):TP_CPU0_RSVD_210
  AM23  TP_CPU0_RSVD_208  RSVD<208>  @BASEBOARD_FAB2_LIB.BASEBOARD_FAB2(SCH_1):TP_CPU0_RSVD_208
  AM59  TP_CPU0_RSVD_205  RSVD<205>  @BASEBOARD_FAB2_LIB.BASEBOARD_FAB2(SCH_1):TP_CPU0_RSVD_205
  AM61  TP_CPU0_RSVD_204  RSVD<204>  @BASEBOARD_FAB2_LIB.BASEBOARD_FAB2(SCH_1):TP_CPU0_RSVD_204
  AN60  TP_CPU0_RSVD_199  RSVD<199>  @BASEBOARD_FAB2_LIB.BASEBOARD_FAB2(SCH_1):TP_CPU0_RSVD_199
  AN62  TP_CPU0_RSVD_198  RSVD<198>  @BASEBOARD_FAB2_LIB.BASEBOARD_FAB2(SCH_1):TP_CPU0_RSVD_198
  AP61  TP_CPU0_RSVD_194  RSVD<194>  @BASEBOARD_FAB2_LIB.BASEBOARD_FAB2(SCH_1):TP_CPU0_RSVD_194
  AM21  PVCCMCP_CPU0   RSVD<209>  @BASEBOARD_FAB2_LIB.BASEBOARD_FAB2(SCH_1):PVCCMCP_CPU0
  AM25  PVCCMCP_CPU0   RSVD<207>  @BASEBOARD_FAB2_LIB.BASEBOARD_FAB2(SCH_1):PVCCMCP_CPU0
  AN18  PVCCMCP_CPU0   RSVD<203>  @BASEBOARD_FAB2_LIB.BASEBOARD_FAB2(SCH_1):PVCCMCP_CPU0
  AN22  PVCCMCP_CPU0   RSVD<202>  @BASEBOARD_FAB2_LIB.BASEBOARD_FAB2(SCH_1):PVCCMCP_CPU0
  AN24  PVCCMCP_CPU0   RSVD<201>  @BASEBOARD_FAB2_LIB.BASEBOARD_FAB2(SCH_1):PVCCMCP_CPU0
  AN26  PVCCMCP_CPU0   RSVD<200>  @BASEBOARD_FAB2_LIB.BASEBOARD_FAB2(SCH_1):PVCCMCP_CPU0
  AP23  PVCCMCP_CPU0   RSVD<197>  @BASEBOARD_FAB2_LIB.BASEBOARD_FAB2(SCH_1):PVCCMCP_CPU0
  AP25  PVCCMCP_CPU0   RSVD<196>  @BASEBOARD_FAB2_LIB.BASEBOARD_FAB2(SCH_1):PVCCMCP_CPU0
  AG46  PD_CPU0_RSVD_TEST_2  TEST_2  @BASEBOARD_FAB2_LIB.BASEBOARD_FAB2(SCH_1):PD_CPU0_RSVD_TEST_2
  AF45  PD_CPU0_RSVD_TEST_1  TEST_1  @BASEBOARD_FAB2_LIB.BASEBOARD_FAB2(SCH_1):PD_CPU0_RSVD_TEST_1
  AW12  PD_CPU0_DMIMODE_OVERRIDE  DMIMODE_OVERRIDE  @BASEBOARD_FAB2_LIB.BASEBOARD_FAB2(SCH_1):PD_CPU0_DMIMODE_OVERRIDE
  A14  P1V8_MCP_CPU0  RSVD<302>  @BASEBOARD_FAB2_LIB.BASEBOARD_FAB2(SCH_1):P1V8_MCP_CPU0
  A16  P1V8_MCP_CPU0  RSVD<301>  @BASEBOARD_FAB2_LIB.BASEBOARD_FAB2(SCH_1):P1V8_MCP_CPU0
  B13  P1V8_MCP_CPU0  RSVD<296>  @BASEBOARD_FAB2_LIB.BASEBOARD_FAB2(SCH_1):P1V8_MCP_CPU0
  B15  P1V8_MCP_CPU0  RSVD<295>  @BASEBOARD_FAB2_LIB.BASEBOARD_FAB2(SCH_1):P1V8_MCP_CPU0
  B17  P1V8_MCP_CPU0  RSVD<294>  @BASEBOARD_FAB2_LIB.BASEBOARD_FAB2(SCH_1):P1V8_MCP_CPU0
  AU14  H_CPU0_FIVR_FAULT_G  FIVR_FAULT  @BASEBOARD_FAB2_LIB.BASEBOARD_FAB2(SCH_1):H_CPU0_FIVR_FAULT_G
  Y23  FM_CPU0_RC_ERROR_N  RSVD<257>  @BASEBOARD_FAB2_LIB.BASEBOARD_FAB2(SCH_1):FM_CPU0_RC_ERROR_N
  AK27  CLK_322M_OSC_CPU0_RC_DP  RSVD<220>  @BASEBOARD_FAB2_LIB.BASEBOARD_FAB2(SCH_1):CLK_322M_OSC_CPU0_RC_DP
  AL26  CLK_322M_OSC_CPU0_RC_DN  RSVD<213>  @BASEBOARD_FAB2_LIB.BASEBOARD_FAB2(SCH_1):CLK_322M_OSC_CPU0_RC_DN
  AM27  CLK_100M_CPU0_RC_REFCLK0_DP  RSVD<206>  @BASEBOARD_FAB2_LIB.BASEBOARD_FAB2(SCH_1):CLK_100M_CPU0_RC_REFCLK0_DP
  AP27  CLK_100M_CPU0_RC_REFCLK0_DN  RSVD<195>  @BASEBOARD_FAB2_LIB.BASEBOARD_FAB2(SCH_1):CLK_100M_CPU0_RC_REFCLK0_DN

SKX_EXT_B_BGA1  I259  U5D1   [SKX_EXT_B_BGA1-IC,TBD]
  Y13  XDP_CPU_TRST_N  TRST_N  @BASEBOARD_FAB2_LIB.BASEBOARD_FAB2(SCH_1):XDP_CPU_TRST_N
  W14  XDP_CPU_TMS      TMS  @BASEBOARD_FAB2_LIB.BASEBOARD_FAB2(SCH_1):XDP_CPU_TMS
  AC14  XDP_CPU_TDI      TDI  @BASEBOARD_FAB2_LIB.BASEBOARD_FAB2(SCH_1):XDP_CPU_TDI
  AA14  XDP_CPU_TCK0     TCK  @BASEBOARD_FAB2_LIB.BASEBOARD_FAB2(SCH_1):XDP_CPU_TCK0
  AR12  XDP_CPU_PREQ_N  PREQ_N  @BASEBOARD_FAB2_LIB.BASEBOARD_FAB2(SCH_1):XDP_CPU_PREQ_N
  AG16  XDP_CPU_PRDY_N  PRDY_N  @BASEBOARD_FAB2_LIB.BASEBOARD_FAB2(SCH_1):XDP_CPU_PRDY_N
  AC12  XDP_CPU_OBSFN_B1_MBP7_N  BPM_N<7>  @BASEBOARD_FAB2_LIB.BASEBOARD_FAB2(SCH_1):XDP_CPU_OBSFN_B1_MBP7_N
  AE12  XDP_CPU_OBSFN_B0_MBP6_N  BPM_N<6>  @BASEBOARD_FAB2_LIB.BASEBOARD_FAB2(SCH_1):XDP_CPU_OBSFN_B0_MBP6_N
  AH11  XDP_CPU_MBP1_N  BPM_N<1>  @BASEBOARD_FAB2_LIB.BASEBOARD_FAB2(SCH_1):XDP_CPU_MBP1_N
  AJ10  XDP_CPU_MBP0_N  BPM_N<0>  @BASEBOARD_FAB2_LIB.BASEBOARD_FAB2(SCH_1):XDP_CPU_MBP0_N
  AE14  XDP_CPU0_TDO     TDO  @BASEBOARD_FAB2_LIB.BASEBOARD_FAB2(SCH_1):XDP_CPU0_TDO
  Y11  TP_XDP_CPU0_OBSDATA_A3_MBP5_N  BPM_N<5>  @BASEBOARD_FAB2_LIB.BASEBOARD_FAB2(SCH_1):TP_XDP_CPU0_OBSDATA_A3_MBP5_N
  AA12  TP_XDP_CPU0_OBSDATA_A2_MBP4_N  BPM_N<4>  @BASEBOARD_FAB2_LIB.BASEBOARD_FAB2(SCH_1):TP_XDP_CPU0_OBSDATA_A2_MBP4_N
  AF11  TP_XDP_CPU0_OBSDATA_A1_MBP3_N  BPM_N<3>  @BASEBOARD_FAB2_LIB.BASEBOARD_FAB2(SCH_1):TP_XDP_CPU0_OBSDATA_A1_MBP3_N
  AG10  TP_XDP_CPU0_OBSDATA_A0_MBP2_N  BPM_N<2>  @BASEBOARD_FAB2_LIB.BASEBOARD_FAB2(SCH_1):TP_XDP_CPU0_OBSDATA_A0_MBP2_N
  AP11  TP_NMI_CPU0      NMI  @BASEBOARD_FAB2_LIB.BASEBOARD_FAB2(SCH_1):TP_NMI_CPU0
  AU20  TP_CPU0_SOCKET_ID_2  SOCKET_ID<2>  @BASEBOARD_FAB2_LIB.BASEBOARD_FAB2(SCH_1):TP_CPU0_SOCKET_ID_2
  AB17  TP_CPU0_PROCDIS_G_N  PROCDIS_N  @BASEBOARD_FAB2_LIB.BASEBOARD_FAB2(SCH_1):TP_CPU0_PROCDIS_G_N
  AL18  TP_CPU0_PE_HP_SDA  PE_HP_SDA  @BASEBOARD_FAB2_LIB.BASEBOARD_FAB2(SCH_1):TP_CPU0_PE_HP_SDA
  AM19  TP_CPU0_PE_HP_SCL  PE_HP_SCL  @BASEBOARD_FAB2_LIB.BASEBOARD_FAB2(SCH_1):TP_CPU0_PE_HP_SCL
  DJ44  SVID_DIO1_CPU0  SVIDDATA<1>  @BASEBOARD_FAB2_LIB.BASEBOARD_FAB2(SCH_1):SVID_DIO1_CPU0
  DB45  SVID_DIO0_CPU0  SVIDDATA<0>  @BASEBOARD_FAB2_LIB.BASEBOARD_FAB2(SCH_1):SVID_DIO0_CPU0
  DG44  SVID_CLK1_CPU0  SVIDCLK<1>  @BASEBOARD_FAB2_LIB.BASEBOARD_FAB2(SCH_1):SVID_CLK1_CPU0
  DC44  SVID_CLK0_CPU0  SVIDCLK<0>  @BASEBOARD_FAB2_LIB.BASEBOARD_FAB2(SCH_1):SVID_CLK0_CPU0
  DL44  SVID_ALERT1_CPU0_N  SVIDALERT_N<1>  @BASEBOARD_FAB2_LIB.BASEBOARD_FAB2(SCH_1):SVID_ALERT1_CPU0_N
  DE44  SVID_ALERT0_CPU0_N  SVIDALERT_N<0>  @BASEBOARD_FAB2_LIB.BASEBOARD_FAB2(SCH_1):SVID_ALERT0_CPU0_N
  CW58  SMB_PIROM_CPU0_SDA  SMBDAT  @BASEBOARD_FAB2_LIB.BASEBOARD_FAB2(SCH_1):SMB_PIROM_CPU0_SDA
  CT59  SMB_PIROM_CPU0_SCL  SMBCLK  @BASEBOARD_FAB2_LIB.BASEBOARD_FAB2(SCH_1):SMB_PIROM_CPU0_SCL
  AD17  SMB_DDR_DEF_SDA_G_R  DDR345_SPDSDA  @BASEBOARD_FAB2_LIB.BASEBOARD_FAB2(SCH_1):SMB_DDR_DEF_SDA_G_R
  AE18  SMB_DDR_DEF_SCL_G_R  DDR345_SPDSCL  @BASEBOARD_FAB2_LIB.BASEBOARD_FAB2(SCH_1):SMB_DDR_DEF_SCL_G_R
  AF17  SMB_DDR_ABC_SDA_G_R  DDR012_SPDSDA  @BASEBOARD_FAB2_LIB.BASEBOARD_FAB2(SCH_1):SMB_DDR_ABC_SDA_G_R
  AJ18  SMB_DDR_ABC_SCL_G_R  DDR012_SPDSCL  @BASEBOARD_FAB2_LIB.BASEBOARD_FAB2(SCH_1):SMB_DDR_ABC_SCL_G_R
  AP21  RST_CPU0_G_N   RESET_N  @BASEBOARD_FAB2_LIB.BASEBOARD_FAB2(SCH_1):RST_CPU0_G_N
  BC24  PWRGD_CPU0_G   PWRGOOD  @BASEBOARD_FAB2_LIB.BASEBOARD_FAB2(SCH_1):PWRGD_CPU0_G
  CR28  PWRGD_CPU0_DRAMPWROK_DEF_G  DDR345_DRAM_PWR_OK  @BASEBOARD_FAB2_LIB.BASEBOARD_FAB2(SCH_1):PWRGD_CPU0_DRAMPWROK_DEF_G
  AN30  PWRGD_CPU0_DRAMPWROK_ABC_G  DDR012_DRAM_PWR_OK  @BASEBOARD_FAB2_LIB.BASEBOARD_FAB2(SCH_1):PWRGD_CPU0_DRAMPWROK_ABC_G
  AW18  PU_CPU0_TXT_AGENT  TXT_AGENT  @BASEBOARD_FAB2_LIB.BASEBOARD_FAB2(SCH_1):PU_CPU0_TXT_AGENT
  AM11  PU_CPU0_TSC_SYNC  TSC_SYNC  @BASEBOARD_FAB2_LIB.BASEBOARD_FAB2(SCH_1):PU_CPU0_TSC_SYNC
  AU16  PU_CPU0_SOCKET_ID_1  SOCKET_ID<1>  @BASEBOARD_FAB2_LIB.BASEBOARD_FAB2(SCH_1):PU_CPU0_SOCKET_ID_1
  AU22  PU_CPU0_SOCKET_ID_0  SOCKET_ID<0>  @BASEBOARD_FAB2_LIB.BASEBOARD_FAB2(SCH_1):PU_CPU0_SOCKET_ID_0
  AR18  PU_CPU0_SAFE_MODE_BOOT  SAFE_MODE_BOOT  @BASEBOARD_FAB2_LIB.BASEBOARD_FAB2(SCH_1):PU_CPU0_SAFE_MODE_BOOT
  AE20  PU_CPU0_LEGACY_SKT  LEGACY_SKT  @BASEBOARD_FAB2_LIB.BASEBOARD_FAB2(SCH_1):PU_CPU0_LEGACY_SKT
  AV17  PU_CPU0_FRMAGENT  FRMAGENT  @BASEBOARD_FAB2_LIB.BASEBOARD_FAB2(SCH_1):PU_CPU0_FRMAGENT
  AJ14  PU_CPU0_EAR_N  EAR_N  @BASEBOARD_FAB2_LIB.BASEBOARD_FAB2(SCH_1):PU_CPU0_EAR_N
  AU12  PECI_CPU_G      PECI  @BASEBOARD_FAB2_LIB.BASEBOARD_FAB2(SCH_1):PECI_CPU_G
  CW56  PD_PIROM_CPU0_ADDR2  PIROM_ADDR<2>  @BASEBOARD_FAB2_LIB.BASEBOARD_FAB2(SCH_1):PD_PIROM_CPU0_ADDR2
  CV57  PD_PIROM_CPU0_ADDR1  PIROM_ADDR<1>  @BASEBOARD_FAB2_LIB.BASEBOARD_FAB2(SCH_1):PD_PIROM_CPU0_ADDR1
  CU58  PD_PIROM_CPU0_ADDR0  PIROM_ADDR<0>  @BASEBOARD_FAB2_LIB.BASEBOARD_FAB2(SCH_1):PD_PIROM_CPU0_ADDR0
  AV15  PD_CPU0_TXT_PLTEN  TXT_PLTEN  @BASEBOARD_FAB2_LIB.BASEBOARD_FAB2(SCH_1):PD_CPU0_TXT_PLTEN
  DC50  PD_CPU0_TEST14  TEST_14  @BASEBOARD_FAB2_LIB.BASEBOARD_FAB2(SCH_1):PD_CPU0_TEST14
  DB51  PD_CPU0_TEST13  TEST_13  @BASEBOARD_FAB2_LIB.BASEBOARD_FAB2(SCH_1):PD_CPU0_TEST13
  AY19  PD_CPU0_TEST12  TEST_12  @BASEBOARD_FAB2_LIB.BASEBOARD_FAB2(SCH_1):PD_CPU0_TEST12
  AW14  PD_CPU0_KSFC_DIS  TEST_15  @BASEBOARD_FAB2_LIB.BASEBOARD_FAB2(SCH_1):PD_CPU0_KSFC_DIS
  BA20  PD_CPU0_BIST_ENABLE  BIST_ENABLE  @BASEBOARD_FAB2_LIB.BASEBOARD_FAB2(SCH_1):PD_CPU0_BIST_ENABLE
  CV61  M_F_CPU_VREF   DDR5_CAVREF  @BASEBOARD_FAB2_LIB.BASEBOARD_FAB2(SCH_1):M_F_CPU_VREF
  CT61  M_E_CPU_VREF   DDR4_CAVREF  @BASEBOARD_FAB2_LIB.BASEBOARD_FAB2(SCH_1):M_E_CPU_VREF
  CP61  M_D_CPU_VREF   DDR3_CAVREF  @BASEBOARD_FAB2_LIB.BASEBOARD_FAB2(SCH_1):M_D_CPU_VREF
  DV63  M_DEF_RST_N    DDR345_RESET_N  @BASEBOARD_FAB2_LIB.BASEBOARD_FAB2(SCH_1):M_DEF_RST_N
  AH63  M_C_CPU_VREF   DDR2_CAVREF  @BASEBOARD_FAB2_LIB.BASEBOARD_FAB2(SCH_1):M_C_CPU_VREF
  AK63  M_B_CPU_VREF   DDR1_CAVREF  @BASEBOARD_FAB2_LIB.BASEBOARD_FAB2(SCH_1):M_B_CPU_VREF
  AJ64  M_A_CPU_VREF   DDR0_CAVREF  @BASEBOARD_FAB2_LIB.BASEBOARD_FAB2(SCH_1):M_A_CPU_VREF
  U64  M_ABC_RST_N    DDR012_RESET_N  @BASEBOARD_FAB2_LIB.BASEBOARD_FAB2(SCH_1):M_ABC_RST_N
  AR14  H_PM_SYNC_GTL_R1  PMSYNC  @BASEBOARD_FAB2_LIB.BASEBOARD_FAB2(SCH_1):H_PM_SYNC_GTL_R1
  AT19  H_PMSYNC_CLK_24M_CPU0  PMSYNC_CLK  @BASEBOARD_FAB2_LIB.BASEBOARD_FAB2(SCH_1):H_PMSYNC_CLK_24M_CPU0
  AB15  H_CPU0_THERMTRIP_G_N  THERMTRIP_N  @BASEBOARD_FAB2_LIB.BASEBOARD_FAB2(SCH_1):H_CPU0_THERMTRIP_G_N
  AC16  H_CPU0_PROCHOT_G_N  PROCHOT_N  @BASEBOARD_FAB2_LIB.BASEBOARD_FAB2(SCH_1):H_CPU0_PROCHOT_G_N
  AN20  H_CPU0_MSMI_G_N  MSMI_N  @BASEBOARD_FAB2_LIB.BASEBOARD_FAB2(SCH_1):H_CPU0_MSMI_G_N
  AF13  H_CPU0_MEMDEF_MEMHOT_G_N  MEM_HOT_C345_N  @BASEBOARD_FAB2_LIB.BASEBOARD_FAB2(SCH_1):H_CPU0_MEMDEF_MEMHOT_G_N
  AH13  H_CPU0_MEMABC_MEMHOT_G_N  MEM_HOT_C012_N  @BASEBOARD_FAB2_LIB.BASEBOARD_FAB2(SCH_1):H_CPU0_MEMABC_MEMHOT_G_N
  AF15  H_CPU0_FAST_WAKE_N  PM_FAST_WAKE_N  @BASEBOARD_FAB2_LIB.BASEBOARD_FAB2(SCH_1):H_CPU0_FAST_WAKE_N
  AL12  H_CPU0_ERR2_G_N  ERROR_N<2>  @BASEBOARD_FAB2_LIB.BASEBOARD_FAB2(SCH_1):H_CPU0_ERR2_G_N
  AK11  H_CPU0_ERR1_G_N  ERROR_N<1>  @BASEBOARD_FAB2_LIB.BASEBOARD_FAB2(SCH_1):H_CPU0_ERR1_G_N
  AJ12  H_CPU0_ERR0_G_N  ERROR_N<0>  @BASEBOARD_FAB2_LIB.BASEBOARD_FAB2(SCH_1):H_CPU0_ERR0_G_N
  AL14  H_CPU0_CATERR_G_N  CATERR_N  @BASEBOARD_FAB2_LIB.BASEBOARD_FAB2(SCH_1):H_CPU0_CATERR_G_N
  BD23  H_CPU0_BMCINIT  BMCINIT  @BASEBOARD_FAB2_LIB.BASEBOARD_FAB2(SCH_1):H_CPU0_BMCINIT
  CV59  FM_CPU0_SM_WP  SM_WP  @BASEBOARD_FAB2_LIB.BASEBOARD_FAB2(SCH_1):FM_CPU0_SM_WP
  AB13  FM_CPU0_SKTOCC_LVT3_N  SKTOCC_N  @BASEBOARD_FAB2_LIB.BASEBOARD_FAB2(SCH_1):FM_CPU0_SKTOCC_LVT3_N
  DB71  FM_CPU0_PROC_ID1  PROC_ID<1>  @BASEBOARD_FAB2_LIB.BASEBOARD_FAB2(SCH_1):FM_CPU0_PROC_ID1
  CY71  FM_CPU0_PROC_ID0  PROC_ID<0>  @BASEBOARD_FAB2_LIB.BASEBOARD_FAB2(SCH_1):FM_CPU0_PROC_ID0
  DA72  FM_CPU0_PKGID2  PKGID<2>  @BASEBOARD_FAB2_LIB.BASEBOARD_FAB2(SCH_1):FM_CPU0_PKGID2
  CW72  FM_CPU0_PKGID1  PKGID<1>  @BASEBOARD_FAB2_LIB.BASEBOARD_FAB2(SCH_1):FM_CPU0_PKGID1
  DC72  FM_CPU0_PKGID0  PKGID<0>  @BASEBOARD_FAB2_LIB.BASEBOARD_FAB2(SCH_1):FM_CPU0_PKGID0
  CU26  CLK_100M_CPU0_BCLK2_DP  BCLK2_DP  @BASEBOARD_FAB2_LIB.BASEBOARD_FAB2(SCH_1):CLK_100M_CPU0_BCLK2_DP
  CT25  CLK_100M_CPU0_BCLK2_DN  BCLK2_DN  @BASEBOARD_FAB2_LIB.BASEBOARD_FAB2(SCH_1):CLK_100M_CPU0_BCLK2_DN
  CP27  CLK_100M_CPU0_BCLK1_DP  BCLK1_DP  @BASEBOARD_FAB2_LIB.BASEBOARD_FAB2(SCH_1):CLK_100M_CPU0_BCLK1_DP
  CR26  CLK_100M_CPU0_BCLK1_DN  BCLK1_DN  @BASEBOARD_FAB2_LIB.BASEBOARD_FAB2(SCH_1):CLK_100M_CPU0_BCLK1_DN
  AW24  CLK_100M_CPU0_BCLK0_DP  BCLK0_DP  @BASEBOARD_FAB2_LIB.BASEBOARD_FAB2(SCH_1):CLK_100M_CPU0_BCLK0_DP
  AU24  CLK_100M_CPU0_BCLK0_DN  BCLK0_DN  @BASEBOARD_FAB2_LIB.BASEBOARD_FAB2(SCH_1):CLK_100M_CPU0_BCLK0_DN
  CK29  A_CPU0_UPI2_RBIAS  UPI2_RBIAS<1>  @BASEBOARD_FAB2_LIB.BASEBOARD_FAB2(SCH_1):A_CPU0_UPI2_RBIAS
  CL28  A_CPU0_UPI2_RBIAS  UPI2_RBIAS<0>  @BASEBOARD_FAB2_LIB.BASEBOARD_FAB2(SCH_1):A_CPU0_UPI2_RBIAS
  AP29  A_CPU0_UPI01_RBIAS  UPI01_RBIAS<1>  @BASEBOARD_FAB2_LIB.BASEBOARD_FAB2(SCH_1):A_CPU0_UPI01_RBIAS
  AT29  A_CPU0_UPI01_RBIAS  UPI01_RBIAS<0>  @BASEBOARD_FAB2_LIB.BASEBOARD_FAB2(SCH_1):A_CPU0_UPI01_RBIAS
  CR30  A_CPU0_PE3_RBIAS  PE3_RBIAS<1>  @BASEBOARD_FAB2_LIB.BASEBOARD_FAB2(SCH_1):A_CPU0_PE3_RBIAS
  CP29  A_CPU0_PE3_RBIAS  PE3_RBIAS<0>  @BASEBOARD_FAB2_LIB.BASEBOARD_FAB2(SCH_1):A_CPU0_PE3_RBIAS
  CL30  A_CPU0_PE012_RBIAS  PE012_RBIAS<1>  @BASEBOARD_FAB2_LIB.BASEBOARD_FAB2(SCH_1):A_CPU0_PE012_RBIAS
  CN30  A_CPU0_PE012_RBIAS  PE012_RBIAS<0>  @BASEBOARD_FAB2_LIB.BASEBOARD_FAB2(SCH_1):A_CPU0_PE012_RBIAS
  CT31  A_CPU0_MCP01_RBIAS  MCP01_RBIAS<1>  @BASEBOARD_FAB2_LIB.BASEBOARD_FAB2(SCH_1):A_CPU0_MCP01_RBIAS
  CU32  A_CPU0_MCP01_RBIAS  MCP01_RBIAS<0>  @BASEBOARD_FAB2_LIB.BASEBOARD_FAB2(SCH_1):A_CPU0_MCP01_RBIAS
  DD49  A_CPU0_DEF_RCOMP2  DDR345_RCOMP<2>  @BASEBOARD_FAB2_LIB.BASEBOARD_FAB2(SCH_1):A_CPU0_DEF_RCOMP2
  DD47  A_CPU0_DEF_RCOMP1  DDR345_RCOMP<1>  @BASEBOARD_FAB2_LIB.BASEBOARD_FAB2(SCH_1):A_CPU0_DEF_RCOMP1
  DC48  A_CPU0_DEF_RCOMP0  DDR345_RCOMP<0>  @BASEBOARD_FAB2_LIB.BASEBOARD_FAB2(SCH_1):A_CPU0_DEF_RCOMP0
  AC42  A_CPU0_ABC_RCOMP2  DDR012_RCOMP<2>  @BASEBOARD_FAB2_LIB.BASEBOARD_FAB2(SCH_1):A_CPU0_ABC_RCOMP2
  AB43  A_CPU0_ABC_RCOMP1  DDR012_RCOMP<1>  @BASEBOARD_FAB2_LIB.BASEBOARD_FAB2(SCH_1):A_CPU0_ABC_RCOMP1
  Y43  A_CPU0_ABC_RCOMP0  DDR012_RCOMP<0>  @BASEBOARD_FAB2_LIB.BASEBOARD_FAB2(SCH_1):A_CPU0_ABC_RCOMP0

PCA9617_SSOP  I15  U6F1   [PCA9617_SSOP-IC,G81764-001-GNDA]
    5  TP_SMB_DDR_ABC_EN     EN  @BASEBOARD_FAB2_LIB.BASEBOARD_FAB2(SCH_1):TP_SMB_DDR_ABC_EN
    6  SMB_DDR_ABC_VPP_SDA_R   SDAB  @BASEBOARD_FAB2_LIB.BASEBOARD_FAB2(SCH_1):SMB_DDR_ABC_VPP_SDA_R
    7  SMB_DDR_ABC_VPP_SCL_R   SCLB  @BASEBOARD_FAB2_LIB.BASEBOARD_FAB2(SCH_1):SMB_DDR_ABC_VPP_SCL_R
    3  SMB_DDR_ABC_SDA_G   SDAA  @BASEBOARD_FAB2_LIB.BASEBOARD_FAB2(SCH_1):SMB_DDR_ABC_SDA_G
    2  SMB_DDR_ABC_SCL_G   SCLA  @BASEBOARD_FAB2_LIB.BASEBOARD_FAB2(SCH_1):SMB_DDR_ABC_SCL_G
    8  PVPP_ABC        VCCB  @BASEBOARD_FAB2_LIB.BASEBOARD_FAB2(SCH_1):PVPP_ABC
    1  PVCCIO_CPU0     VCCA  @BASEBOARD_FAB2_LIB.BASEBOARD_FAB2(SCH_1):PVCCIO_CPU0

74CBTLV1G125  I190  U6M1   [74CBTLV1G125_SMLF-IC,C88177-00A]
    2  P1V8_MCP_CPU1      A  @BASEBOARD_FAB2_LIB.BASEBOARD_FAB2(SCH_1):P1V8_MCP_CPU1
    4  JTAG_MCP_CPU1_TDI_R      B  @BASEBOARD_FAB2_LIB.BASEBOARD_FAB2(SCH_1):JTAG_MCP_CPU1_TDI_R
    1  FM_CPU1_PKGID1   OE_N  @BASEBOARD_FAB2_LIB.BASEBOARD_FAB2(SCH_1):FM_CPU1_PKGID1

LBG_CORE_QAT_EXT_D  I15  U7C1   [LBG_CORE_QAT_EXT_D_BGA1-IC,H91A]
  BK24  GND            VSS<74>  @BASEBOARD_FAB2_LIB.BASEBOARD_FAB2(SCH_1):GND
  BK27  GND            VSS<73>  @BASEBOARD_FAB2_LIB.BASEBOARD_FAB2(SCH_1):GND
  BK31  GND            VSS<72>  @BASEBOARD_FAB2_LIB.BASEBOARD_FAB2(SCH_1):GND
  BK35  GND            VSS<71>  @BASEBOARD_FAB2_LIB.BASEBOARD_FAB2(SCH_1):GND
  BK38  GND            VSS<70>  @BASEBOARD_FAB2_LIB.BASEBOARD_FAB2(SCH_1):GND
  BK42  GND            VSS<69>  @BASEBOARD_FAB2_LIB.BASEBOARD_FAB2(SCH_1):GND
  BK50  GND            VSS<68>  @BASEBOARD_FAB2_LIB.BASEBOARD_FAB2(SCH_1):GND
  BL22  GND            VSS<67>  @BASEBOARD_FAB2_LIB.BASEBOARD_FAB2(SCH_1):GND
  BL40  GND            VSS<66>  @BASEBOARD_FAB2_LIB.BASEBOARD_FAB2(SCH_1):GND
  BL68  GND            VSS<65>  @BASEBOARD_FAB2_LIB.BASEBOARD_FAB2(SCH_1):GND
  BL37  GND            VSS<64>  @BASEBOARD_FAB2_LIB.BASEBOARD_FAB2(SCH_1):GND
  BL5  GND            VSS<63>  @BASEBOARD_FAB2_LIB.BASEBOARD_FAB2(SCH_1):GND
  BL63  GND            VSS<62>  @BASEBOARD_FAB2_LIB.BASEBOARD_FAB2(SCH_1):GND
  BL70  GND            VSS<61>  @BASEBOARD_FAB2_LIB.BASEBOARD_FAB2(SCH_1):GND
  BL72  GND            VSS<60>  @BASEBOARD_FAB2_LIB.BASEBOARD_FAB2(SCH_1):GND
  BM13  GND            VSS<59>  @BASEBOARD_FAB2_LIB.BASEBOARD_FAB2(SCH_1):GND
  BM17  GND            VSS<58>  @BASEBOARD_FAB2_LIB.BASEBOARD_FAB2(SCH_1):GND
  BN37  GND            VSS<57>  @BASEBOARD_FAB2_LIB.BASEBOARD_FAB2(SCH_1):GND
  BM46  GND            VSS<56>  @BASEBOARD_FAB2_LIB.BASEBOARD_FAB2(SCH_1):GND
  BM50  GND            VSS<55>  @BASEBOARD_FAB2_LIB.BASEBOARD_FAB2(SCH_1):GND
  BM58  GND            VSS<54>  @BASEBOARD_FAB2_LIB.BASEBOARD_FAB2(SCH_1):GND
  BM69  GND            VSS<53>  @BASEBOARD_FAB2_LIB.BASEBOARD_FAB2(SCH_1):GND
  BM71  GND            VSS<52>  @BASEBOARD_FAB2_LIB.BASEBOARD_FAB2(SCH_1):GND
  BM9  GND            VSS<51>  @BASEBOARD_FAB2_LIB.BASEBOARD_FAB2(SCH_1):GND
  BN22  GND            VSS<50>  @BASEBOARD_FAB2_LIB.BASEBOARD_FAB2(SCH_1):GND
  BN59  GND            VSS<49>  @BASEBOARD_FAB2_LIB.BASEBOARD_FAB2(SCH_1):GND
  BN5  GND            VSS<48>  @BASEBOARD_FAB2_LIB.BASEBOARD_FAB2(SCH_1):GND
  BN52  GND            VSS<47>  @BASEBOARD_FAB2_LIB.BASEBOARD_FAB2(SCH_1):GND
  BN66  GND            VSS<46>  @BASEBOARD_FAB2_LIB.BASEBOARD_FAB2(SCH_1):GND
  BR20  GND            VSS<45>  @BASEBOARD_FAB2_LIB.BASEBOARD_FAB2(SCH_1):GND
  BR50  GND            VSS<44>  @BASEBOARD_FAB2_LIB.BASEBOARD_FAB2(SCH_1):GND
  BT8  GND            VSS<43>  @BASEBOARD_FAB2_LIB.BASEBOARD_FAB2(SCH_1):GND
  BR54  GND            VSS<42>  @BASEBOARD_FAB2_LIB.BASEBOARD_FAB2(SCH_1):GND
  BR58  GND            VSS<41>  @BASEBOARD_FAB2_LIB.BASEBOARD_FAB2(SCH_1):GND
  BR6  GND            VSS<40>  @BASEBOARD_FAB2_LIB.BASEBOARD_FAB2(SCH_1):GND
  BT66  GND            VSS<39>  @BASEBOARD_FAB2_LIB.BASEBOARD_FAB2(SCH_1):GND
  BU13  GND            VSS<38>  @BASEBOARD_FAB2_LIB.BASEBOARD_FAB2(SCH_1):GND
  BU11  GND            VSS<37>  @BASEBOARD_FAB2_LIB.BASEBOARD_FAB2(SCH_1):GND
  BV49  GND            VSS<36>  @BASEBOARD_FAB2_LIB.BASEBOARD_FAB2(SCH_1):GND
  BU15  GND            VSS<35>  @BASEBOARD_FAB2_LIB.BASEBOARD_FAB2(SCH_1):GND
  BU18  GND            VSS<34>  @BASEBOARD_FAB2_LIB.BASEBOARD_FAB2(SCH_1):GND
  BU20  GND            VSS<33>  @BASEBOARD_FAB2_LIB.BASEBOARD_FAB2(SCH_1):GND
  BU22  GND            VSS<32>  @BASEBOARD_FAB2_LIB.BASEBOARD_FAB2(SCH_1):GND
  BU24  GND            VSS<31>  @BASEBOARD_FAB2_LIB.BASEBOARD_FAB2(SCH_1):GND
  BU26  GND            VSS<30>  @BASEBOARD_FAB2_LIB.BASEBOARD_FAB2(SCH_1):GND
  BU28  GND            VSS<29>  @BASEBOARD_FAB2_LIB.BASEBOARD_FAB2(SCH_1):GND
  BU30  GND            VSS<28>  @BASEBOARD_FAB2_LIB.BASEBOARD_FAB2(SCH_1):GND
  BU32  GND            VSS<27>  @BASEBOARD_FAB2_LIB.BASEBOARD_FAB2(SCH_1):GND
  BU34  GND            VSS<26>  @BASEBOARD_FAB2_LIB.BASEBOARD_FAB2(SCH_1):GND
  BU37  GND            VSS<25>  @BASEBOARD_FAB2_LIB.BASEBOARD_FAB2(SCH_1):GND
  BU39  GND            VSS<24>  @BASEBOARD_FAB2_LIB.BASEBOARD_FAB2(SCH_1):GND
  BU41  GND            VSS<23>  @BASEBOARD_FAB2_LIB.BASEBOARD_FAB2(SCH_1):GND
  BU43  GND            VSS<22>  @BASEBOARD_FAB2_LIB.BASEBOARD_FAB2(SCH_1):GND
  BU45  GND            VSS<21>  @BASEBOARD_FAB2_LIB.BASEBOARD_FAB2(SCH_1):GND
  BU48  GND            VSS<20>  @BASEBOARD_FAB2_LIB.BASEBOARD_FAB2(SCH_1):GND
  BU50  GND            VSS<19>  @BASEBOARD_FAB2_LIB.BASEBOARD_FAB2(SCH_1):GND
  BU52  GND            VSS<18>  @BASEBOARD_FAB2_LIB.BASEBOARD_FAB2(SCH_1):GND
  BU54  GND            VSS<17>  @BASEBOARD_FAB2_LIB.BASEBOARD_FAB2(SCH_1):GND
  BU57  GND            VSS<16>  @BASEBOARD_FAB2_LIB.BASEBOARD_FAB2(SCH_1):GND
  BU59  GND            VSS<15>  @BASEBOARD_FAB2_LIB.BASEBOARD_FAB2(SCH_1):GND
  BU61  GND            VSS<14>  @BASEBOARD_FAB2_LIB.BASEBOARD_FAB2(SCH_1):GND
  BU63  GND            VSS<13>  @BASEBOARD_FAB2_LIB.BASEBOARD_FAB2(SCH_1):GND
  BU9  GND            VSS<12>  @BASEBOARD_FAB2_LIB.BASEBOARD_FAB2(SCH_1):GND
  BV40  GND            VSS<11>  @BASEBOARD_FAB2_LIB.BASEBOARD_FAB2(SCH_1):GND
  BW15  GND            VSS<10>  @BASEBOARD_FAB2_LIB.BASEBOARD_FAB2(SCH_1):GND
  BW18  GND            VSS<9>  @BASEBOARD_FAB2_LIB.BASEBOARD_FAB2(SCH_1):GND
  BW26  GND            VSS<8>  @BASEBOARD_FAB2_LIB.BASEBOARD_FAB2(SCH_1):GND
  BW52  GND            VSS<7>  @BASEBOARD_FAB2_LIB.BASEBOARD_FAB2(SCH_1):GND
  BY40  GND            VSS<6>  @BASEBOARD_FAB2_LIB.BASEBOARD_FAB2(SCH_1):GND
  BY49  GND            VSS<5>  @BASEBOARD_FAB2_LIB.BASEBOARD_FAB2(SCH_1):GND
  CA15  GND            VSS<4>  @BASEBOARD_FAB2_LIB.BASEBOARD_FAB2(SCH_1):GND
  CA18  GND            VSS<3>  @BASEBOARD_FAB2_LIB.BASEBOARD_FAB2(SCH_1):GND
  CA26  GND            VSS<2>  @BASEBOARD_FAB2_LIB.BASEBOARD_FAB2(SCH_1):GND
  CA50  GND            VSS<1>  @BASEBOARD_FAB2_LIB.BASEBOARD_FAB2(SCH_1):GND
  CA52  GND            VSS<0>  @BASEBOARD_FAB2_LIB.BASEBOARD_FAB2(SCH_1):GND

LBG_CORE_QAT_EXT_D  I16  U7C1   [LBG_CORE_QAT_EXT_D_BGA1-IC,H91A]
  AL68  GND            VSS<214>  @BASEBOARD_FAB2_LIB.BASEBOARD_FAB2(SCH_1):GND
  AL70  GND            VSS<213>  @BASEBOARD_FAB2_LIB.BASEBOARD_FAB2(SCH_1):GND
  AL72  GND            VSS<212>  @BASEBOARD_FAB2_LIB.BASEBOARD_FAB2(SCH_1):GND
  AM26  GND            VSS<211>  @BASEBOARD_FAB2_LIB.BASEBOARD_FAB2(SCH_1):GND
  AM30  GND            VSS<210>  @BASEBOARD_FAB2_LIB.BASEBOARD_FAB2(SCH_1):GND
  AM41  GND            VSS<209>  @BASEBOARD_FAB2_LIB.BASEBOARD_FAB2(SCH_1):GND
  AM46  GND            VSS<208>  @BASEBOARD_FAB2_LIB.BASEBOARD_FAB2(SCH_1):GND
  AN13  GND            VSS<207>  @BASEBOARD_FAB2_LIB.BASEBOARD_FAB2(SCH_1):GND
  AN17  GND            VSS<206>  @BASEBOARD_FAB2_LIB.BASEBOARD_FAB2(SCH_1):GND
  AN68  GND            VSS<205>  @BASEBOARD_FAB2_LIB.BASEBOARD_FAB2(SCH_1):GND
  AP22  GND            VSS<204>  @BASEBOARD_FAB2_LIB.BASEBOARD_FAB2(SCH_1):GND
  AN20  GND            VSS<203>  @BASEBOARD_FAB2_LIB.BASEBOARD_FAB2(SCH_1):GND
  AN5  GND            VSS<202>  @BASEBOARD_FAB2_LIB.BASEBOARD_FAB2(SCH_1):GND
  AN58  GND            VSS<201>  @BASEBOARD_FAB2_LIB.BASEBOARD_FAB2(SCH_1):GND
  AN9  GND            VSS<200>  @BASEBOARD_FAB2_LIB.BASEBOARD_FAB2(SCH_1):GND
  AP2  GND            VSS<199>  @BASEBOARD_FAB2_LIB.BASEBOARD_FAB2(SCH_1):GND
  AP26  GND            VSS<198>  @BASEBOARD_FAB2_LIB.BASEBOARD_FAB2(SCH_1):GND
  AP30  GND            VSS<197>  @BASEBOARD_FAB2_LIB.BASEBOARD_FAB2(SCH_1):GND
  AP4  GND            VSS<196>  @BASEBOARD_FAB2_LIB.BASEBOARD_FAB2(SCH_1):GND
  AP41  GND            VSS<195>  @BASEBOARD_FAB2_LIB.BASEBOARD_FAB2(SCH_1):GND
  AP46  GND            VSS<194>  @BASEBOARD_FAB2_LIB.BASEBOARD_FAB2(SCH_1):GND
  AP52  GND            VSS<193>  @BASEBOARD_FAB2_LIB.BASEBOARD_FAB2(SCH_1):GND
  AP66  GND            VSS<192>  @BASEBOARD_FAB2_LIB.BASEBOARD_FAB2(SCH_1):GND
  AR5  GND            VSS<191>  @BASEBOARD_FAB2_LIB.BASEBOARD_FAB2(SCH_1):GND
  AR50  GND            VSS<190>  @BASEBOARD_FAB2_LIB.BASEBOARD_FAB2(SCH_1):GND
  AR58  GND            VSS<189>  @BASEBOARD_FAB2_LIB.BASEBOARD_FAB2(SCH_1):GND
  AR65  GND            VSS<188>  @BASEBOARD_FAB2_LIB.BASEBOARD_FAB2(SCH_1):GND
  AR68  GND            VSS<187>  @BASEBOARD_FAB2_LIB.BASEBOARD_FAB2(SCH_1):GND
  AR70  GND            VSS<186>  @BASEBOARD_FAB2_LIB.BASEBOARD_FAB2(SCH_1):GND
  AR72  GND            VSS<185>  @BASEBOARD_FAB2_LIB.BASEBOARD_FAB2(SCH_1):GND
  AT7  GND            VSS<184>  @BASEBOARD_FAB2_LIB.BASEBOARD_FAB2(SCH_1):GND
  AT11  GND            VSS<183>  @BASEBOARD_FAB2_LIB.BASEBOARD_FAB2(SCH_1):GND
  AT15  GND            VSS<182>  @BASEBOARD_FAB2_LIB.BASEBOARD_FAB2(SCH_1):GND
  AT18  GND            VSS<181>  @BASEBOARD_FAB2_LIB.BASEBOARD_FAB2(SCH_1):GND
  AT22  GND            VSS<180>  @BASEBOARD_FAB2_LIB.BASEBOARD_FAB2(SCH_1):GND
  AT26  GND            VSS<179>  @BASEBOARD_FAB2_LIB.BASEBOARD_FAB2(SCH_1):GND
  AT30  GND            VSS<178>  @BASEBOARD_FAB2_LIB.BASEBOARD_FAB2(SCH_1):GND
  AT41  GND            VSS<177>  @BASEBOARD_FAB2_LIB.BASEBOARD_FAB2(SCH_1):GND
  AT46  GND            VSS<176>  @BASEBOARD_FAB2_LIB.BASEBOARD_FAB2(SCH_1):GND
  AT59  GND            VSS<175>  @BASEBOARD_FAB2_LIB.BASEBOARD_FAB2(SCH_1):GND
  AU26  GND            VSS<174>  @BASEBOARD_FAB2_LIB.BASEBOARD_FAB2(SCH_1):GND
  AU30  GND            VSS<173>  @BASEBOARD_FAB2_LIB.BASEBOARD_FAB2(SCH_1):GND
  AE22  GND            VSS<172>  @BASEBOARD_FAB2_LIB.BASEBOARD_FAB2(SCH_1):GND
  AU41  GND            VSS<171>  @BASEBOARD_FAB2_LIB.BASEBOARD_FAB2(SCH_1):GND
  AU46  GND            VSS<170>  @BASEBOARD_FAB2_LIB.BASEBOARD_FAB2(SCH_1):GND
  AU50  GND            VSS<169>  @BASEBOARD_FAB2_LIB.BASEBOARD_FAB2(SCH_1):GND
  AU54  GND            VSS<168>  @BASEBOARD_FAB2_LIB.BASEBOARD_FAB2(SCH_1):GND
  AU61  GND            VSS<167>  @BASEBOARD_FAB2_LIB.BASEBOARD_FAB2(SCH_1):GND
  AV5  GND            VSS<166>  @BASEBOARD_FAB2_LIB.BASEBOARD_FAB2(SCH_1):GND
  AV22  GND            VSS<165>  @BASEBOARD_FAB2_LIB.BASEBOARD_FAB2(SCH_1):GND
  AV59  GND            VSS<164>  @BASEBOARD_FAB2_LIB.BASEBOARD_FAB2(SCH_1):GND
  AV68  GND            VSS<163>  @BASEBOARD_FAB2_LIB.BASEBOARD_FAB2(SCH_1):GND
  AW9  GND            VSS<162>  @BASEBOARD_FAB2_LIB.BASEBOARD_FAB2(SCH_1):GND
  AW13  GND            VSS<161>  @BASEBOARD_FAB2_LIB.BASEBOARD_FAB2(SCH_1):GND
  AW17  GND            VSS<160>  @BASEBOARD_FAB2_LIB.BASEBOARD_FAB2(SCH_1):GND
  AW26  GND            VSS<159>  @BASEBOARD_FAB2_LIB.BASEBOARD_FAB2(SCH_1):GND
  AW30  GND            VSS<158>  @BASEBOARD_FAB2_LIB.BASEBOARD_FAB2(SCH_1):GND
  AW32  GND            VSS<157>  @BASEBOARD_FAB2_LIB.BASEBOARD_FAB2(SCH_1):GND
  AW34  GND            VSS<156>  @BASEBOARD_FAB2_LIB.BASEBOARD_FAB2(SCH_1):GND
  AW36  GND            VSS<155>  @BASEBOARD_FAB2_LIB.BASEBOARD_FAB2(SCH_1):GND
  AW37  GND            VSS<154>  @BASEBOARD_FAB2_LIB.BASEBOARD_FAB2(SCH_1):GND
  AW39  GND            VSS<153>  @BASEBOARD_FAB2_LIB.BASEBOARD_FAB2(SCH_1):GND
  AW41  GND            VSS<152>  @BASEBOARD_FAB2_LIB.BASEBOARD_FAB2(SCH_1):GND
  AW46  GND            VSS<151>  @BASEBOARD_FAB2_LIB.BASEBOARD_FAB2(SCH_1):GND
  AW50  GND            VSS<150>  @BASEBOARD_FAB2_LIB.BASEBOARD_FAB2(SCH_1):GND
  AW58  GND            VSS<149>  @BASEBOARD_FAB2_LIB.BASEBOARD_FAB2(SCH_1):GND
  AW61  GND            VSS<148>  @BASEBOARD_FAB2_LIB.BASEBOARD_FAB2(SCH_1):GND
  AY5  GND            VSS<147>  @BASEBOARD_FAB2_LIB.BASEBOARD_FAB2(SCH_1):GND
  AY22  GND            VSS<146>  @BASEBOARD_FAB2_LIB.BASEBOARD_FAB2(SCH_1):GND
  AY56  GND            VSS<145>  @BASEBOARD_FAB2_LIB.BASEBOARD_FAB2(SCH_1):GND
  AY63  GND            VSS<144>  @BASEBOARD_FAB2_LIB.BASEBOARD_FAB2(SCH_1):GND
  AY68  GND            VSS<143>  @BASEBOARD_FAB2_LIB.BASEBOARD_FAB2(SCH_1):GND
  BA50  GND            VSS<142>  @BASEBOARD_FAB2_LIB.BASEBOARD_FAB2(SCH_1):GND
  BA54  GND            VSS<141>  @BASEBOARD_FAB2_LIB.BASEBOARD_FAB2(SCH_1):GND
  BA58  GND            VSS<140>  @BASEBOARD_FAB2_LIB.BASEBOARD_FAB2(SCH_1):GND
  BB5  GND            VSS<139>  @BASEBOARD_FAB2_LIB.BASEBOARD_FAB2(SCH_1):GND
  BB7  GND            VSS<138>  @BASEBOARD_FAB2_LIB.BASEBOARD_FAB2(SCH_1):GND
  BB11  GND            VSS<137>  @BASEBOARD_FAB2_LIB.BASEBOARD_FAB2(SCH_1):GND
  BB15  GND            VSS<136>  @BASEBOARD_FAB2_LIB.BASEBOARD_FAB2(SCH_1):GND
  BB18  GND            VSS<135>  @BASEBOARD_FAB2_LIB.BASEBOARD_FAB2(SCH_1):GND
  BB22  GND            VSS<134>  @BASEBOARD_FAB2_LIB.BASEBOARD_FAB2(SCH_1):GND
  BB44  GND            VSS<133>  @BASEBOARD_FAB2_LIB.BASEBOARD_FAB2(SCH_1):GND
  BB59  GND            VSS<132>  @BASEBOARD_FAB2_LIB.BASEBOARD_FAB2(SCH_1):GND
  BB66  GND            VSS<131>  @BASEBOARD_FAB2_LIB.BASEBOARD_FAB2(SCH_1):GND
  BB68  GND            VSS<130>  @BASEBOARD_FAB2_LIB.BASEBOARD_FAB2(SCH_1):GND
  BB70  GND            VSS<129>  @BASEBOARD_FAB2_LIB.BASEBOARD_FAB2(SCH_1):GND
  BB72  GND            VSS<128>  @BASEBOARD_FAB2_LIB.BASEBOARD_FAB2(SCH_1):GND
  BC69  GND            VSS<127>  @BASEBOARD_FAB2_LIB.BASEBOARD_FAB2(SCH_1):GND
  BC71  GND            VSS<126>  @BASEBOARD_FAB2_LIB.BASEBOARD_FAB2(SCH_1):GND
  BD24  GND            VSS<125>  @BASEBOARD_FAB2_LIB.BASEBOARD_FAB2(SCH_1):GND
  BD27  GND            VSS<124>  @BASEBOARD_FAB2_LIB.BASEBOARD_FAB2(SCH_1):GND
  BD31  GND            VSS<123>  @BASEBOARD_FAB2_LIB.BASEBOARD_FAB2(SCH_1):GND
  BD35  GND            VSS<122>  @BASEBOARD_FAB2_LIB.BASEBOARD_FAB2(SCH_1):GND
  BD5  GND            VSS<121>  @BASEBOARD_FAB2_LIB.BASEBOARD_FAB2(SCH_1):GND
  BD50  GND            VSS<120>  @BASEBOARD_FAB2_LIB.BASEBOARD_FAB2(SCH_1):GND
  BD54  GND            VSS<119>  @BASEBOARD_FAB2_LIB.BASEBOARD_FAB2(SCH_1):GND
  BD68  GND            VSS<118>  @BASEBOARD_FAB2_LIB.BASEBOARD_FAB2(SCH_1):GND
  BE29  GND            VSS<117>  @BASEBOARD_FAB2_LIB.BASEBOARD_FAB2(SCH_1):GND
  BE33  GND            VSS<116>  @BASEBOARD_FAB2_LIB.BASEBOARD_FAB2(SCH_1):GND
  BE37  GND            VSS<115>  @BASEBOARD_FAB2_LIB.BASEBOARD_FAB2(SCH_1):GND
  BE56  GND            VSS<114>  @BASEBOARD_FAB2_LIB.BASEBOARD_FAB2(SCH_1):GND
  BE59  GND            VSS<113>  @BASEBOARD_FAB2_LIB.BASEBOARD_FAB2(SCH_1):GND
  BE63  GND            VSS<112>  @BASEBOARD_FAB2_LIB.BASEBOARD_FAB2(SCH_1):GND
  BE66  GND            VSS<111>  @BASEBOARD_FAB2_LIB.BASEBOARD_FAB2(SCH_1):GND
  BF13  GND            VSS<110>  @BASEBOARD_FAB2_LIB.BASEBOARD_FAB2(SCH_1):GND
  BF17  GND            VSS<109>  @BASEBOARD_FAB2_LIB.BASEBOARD_FAB2(SCH_1):GND
  BF54  GND            VSS<108>  @BASEBOARD_FAB2_LIB.BASEBOARD_FAB2(SCH_1):GND
  BG44  GND            VSS<107>  @BASEBOARD_FAB2_LIB.BASEBOARD_FAB2(SCH_1):GND
  BF20  GND            VSS<106>  @BASEBOARD_FAB2_LIB.BASEBOARD_FAB2(SCH_1):GND
  BF24  GND            VSS<105>  @BASEBOARD_FAB2_LIB.BASEBOARD_FAB2(SCH_1):GND
  BF27  GND            VSS<104>  @BASEBOARD_FAB2_LIB.BASEBOARD_FAB2(SCH_1):GND
  BF38  GND            VSS<103>  @BASEBOARD_FAB2_LIB.BASEBOARD_FAB2(SCH_1):GND
  BF42  GND            VSS<102>  @BASEBOARD_FAB2_LIB.BASEBOARD_FAB2(SCH_1):GND
  BF5  GND            VSS<101>  @BASEBOARD_FAB2_LIB.BASEBOARD_FAB2(SCH_1):GND
  BF50  GND            VSS<100>  @BASEBOARD_FAB2_LIB.BASEBOARD_FAB2(SCH_1):GND
  BF58  GND            VSS<99>  @BASEBOARD_FAB2_LIB.BASEBOARD_FAB2(SCH_1):GND
  BF61  GND            VSS<98>  @BASEBOARD_FAB2_LIB.BASEBOARD_FAB2(SCH_1):GND
  BF65  GND            VSS<97>  @BASEBOARD_FAB2_LIB.BASEBOARD_FAB2(SCH_1):GND
  BF68  GND            VSS<96>  @BASEBOARD_FAB2_LIB.BASEBOARD_FAB2(SCH_1):GND
  BF9  GND            VSS<95>  @BASEBOARD_FAB2_LIB.BASEBOARD_FAB2(SCH_1):GND
  BG33  GND            VSS<94>  @BASEBOARD_FAB2_LIB.BASEBOARD_FAB2(SCH_1):GND
  BG48  GND            VSS<93>  @BASEBOARD_FAB2_LIB.BASEBOARD_FAB2(SCH_1):GND
  BG59  GND            VSS<92>  @BASEBOARD_FAB2_LIB.BASEBOARD_FAB2(SCH_1):GND
  BG63  GND            VSS<91>  @BASEBOARD_FAB2_LIB.BASEBOARD_FAB2(SCH_1):GND
  BH27  GND            VSS<90>  @BASEBOARD_FAB2_LIB.BASEBOARD_FAB2(SCH_1):GND
  BH38  GND            VSS<89>  @BASEBOARD_FAB2_LIB.BASEBOARD_FAB2(SCH_1):GND
  BH42  GND            VSS<88>  @BASEBOARD_FAB2_LIB.BASEBOARD_FAB2(SCH_1):GND
  BH46  GND            VSS<87>  @BASEBOARD_FAB2_LIB.BASEBOARD_FAB2(SCH_1):GND
  BH54  GND            VSS<86>  @BASEBOARD_FAB2_LIB.BASEBOARD_FAB2(SCH_1):GND
  BJ1  GND            VSS<85>  @BASEBOARD_FAB2_LIB.BASEBOARD_FAB2(SCH_1):GND
  BJ11  GND            VSS<84>  @BASEBOARD_FAB2_LIB.BASEBOARD_FAB2(SCH_1):GND
  BJ5  GND            VSS<83>  @BASEBOARD_FAB2_LIB.BASEBOARD_FAB2(SCH_1):GND
  BJ7  GND            VSS<82>  @BASEBOARD_FAB2_LIB.BASEBOARD_FAB2(SCH_1):GND
  BJ15  GND            VSS<81>  @BASEBOARD_FAB2_LIB.BASEBOARD_FAB2(SCH_1):GND
  BJ18  GND            VSS<80>  @BASEBOARD_FAB2_LIB.BASEBOARD_FAB2(SCH_1):GND
  BJ26  GND            VSS<79>  @BASEBOARD_FAB2_LIB.BASEBOARD_FAB2(SCH_1):GND
  BJ3  GND            VSS<78>  @BASEBOARD_FAB2_LIB.BASEBOARD_FAB2(SCH_1):GND
  BJ33  GND            VSS<77>  @BASEBOARD_FAB2_LIB.BASEBOARD_FAB2(SCH_1):GND
  BJ52  GND            VSS<76>  @BASEBOARD_FAB2_LIB.BASEBOARD_FAB2(SCH_1):GND
  BJ68  GND            VSS<75>  @BASEBOARD_FAB2_LIB.BASEBOARD_FAB2(SCH_1):GND

LBG_CORE_QAT_EXT_D  I17  U7C1   [LBG_CORE_QAT_EXT_D_BGA1-IC,H91A]
  N35  GND            VSS<354>  @BASEBOARD_FAB2_LIB.BASEBOARD_FAB2(SCH_1):GND
  N38  GND            VSS<353>  @BASEBOARD_FAB2_LIB.BASEBOARD_FAB2(SCH_1):GND
  N46  GND            VSS<352>  @BASEBOARD_FAB2_LIB.BASEBOARD_FAB2(SCH_1):GND
   N5  GND            VSS<351>  @BASEBOARD_FAB2_LIB.BASEBOARD_FAB2(SCH_1):GND
  R38  GND            VSS<350>  @BASEBOARD_FAB2_LIB.BASEBOARD_FAB2(SCH_1):GND
  N68  GND            VSS<349>  @BASEBOARD_FAB2_LIB.BASEBOARD_FAB2(SCH_1):GND
   N9  GND            VSS<348>  @BASEBOARD_FAB2_LIB.BASEBOARD_FAB2(SCH_1):GND
  AE43  GND            VSS<347>  @BASEBOARD_FAB2_LIB.BASEBOARD_FAB2(SCH_1):GND
  P63  GND            VSS<346>  @BASEBOARD_FAB2_LIB.BASEBOARD_FAB2(SCH_1):GND
  R27  GND            VSS<345>  @BASEBOARD_FAB2_LIB.BASEBOARD_FAB2(SCH_1):GND
  U42  GND            VSS<344>  @BASEBOARD_FAB2_LIB.BASEBOARD_FAB2(SCH_1):GND
   R5  GND            VSS<343>  @BASEBOARD_FAB2_LIB.BASEBOARD_FAB2(SCH_1):GND
  R50  GND            VSS<342>  @BASEBOARD_FAB2_LIB.BASEBOARD_FAB2(SCH_1):GND
  R54  GND            VSS<341>  @BASEBOARD_FAB2_LIB.BASEBOARD_FAB2(SCH_1):GND
  T56  GND            VSS<340>  @BASEBOARD_FAB2_LIB.BASEBOARD_FAB2(SCH_1):GND
  R58  GND            VSS<339>  @BASEBOARD_FAB2_LIB.BASEBOARD_FAB2(SCH_1):GND
  R68  GND            VSS<338>  @BASEBOARD_FAB2_LIB.BASEBOARD_FAB2(SCH_1):GND
  T11  GND            VSS<337>  @BASEBOARD_FAB2_LIB.BASEBOARD_FAB2(SCH_1):GND
  T15  GND            VSS<336>  @BASEBOARD_FAB2_LIB.BASEBOARD_FAB2(SCH_1):GND
  T18  GND            VSS<335>  @BASEBOARD_FAB2_LIB.BASEBOARD_FAB2(SCH_1):GND
  T22  GND            VSS<334>  @BASEBOARD_FAB2_LIB.BASEBOARD_FAB2(SCH_1):GND
  T26  GND            VSS<333>  @BASEBOARD_FAB2_LIB.BASEBOARD_FAB2(SCH_1):GND
  T29  GND            VSS<332>  @BASEBOARD_FAB2_LIB.BASEBOARD_FAB2(SCH_1):GND
  T33  GND            VSS<331>  @BASEBOARD_FAB2_LIB.BASEBOARD_FAB2(SCH_1):GND
  T37  GND            VSS<330>  @BASEBOARD_FAB2_LIB.BASEBOARD_FAB2(SCH_1):GND
  T40  GND            VSS<329>  @BASEBOARD_FAB2_LIB.BASEBOARD_FAB2(SCH_1):GND
  AJ45  GND            VSS<328>  @BASEBOARD_FAB2_LIB.BASEBOARD_FAB2(SCH_1):GND
  T48  GND            VSS<327>  @BASEBOARD_FAB2_LIB.BASEBOARD_FAB2(SCH_1):GND
  T52  GND            VSS<326>  @BASEBOARD_FAB2_LIB.BASEBOARD_FAB2(SCH_1):GND
  T66  GND            VSS<325>  @BASEBOARD_FAB2_LIB.BASEBOARD_FAB2(SCH_1):GND
   T7  GND            VSS<324>  @BASEBOARD_FAB2_LIB.BASEBOARD_FAB2(SCH_1):GND
  AF50  GND            VSS<323>  @BASEBOARD_FAB2_LIB.BASEBOARD_FAB2(SCH_1):GND
  AG46  GND            VSS<322>  @BASEBOARD_FAB2_LIB.BASEBOARD_FAB2(SCH_1):GND
  U58  GND            VSS<321>  @BASEBOARD_FAB2_LIB.BASEBOARD_FAB2(SCH_1):GND
  V26  GND            VSS<320>  @BASEBOARD_FAB2_LIB.BASEBOARD_FAB2(SCH_1):GND
  V48  GND            VSS<319>  @BASEBOARD_FAB2_LIB.BASEBOARD_FAB2(SCH_1):GND
   V5  GND            VSS<318>  @BASEBOARD_FAB2_LIB.BASEBOARD_FAB2(SCH_1):GND
  V52  GND            VSS<317>  @BASEBOARD_FAB2_LIB.BASEBOARD_FAB2(SCH_1):GND
  W58  GND            VSS<316>  @BASEBOARD_FAB2_LIB.BASEBOARD_FAB2(SCH_1):GND
  V66  GND            VSS<315>  @BASEBOARD_FAB2_LIB.BASEBOARD_FAB2(SCH_1):GND
  V68  GND            VSS<314>  @BASEBOARD_FAB2_LIB.BASEBOARD_FAB2(SCH_1):GND
  W13  GND            VSS<313>  @BASEBOARD_FAB2_LIB.BASEBOARD_FAB2(SCH_1):GND
  W17  GND            VSS<312>  @BASEBOARD_FAB2_LIB.BASEBOARD_FAB2(SCH_1):GND
  W20  GND            VSS<311>  @BASEBOARD_FAB2_LIB.BASEBOARD_FAB2(SCH_1):GND
  W24  GND            VSS<310>  @BASEBOARD_FAB2_LIB.BASEBOARD_FAB2(SCH_1):GND
  AA50  GND            VSS<309>  @BASEBOARD_FAB2_LIB.BASEBOARD_FAB2(SCH_1):GND
  Y43  GND            VSS<308>  @BASEBOARD_FAB2_LIB.BASEBOARD_FAB2(SCH_1):GND
  W61  GND            VSS<307>  @BASEBOARD_FAB2_LIB.BASEBOARD_FAB2(SCH_1):GND
   W9  GND            VSS<306>  @BASEBOARD_FAB2_LIB.BASEBOARD_FAB2(SCH_1):GND
  Y22  GND            VSS<305>  @BASEBOARD_FAB2_LIB.BASEBOARD_FAB2(SCH_1):GND
  Y27  GND            VSS<304>  @BASEBOARD_FAB2_LIB.BASEBOARD_FAB2(SCH_1):GND
  Y48  GND            VSS<303>  @BASEBOARD_FAB2_LIB.BASEBOARD_FAB2(SCH_1):GND
   Y5  GND            VSS<302>  @BASEBOARD_FAB2_LIB.BASEBOARD_FAB2(SCH_1):GND
  Y52  GND            VSS<301>  @BASEBOARD_FAB2_LIB.BASEBOARD_FAB2(SCH_1):GND
  Y59  GND            VSS<300>  @BASEBOARD_FAB2_LIB.BASEBOARD_FAB2(SCH_1):GND
  Y63  GND            VSS<299>  @BASEBOARD_FAB2_LIB.BASEBOARD_FAB2(SCH_1):GND
  Y68  GND            VSS<298>  @BASEBOARD_FAB2_LIB.BASEBOARD_FAB2(SCH_1):GND
  AA26  GND            VSS<297>  @BASEBOARD_FAB2_LIB.BASEBOARD_FAB2(SCH_1):GND
  AA27  GND            VSS<296>  @BASEBOARD_FAB2_LIB.BASEBOARD_FAB2(SCH_1):GND
  AA43  GND            VSS<295>  @BASEBOARD_FAB2_LIB.BASEBOARD_FAB2(SCH_1):GND
  AA48  GND            VSS<294>  @BASEBOARD_FAB2_LIB.BASEBOARD_FAB2(SCH_1):GND
  AB5  GND            VSS<293>  @BASEBOARD_FAB2_LIB.BASEBOARD_FAB2(SCH_1):GND
  AB68  GND            VSS<292>  @BASEBOARD_FAB2_LIB.BASEBOARD_FAB2(SCH_1):GND
  AB70  GND            VSS<291>  @BASEBOARD_FAB2_LIB.BASEBOARD_FAB2(SCH_1):GND
  AB72  GND            VSS<290>  @BASEBOARD_FAB2_LIB.BASEBOARD_FAB2(SCH_1):GND
  AC11  GND            VSS<289>  @BASEBOARD_FAB2_LIB.BASEBOARD_FAB2(SCH_1):GND
  AC15  GND            VSS<288>  @BASEBOARD_FAB2_LIB.BASEBOARD_FAB2(SCH_1):GND
  AC18  GND            VSS<287>  @BASEBOARD_FAB2_LIB.BASEBOARD_FAB2(SCH_1):GND
  AC22  GND            VSS<286>  @BASEBOARD_FAB2_LIB.BASEBOARD_FAB2(SCH_1):GND
  AC45  GND            VSS<285>  @BASEBOARD_FAB2_LIB.BASEBOARD_FAB2(SCH_1):GND
  AD58  GND            VSS<284>  @BASEBOARD_FAB2_LIB.BASEBOARD_FAB2(SCH_1):GND
  AC27  GND            VSS<283>  @BASEBOARD_FAB2_LIB.BASEBOARD_FAB2(SCH_1):GND
  AC43  GND            VSS<282>  @BASEBOARD_FAB2_LIB.BASEBOARD_FAB2(SCH_1):GND
  AC46  GND            VSS<281>  @BASEBOARD_FAB2_LIB.BASEBOARD_FAB2(SCH_1):GND
  AC48  GND            VSS<280>  @BASEBOARD_FAB2_LIB.BASEBOARD_FAB2(SCH_1):GND
  AC52  GND            VSS<279>  @BASEBOARD_FAB2_LIB.BASEBOARD_FAB2(SCH_1):GND
  AC59  GND            VSS<278>  @BASEBOARD_FAB2_LIB.BASEBOARD_FAB2(SCH_1):GND
  AC63  GND            VSS<277>  @BASEBOARD_FAB2_LIB.BASEBOARD_FAB2(SCH_1):GND
  AC66  GND            VSS<276>  @BASEBOARD_FAB2_LIB.BASEBOARD_FAB2(SCH_1):GND
  AC7  GND            VSS<275>  @BASEBOARD_FAB2_LIB.BASEBOARD_FAB2(SCH_1):GND
  AD5  GND            VSS<274>  @BASEBOARD_FAB2_LIB.BASEBOARD_FAB2(SCH_1):GND
  AD65  GND            VSS<273>  @BASEBOARD_FAB2_LIB.BASEBOARD_FAB2(SCH_1):GND
  AD68  GND            VSS<272>  @BASEBOARD_FAB2_LIB.BASEBOARD_FAB2(SCH_1):GND
  AE29  GND            VSS<271>  @BASEBOARD_FAB2_LIB.BASEBOARD_FAB2(SCH_1):GND
  J18  GND            VSS<270>  @BASEBOARD_FAB2_LIB.BASEBOARD_FAB2(SCH_1):GND
  AE48  GND            VSS<269>  @BASEBOARD_FAB2_LIB.BASEBOARD_FAB2(SCH_1):GND
  AE52  GND            VSS<268>  @BASEBOARD_FAB2_LIB.BASEBOARD_FAB2(SCH_1):GND
  AE56  GND            VSS<267>  @BASEBOARD_FAB2_LIB.BASEBOARD_FAB2(SCH_1):GND
  AE59  GND            VSS<266>  @BASEBOARD_FAB2_LIB.BASEBOARD_FAB2(SCH_1):GND
  AE63  GND            VSS<265>  @BASEBOARD_FAB2_LIB.BASEBOARD_FAB2(SCH_1):GND
  AE66  GND            VSS<264>  @BASEBOARD_FAB2_LIB.BASEBOARD_FAB2(SCH_1):GND
  AF1  GND            VSS<263>  @BASEBOARD_FAB2_LIB.BASEBOARD_FAB2(SCH_1):GND
  AF13  GND            VSS<262>  @BASEBOARD_FAB2_LIB.BASEBOARD_FAB2(SCH_1):GND
  AF5  GND            VSS<261>  @BASEBOARD_FAB2_LIB.BASEBOARD_FAB2(SCH_1):GND
  AF9  GND            VSS<260>  @BASEBOARD_FAB2_LIB.BASEBOARD_FAB2(SCH_1):GND
  AF17  GND            VSS<259>  @BASEBOARD_FAB2_LIB.BASEBOARD_FAB2(SCH_1):GND
  AF24  GND            VSS<258>  @BASEBOARD_FAB2_LIB.BASEBOARD_FAB2(SCH_1):GND
  AF3  GND            VSS<257>  @BASEBOARD_FAB2_LIB.BASEBOARD_FAB2(SCH_1):GND
  AF68  GND            VSS<256>  @BASEBOARD_FAB2_LIB.BASEBOARD_FAB2(SCH_1):GND
  AG26  GND            VSS<255>  @BASEBOARD_FAB2_LIB.BASEBOARD_FAB2(SCH_1):GND
  AG30  GND            VSS<254>  @BASEBOARD_FAB2_LIB.BASEBOARD_FAB2(SCH_1):GND
  AG41  GND            VSS<253>  @BASEBOARD_FAB2_LIB.BASEBOARD_FAB2(SCH_1):GND
  AG43  GND            VSS<252>  @BASEBOARD_FAB2_LIB.BASEBOARD_FAB2(SCH_1):GND
  AG52  GND            VSS<251>  @BASEBOARD_FAB2_LIB.BASEBOARD_FAB2(SCH_1):GND
  AG56  GND            VSS<250>  @BASEBOARD_FAB2_LIB.BASEBOARD_FAB2(SCH_1):GND
  AG59  GND            VSS<249>  @BASEBOARD_FAB2_LIB.BASEBOARD_FAB2(SCH_1):GND
  AG66  GND            VSS<248>  @BASEBOARD_FAB2_LIB.BASEBOARD_FAB2(SCH_1):GND
  AH20  GND            VSS<247>  @BASEBOARD_FAB2_LIB.BASEBOARD_FAB2(SCH_1):GND
  AJ11  GND            VSS<246>  @BASEBOARD_FAB2_LIB.BASEBOARD_FAB2(SCH_1):GND
  AJ32  GND            VSS<245>  @BASEBOARD_FAB2_LIB.BASEBOARD_FAB2(SCH_1):GND
  AJ56  GND            VSS<244>  @BASEBOARD_FAB2_LIB.BASEBOARD_FAB2(SCH_1):GND
  AK30  GND            VSS<243>  @BASEBOARD_FAB2_LIB.BASEBOARD_FAB2(SCH_1):GND
  AJ15  GND            VSS<242>  @BASEBOARD_FAB2_LIB.BASEBOARD_FAB2(SCH_1):GND
  AJ18  GND            VSS<241>  @BASEBOARD_FAB2_LIB.BASEBOARD_FAB2(SCH_1):GND
  AJ22  GND            VSS<240>  @BASEBOARD_FAB2_LIB.BASEBOARD_FAB2(SCH_1):GND
  AJ26  GND            VSS<239>  @BASEBOARD_FAB2_LIB.BASEBOARD_FAB2(SCH_1):GND
  AJ30  GND            VSS<238>  @BASEBOARD_FAB2_LIB.BASEBOARD_FAB2(SCH_1):GND
  AJ34  GND            VSS<237>  @BASEBOARD_FAB2_LIB.BASEBOARD_FAB2(SCH_1):GND
  AJ36  GND            VSS<236>  @BASEBOARD_FAB2_LIB.BASEBOARD_FAB2(SCH_1):GND
  AJ37  GND            VSS<235>  @BASEBOARD_FAB2_LIB.BASEBOARD_FAB2(SCH_1):GND
  AJ39  GND            VSS<234>  @BASEBOARD_FAB2_LIB.BASEBOARD_FAB2(SCH_1):GND
  AJ41  GND            VSS<233>  @BASEBOARD_FAB2_LIB.BASEBOARD_FAB2(SCH_1):GND
  AJ5  GND            VSS<232>  @BASEBOARD_FAB2_LIB.BASEBOARD_FAB2(SCH_1):GND
  AJ52  GND            VSS<231>  @BASEBOARD_FAB2_LIB.BASEBOARD_FAB2(SCH_1):GND
  AJ59  GND            VSS<230>  @BASEBOARD_FAB2_LIB.BASEBOARD_FAB2(SCH_1):GND
  AJ66  GND            VSS<229>  @BASEBOARD_FAB2_LIB.BASEBOARD_FAB2(SCH_1):GND
  AJ68  GND            VSS<228>  @BASEBOARD_FAB2_LIB.BASEBOARD_FAB2(SCH_1):GND
  AJ7  GND            VSS<227>  @BASEBOARD_FAB2_LIB.BASEBOARD_FAB2(SCH_1):GND
  AK26  GND            VSS<226>  @BASEBOARD_FAB2_LIB.BASEBOARD_FAB2(SCH_1):GND
  AK41  GND            VSS<225>  @BASEBOARD_FAB2_LIB.BASEBOARD_FAB2(SCH_1):GND
  AK46  GND            VSS<224>  @BASEBOARD_FAB2_LIB.BASEBOARD_FAB2(SCH_1):GND
  AK48  GND            VSS<223>  @BASEBOARD_FAB2_LIB.BASEBOARD_FAB2(SCH_1):GND
  AK58  GND            VSS<222>  @BASEBOARD_FAB2_LIB.BASEBOARD_FAB2(SCH_1):GND
  AK61  GND            VSS<221>  @BASEBOARD_FAB2_LIB.BASEBOARD_FAB2(SCH_1):GND
  AK69  GND            VSS<220>  @BASEBOARD_FAB2_LIB.BASEBOARD_FAB2(SCH_1):GND
  AK71  GND            VSS<219>  @BASEBOARD_FAB2_LIB.BASEBOARD_FAB2(SCH_1):GND
  AL22  GND            VSS<218>  @BASEBOARD_FAB2_LIB.BASEBOARD_FAB2(SCH_1):GND
  AL5  GND            VSS<217>  @BASEBOARD_FAB2_LIB.BASEBOARD_FAB2(SCH_1):GND
  AL52  GND            VSS<216>  @BASEBOARD_FAB2_LIB.BASEBOARD_FAB2(SCH_1):GND
  AL59  GND            VSS<215>  @BASEBOARD_FAB2_LIB.BASEBOARD_FAB2(SCH_1):GND

LBG_CORE_QAT_EXT_D  I13  U7C1   [LBG_CORE_QAT_EXT_D_BGA1-IC,H91A]
  BP69  GND            VSS<494>  @BASEBOARD_FAB2_LIB.BASEBOARD_FAB2(SCH_1):GND
  BT69  GND            VSS<493>  @BASEBOARD_FAB2_LIB.BASEBOARD_FAB2(SCH_1):GND
  BU70  GND            VSS<492>  @BASEBOARD_FAB2_LIB.BASEBOARD_FAB2(SCH_1):GND
  BR70  GND            VSS<491>  @BASEBOARD_FAB2_LIB.BASEBOARD_FAB2(SCH_1):GND
  F70  GND            VSS<490>  @BASEBOARD_FAB2_LIB.BASEBOARD_FAB2(SCH_1):GND
  E70  GND            VSS<489>  @BASEBOARD_FAB2_LIB.BASEBOARD_FAB2(SCH_1):GND
  BU3  GND            VSS<488>  @BASEBOARD_FAB2_LIB.BASEBOARD_FAB2(SCH_1):GND
  BR3  GND            VSS<487>  @BASEBOARD_FAB2_LIB.BASEBOARD_FAB2(SCH_1):GND
   F3  GND            VSS<486>  @BASEBOARD_FAB2_LIB.BASEBOARD_FAB2(SCH_1):GND
   E3  GND            VSS<485>  @BASEBOARD_FAB2_LIB.BASEBOARD_FAB2(SCH_1):GND
   A5  GND            VSS<484>  @BASEBOARD_FAB2_LIB.BASEBOARD_FAB2(SCH_1):GND
   A7  GND            VSS<483>  @BASEBOARD_FAB2_LIB.BASEBOARD_FAB2(SCH_1):GND
   A9  GND            VSS<482>  @BASEBOARD_FAB2_LIB.BASEBOARD_FAB2(SCH_1):GND
  A65  GND            VSS<481>  @BASEBOARD_FAB2_LIB.BASEBOARD_FAB2(SCH_1):GND
  A66  GND            VSS<480>  @BASEBOARD_FAB2_LIB.BASEBOARD_FAB2(SCH_1):GND
  A68  GND            VSS<479>  @BASEBOARD_FAB2_LIB.BASEBOARD_FAB2(SCH_1):GND
   J1  GND            VSS<478>  @BASEBOARD_FAB2_LIB.BASEBOARD_FAB2(SCH_1):GND
  J72  GND            VSS<477>  @BASEBOARD_FAB2_LIB.BASEBOARD_FAB2(SCH_1):GND
  BN1  GND            VSS<476>  @BASEBOARD_FAB2_LIB.BASEBOARD_FAB2(SCH_1):GND
  BN72  GND            VSS<475>  @BASEBOARD_FAB2_LIB.BASEBOARD_FAB2(SCH_1):GND
  CA68  GND            VSS<474>  @BASEBOARD_FAB2_LIB.BASEBOARD_FAB2(SCH_1):GND
  CA66  GND            VSS<473>  @BASEBOARD_FAB2_LIB.BASEBOARD_FAB2(SCH_1):GND
  CA65  GND            VSS<472>  @BASEBOARD_FAB2_LIB.BASEBOARD_FAB2(SCH_1):GND
  CA9  GND            VSS<471>  @BASEBOARD_FAB2_LIB.BASEBOARD_FAB2(SCH_1):GND
  CA7  GND            VSS<470>  @BASEBOARD_FAB2_LIB.BASEBOARD_FAB2(SCH_1):GND
  CA5  GND            VSS<469>  @BASEBOARD_FAB2_LIB.BASEBOARD_FAB2(SCH_1):GND
  A70  GND            VSS<468>  @BASEBOARD_FAB2_LIB.BASEBOARD_FAB2(SCH_1):GND
  CA3  GND            VSS<467>  @BASEBOARD_FAB2_LIB.BASEBOARD_FAB2(SCH_1):GND
  BW1  GND            VSS<466>  @BASEBOARD_FAB2_LIB.BASEBOARD_FAB2(SCH_1):GND
  BU1  GND            VSS<465>  @BASEBOARD_FAB2_LIB.BASEBOARD_FAB2(SCH_1):GND
  BR1  GND            VSS<464>  @BASEBOARD_FAB2_LIB.BASEBOARD_FAB2(SCH_1):GND
   C3  GND            VSS<463>  @BASEBOARD_FAB2_LIB.BASEBOARD_FAB2(SCH_1):GND
  C72  GND            VSS<462>  @BASEBOARD_FAB2_LIB.BASEBOARD_FAB2(SCH_1):GND
   E1  GND            VSS<461>  @BASEBOARD_FAB2_LIB.BASEBOARD_FAB2(SCH_1):GND
  E72  GND            VSS<460>  @BASEBOARD_FAB2_LIB.BASEBOARD_FAB2(SCH_1):GND
   G1  GND            VSS<459>  @BASEBOARD_FAB2_LIB.BASEBOARD_FAB2(SCH_1):GND
  G72  GND            VSS<458>  @BASEBOARD_FAB2_LIB.BASEBOARD_FAB2(SCH_1):GND
  BR72  GND            VSS<457>  @BASEBOARD_FAB2_LIB.BASEBOARD_FAB2(SCH_1):GND
  BU72  GND            VSS<456>  @BASEBOARD_FAB2_LIB.BASEBOARD_FAB2(SCH_1):GND
  BW70  GND            VSS<455>  @BASEBOARD_FAB2_LIB.BASEBOARD_FAB2(SCH_1):GND
  BW72  GND            VSS<454>  @BASEBOARD_FAB2_LIB.BASEBOARD_FAB2(SCH_1):GND
  CA70  GND            VSS<453>  @BASEBOARD_FAB2_LIB.BASEBOARD_FAB2(SCH_1):GND
  BB48  GND            VSS<452>  @BASEBOARD_FAB2_LIB.BASEBOARD_FAB2(SCH_1):GND
  AT37  GND            VSS<451>  @BASEBOARD_FAB2_LIB.BASEBOARD_FAB2(SCH_1):GND
  Y72  GND            VSS<450>  @BASEBOARD_FAB2_LIB.BASEBOARD_FAB2(SCH_1):GND
  Y70  GND            VSS<449>  @BASEBOARD_FAB2_LIB.BASEBOARD_FAB2(SCH_1):GND
  A18  GND            VSS<448>  @BASEBOARD_FAB2_LIB.BASEBOARD_FAB2(SCH_1):GND
  A22  GND            VSS<447>  @BASEBOARD_FAB2_LIB.BASEBOARD_FAB2(SCH_1):GND
  A30  GND            VSS<446>  @BASEBOARD_FAB2_LIB.BASEBOARD_FAB2(SCH_1):GND
  A34  GND            VSS<445>  @BASEBOARD_FAB2_LIB.BASEBOARD_FAB2(SCH_1):GND
  A37  GND            VSS<444>  @BASEBOARD_FAB2_LIB.BASEBOARD_FAB2(SCH_1):GND
  A41  GND            VSS<443>  @BASEBOARD_FAB2_LIB.BASEBOARD_FAB2(SCH_1):GND
  B12  GND            VSS<442>  @BASEBOARD_FAB2_LIB.BASEBOARD_FAB2(SCH_1):GND
  B19  GND            VSS<441>  @BASEBOARD_FAB2_LIB.BASEBOARD_FAB2(SCH_1):GND
  B25  GND            VSS<440>  @BASEBOARD_FAB2_LIB.BASEBOARD_FAB2(SCH_1):GND
  B27  GND            VSS<439>  @BASEBOARD_FAB2_LIB.BASEBOARD_FAB2(SCH_1):GND
  B47  GND            VSS<438>  @BASEBOARD_FAB2_LIB.BASEBOARD_FAB2(SCH_1):GND
  C22  GND            VSS<437>  @BASEBOARD_FAB2_LIB.BASEBOARD_FAB2(SCH_1):GND
  C30  GND            VSS<436>  @BASEBOARD_FAB2_LIB.BASEBOARD_FAB2(SCH_1):GND
  C34  GND            VSS<435>  @BASEBOARD_FAB2_LIB.BASEBOARD_FAB2(SCH_1):GND
  C37  GND            VSS<434>  @BASEBOARD_FAB2_LIB.BASEBOARD_FAB2(SCH_1):GND
  C41  GND            VSS<433>  @BASEBOARD_FAB2_LIB.BASEBOARD_FAB2(SCH_1):GND
  C65  GND            VSS<432>  @BASEBOARD_FAB2_LIB.BASEBOARD_FAB2(SCH_1):GND
  D12  GND            VSS<431>  @BASEBOARD_FAB2_LIB.BASEBOARD_FAB2(SCH_1):GND
  D16  GND            VSS<430>  @BASEBOARD_FAB2_LIB.BASEBOARD_FAB2(SCH_1):GND
  D19  GND            VSS<429>  @BASEBOARD_FAB2_LIB.BASEBOARD_FAB2(SCH_1):GND
  D25  GND            VSS<428>  @BASEBOARD_FAB2_LIB.BASEBOARD_FAB2(SCH_1):GND
  D27  GND            VSS<427>  @BASEBOARD_FAB2_LIB.BASEBOARD_FAB2(SCH_1):GND
  E59  GND            VSS<426>  @BASEBOARD_FAB2_LIB.BASEBOARD_FAB2(SCH_1):GND
  E65  GND            VSS<425>  @BASEBOARD_FAB2_LIB.BASEBOARD_FAB2(SCH_1):GND
  D47  GND            VSS<424>  @BASEBOARD_FAB2_LIB.BASEBOARD_FAB2(SCH_1):GND
  E11  GND            VSS<423>  @BASEBOARD_FAB2_LIB.BASEBOARD_FAB2(SCH_1):GND
  E13  GND            VSS<422>  @BASEBOARD_FAB2_LIB.BASEBOARD_FAB2(SCH_1):GND
  E15  GND            VSS<421>  @BASEBOARD_FAB2_LIB.BASEBOARD_FAB2(SCH_1):GND
  E20  GND            VSS<420>  @BASEBOARD_FAB2_LIB.BASEBOARD_FAB2(SCH_1):GND
  E22  GND            VSS<419>  @BASEBOARD_FAB2_LIB.BASEBOARD_FAB2(SCH_1):GND
  E24  GND            VSS<418>  @BASEBOARD_FAB2_LIB.BASEBOARD_FAB2(SCH_1):GND
  E26  GND            VSS<417>  @BASEBOARD_FAB2_LIB.BASEBOARD_FAB2(SCH_1):GND
  E28  GND            VSS<416>  @BASEBOARD_FAB2_LIB.BASEBOARD_FAB2(SCH_1):GND
  E30  GND            VSS<415>  @BASEBOARD_FAB2_LIB.BASEBOARD_FAB2(SCH_1):GND
  E32  GND            VSS<414>  @BASEBOARD_FAB2_LIB.BASEBOARD_FAB2(SCH_1):GND
  E34  GND            VSS<413>  @BASEBOARD_FAB2_LIB.BASEBOARD_FAB2(SCH_1):GND
  E37  GND            VSS<412>  @BASEBOARD_FAB2_LIB.BASEBOARD_FAB2(SCH_1):GND
  E39  GND            VSS<411>  @BASEBOARD_FAB2_LIB.BASEBOARD_FAB2(SCH_1):GND
  E41  GND            VSS<410>  @BASEBOARD_FAB2_LIB.BASEBOARD_FAB2(SCH_1):GND
  E43  GND            VSS<409>  @BASEBOARD_FAB2_LIB.BASEBOARD_FAB2(SCH_1):GND
  E45  GND            VSS<408>  @BASEBOARD_FAB2_LIB.BASEBOARD_FAB2(SCH_1):GND
  E48  GND            VSS<407>  @BASEBOARD_FAB2_LIB.BASEBOARD_FAB2(SCH_1):GND
  E50  GND            VSS<406>  @BASEBOARD_FAB2_LIB.BASEBOARD_FAB2(SCH_1):GND
  E52  GND            VSS<405>  @BASEBOARD_FAB2_LIB.BASEBOARD_FAB2(SCH_1):GND
  E54  GND            VSS<404>  @BASEBOARD_FAB2_LIB.BASEBOARD_FAB2(SCH_1):GND
  E57  GND            VSS<403>  @BASEBOARD_FAB2_LIB.BASEBOARD_FAB2(SCH_1):GND
   E6  GND            VSS<402>  @BASEBOARD_FAB2_LIB.BASEBOARD_FAB2(SCH_1):GND
  E61  GND            VSS<401>  @BASEBOARD_FAB2_LIB.BASEBOARD_FAB2(SCH_1):GND
  E63  GND            VSS<400>  @BASEBOARD_FAB2_LIB.BASEBOARD_FAB2(SCH_1):GND
  G59  GND            VSS<399>  @BASEBOARD_FAB2_LIB.BASEBOARD_FAB2(SCH_1):GND
   E9  GND            VSS<398>  @BASEBOARD_FAB2_LIB.BASEBOARD_FAB2(SCH_1):GND
  G22  GND            VSS<397>  @BASEBOARD_FAB2_LIB.BASEBOARD_FAB2(SCH_1):GND
  G29  GND            VSS<396>  @BASEBOARD_FAB2_LIB.BASEBOARD_FAB2(SCH_1):GND
  G37  GND            VSS<395>  @BASEBOARD_FAB2_LIB.BASEBOARD_FAB2(SCH_1):GND
  G48  GND            VSS<394>  @BASEBOARD_FAB2_LIB.BASEBOARD_FAB2(SCH_1):GND
   G6  GND            VSS<393>  @BASEBOARD_FAB2_LIB.BASEBOARD_FAB2(SCH_1):GND
  G63  GND            VSS<392>  @BASEBOARD_FAB2_LIB.BASEBOARD_FAB2(SCH_1):GND
  G66  GND            VSS<391>  @BASEBOARD_FAB2_LIB.BASEBOARD_FAB2(SCH_1):GND
  H58  GND            VSS<390>  @BASEBOARD_FAB2_LIB.BASEBOARD_FAB2(SCH_1):GND
  J29  GND            VSS<389>  @BASEBOARD_FAB2_LIB.BASEBOARD_FAB2(SCH_1):GND
   J5  GND            VSS<388>  @BASEBOARD_FAB2_LIB.BASEBOARD_FAB2(SCH_1):GND
   J7  GND            VSS<387>  @BASEBOARD_FAB2_LIB.BASEBOARD_FAB2(SCH_1):GND
  H65  GND            VSS<386>  @BASEBOARD_FAB2_LIB.BASEBOARD_FAB2(SCH_1):GND
  J11  GND            VSS<385>  @BASEBOARD_FAB2_LIB.BASEBOARD_FAB2(SCH_1):GND
  J15  GND            VSS<384>  @BASEBOARD_FAB2_LIB.BASEBOARD_FAB2(SCH_1):GND
  J22  GND            VSS<383>  @BASEBOARD_FAB2_LIB.BASEBOARD_FAB2(SCH_1):GND
  J37  GND            VSS<382>  @BASEBOARD_FAB2_LIB.BASEBOARD_FAB2(SCH_1):GND
  J44  GND            VSS<381>  @BASEBOARD_FAB2_LIB.BASEBOARD_FAB2(SCH_1):GND
  J59  GND            VSS<380>  @BASEBOARD_FAB2_LIB.BASEBOARD_FAB2(SCH_1):GND
  J68  GND            VSS<379>  @BASEBOARD_FAB2_LIB.BASEBOARD_FAB2(SCH_1):GND
  J70  GND            VSS<378>  @BASEBOARD_FAB2_LIB.BASEBOARD_FAB2(SCH_1):GND
  K54  GND            VSS<377>  @BASEBOARD_FAB2_LIB.BASEBOARD_FAB2(SCH_1):GND
  K69  GND            VSS<376>  @BASEBOARD_FAB2_LIB.BASEBOARD_FAB2(SCH_1):GND
  K71  GND            VSS<375>  @BASEBOARD_FAB2_LIB.BASEBOARD_FAB2(SCH_1):GND
   L5  GND            VSS<374>  @BASEBOARD_FAB2_LIB.BASEBOARD_FAB2(SCH_1):GND
  L68  GND            VSS<373>  @BASEBOARD_FAB2_LIB.BASEBOARD_FAB2(SCH_1):GND
   M2  GND            VSS<372>  @BASEBOARD_FAB2_LIB.BASEBOARD_FAB2(SCH_1):GND
  M22  GND            VSS<371>  @BASEBOARD_FAB2_LIB.BASEBOARD_FAB2(SCH_1):GND
  M26  GND            VSS<370>  @BASEBOARD_FAB2_LIB.BASEBOARD_FAB2(SCH_1):GND
  M29  GND            VSS<369>  @BASEBOARD_FAB2_LIB.BASEBOARD_FAB2(SCH_1):GND
  M33  GND            VSS<368>  @BASEBOARD_FAB2_LIB.BASEBOARD_FAB2(SCH_1):GND
  M37  GND            VSS<367>  @BASEBOARD_FAB2_LIB.BASEBOARD_FAB2(SCH_1):GND
   M4  GND            VSS<366>  @BASEBOARD_FAB2_LIB.BASEBOARD_FAB2(SCH_1):GND
  M40  GND            VSS<365>  @BASEBOARD_FAB2_LIB.BASEBOARD_FAB2(SCH_1):GND
  N42  GND            VSS<364>  @BASEBOARD_FAB2_LIB.BASEBOARD_FAB2(SCH_1):GND
  N50  GND            VSS<363>  @BASEBOARD_FAB2_LIB.BASEBOARD_FAB2(SCH_1):GND
  M44  GND            VSS<362>  @BASEBOARD_FAB2_LIB.BASEBOARD_FAB2(SCH_1):GND
  M48  GND            VSS<361>  @BASEBOARD_FAB2_LIB.BASEBOARD_FAB2(SCH_1):GND
  N13  GND            VSS<360>  @BASEBOARD_FAB2_LIB.BASEBOARD_FAB2(SCH_1):GND
  N17  GND            VSS<359>  @BASEBOARD_FAB2_LIB.BASEBOARD_FAB2(SCH_1):GND
  N20  GND            VSS<358>  @BASEBOARD_FAB2_LIB.BASEBOARD_FAB2(SCH_1):GND
  N24  GND            VSS<357>  @BASEBOARD_FAB2_LIB.BASEBOARD_FAB2(SCH_1):GND
  N27  GND            VSS<356>  @BASEBOARD_FAB2_LIB.BASEBOARD_FAB2(SCH_1):GND
  N31  GND            VSS<355>  @BASEBOARD_FAB2_LIB.BASEBOARD_FAB2(SCH_1):GND

LBG_CORE_QAT_EXT_D  I21  U7C1   [LBG_CORE_QAT_EXT_D_BGA1-IC,H91A]
  V37  VSENSE_PVNN_PCH_STBY_QAT  VCCPRIM_AVID_QAT_SENSE  @BASEBOARD_FAB2_LIB.BASEBOARD_FAB2(SCH_1):VSENSE_PVNN_PCH_STBY_QAT
  AK36  VSENSE_PVNN_PCH_STBY_FPK  VCCPRIM_AVID_SENSE  @BASEBOARD_FAB2_LIB.BASEBOARD_FAB2(SCH_1):VSENSE_PVNN_PCH_STBY_FPK
  AK32  PVNN_PCH_STBY  VCCPRIM_AVID<62>  @BASEBOARD_FAB2_LIB.BASEBOARD_FAB2(SCH_1):PVNN_PCH_STBY
  U31  PVNN_PCH_STBY  VCCPRIM_AVID<61>  @BASEBOARD_FAB2_LIB.BASEBOARD_FAB2(SCH_1):PVNN_PCH_STBY
  U35  PVNN_PCH_STBY  VCCPRIM_AVID<60>  @BASEBOARD_FAB2_LIB.BASEBOARD_FAB2(SCH_1):PVNN_PCH_STBY
  U38  PVNN_PCH_STBY  VCCPRIM_AVID<59>  @BASEBOARD_FAB2_LIB.BASEBOARD_FAB2(SCH_1):PVNN_PCH_STBY
  V29  PVNN_PCH_STBY  VCCPRIM_AVID<58>  @BASEBOARD_FAB2_LIB.BASEBOARD_FAB2(SCH_1):PVNN_PCH_STBY
  V33  PVNN_PCH_STBY  VCCPRIM_AVID<57>  @BASEBOARD_FAB2_LIB.BASEBOARD_FAB2(SCH_1):PVNN_PCH_STBY
  V40  PVNN_PCH_STBY  VCCPRIM_AVID<56>  @BASEBOARD_FAB2_LIB.BASEBOARD_FAB2(SCH_1):PVNN_PCH_STBY
  Y29  PVNN_PCH_STBY  VCCPRIM_AVID<55>  @BASEBOARD_FAB2_LIB.BASEBOARD_FAB2(SCH_1):PVNN_PCH_STBY
  Y30  PVNN_PCH_STBY  VCCPRIM_AVID<54>  @BASEBOARD_FAB2_LIB.BASEBOARD_FAB2(SCH_1):PVNN_PCH_STBY
  Y32  PVNN_PCH_STBY  VCCPRIM_AVID<53>  @BASEBOARD_FAB2_LIB.BASEBOARD_FAB2(SCH_1):PVNN_PCH_STBY
  Y34  PVNN_PCH_STBY  VCCPRIM_AVID<52>  @BASEBOARD_FAB2_LIB.BASEBOARD_FAB2(SCH_1):PVNN_PCH_STBY
  Y36  PVNN_PCH_STBY  VCCPRIM_AVID<51>  @BASEBOARD_FAB2_LIB.BASEBOARD_FAB2(SCH_1):PVNN_PCH_STBY
  Y37  PVNN_PCH_STBY  VCCPRIM_AVID<50>  @BASEBOARD_FAB2_LIB.BASEBOARD_FAB2(SCH_1):PVNN_PCH_STBY
  Y39  PVNN_PCH_STBY  VCCPRIM_AVID<49>  @BASEBOARD_FAB2_LIB.BASEBOARD_FAB2(SCH_1):PVNN_PCH_STBY
  Y41  PVNN_PCH_STBY  VCCPRIM_AVID<48>  @BASEBOARD_FAB2_LIB.BASEBOARD_FAB2(SCH_1):PVNN_PCH_STBY
  AA29  PVNN_PCH_STBY  VCCPRIM_AVID<47>  @BASEBOARD_FAB2_LIB.BASEBOARD_FAB2(SCH_1):PVNN_PCH_STBY
  AA30  PVNN_PCH_STBY  VCCPRIM_AVID<46>  @BASEBOARD_FAB2_LIB.BASEBOARD_FAB2(SCH_1):PVNN_PCH_STBY
  AA32  PVNN_PCH_STBY  VCCPRIM_AVID<45>  @BASEBOARD_FAB2_LIB.BASEBOARD_FAB2(SCH_1):PVNN_PCH_STBY
  AA34  PVNN_PCH_STBY  VCCPRIM_AVID<44>  @BASEBOARD_FAB2_LIB.BASEBOARD_FAB2(SCH_1):PVNN_PCH_STBY
  AA36  PVNN_PCH_STBY  VCCPRIM_AVID<43>  @BASEBOARD_FAB2_LIB.BASEBOARD_FAB2(SCH_1):PVNN_PCH_STBY
  AA37  PVNN_PCH_STBY  VCCPRIM_AVID<42>  @BASEBOARD_FAB2_LIB.BASEBOARD_FAB2(SCH_1):PVNN_PCH_STBY
  AA39  PVNN_PCH_STBY  VCCPRIM_AVID<41>  @BASEBOARD_FAB2_LIB.BASEBOARD_FAB2(SCH_1):PVNN_PCH_STBY
  AA41  PVNN_PCH_STBY  VCCPRIM_AVID<40>  @BASEBOARD_FAB2_LIB.BASEBOARD_FAB2(SCH_1):PVNN_PCH_STBY
  AC29  PVNN_PCH_STBY  VCCPRIM_AVID<39>  @BASEBOARD_FAB2_LIB.BASEBOARD_FAB2(SCH_1):PVNN_PCH_STBY
  AC30  PVNN_PCH_STBY  VCCPRIM_AVID<38>  @BASEBOARD_FAB2_LIB.BASEBOARD_FAB2(SCH_1):PVNN_PCH_STBY
  AC32  PVNN_PCH_STBY  VCCPRIM_AVID<37>  @BASEBOARD_FAB2_LIB.BASEBOARD_FAB2(SCH_1):PVNN_PCH_STBY
  AC34  PVNN_PCH_STBY  VCCPRIM_AVID<36>  @BASEBOARD_FAB2_LIB.BASEBOARD_FAB2(SCH_1):PVNN_PCH_STBY
  AC36  PVNN_PCH_STBY  VCCPRIM_AVID<35>  @BASEBOARD_FAB2_LIB.BASEBOARD_FAB2(SCH_1):PVNN_PCH_STBY
  AC37  PVNN_PCH_STBY  VCCPRIM_AVID<34>  @BASEBOARD_FAB2_LIB.BASEBOARD_FAB2(SCH_1):PVNN_PCH_STBY
  AC39  PVNN_PCH_STBY  VCCPRIM_AVID<33>  @BASEBOARD_FAB2_LIB.BASEBOARD_FAB2(SCH_1):PVNN_PCH_STBY
  AC41  PVNN_PCH_STBY  VCCPRIM_AVID<32>  @BASEBOARD_FAB2_LIB.BASEBOARD_FAB2(SCH_1):PVNN_PCH_STBY
  U27  PVNN_PCH_STBY  VCCPRIM_AVID<31>  @BASEBOARD_FAB2_LIB.BASEBOARD_FAB2(SCH_1):PVNN_PCH_STBY
  AE30  PVNN_PCH_STBY  VCCPRIM_AVID<30>  @BASEBOARD_FAB2_LIB.BASEBOARD_FAB2(SCH_1):PVNN_PCH_STBY
  AE32  PVNN_PCH_STBY  VCCPRIM_AVID<29>  @BASEBOARD_FAB2_LIB.BASEBOARD_FAB2(SCH_1):PVNN_PCH_STBY
  AE34  PVNN_PCH_STBY  VCCPRIM_AVID<28>  @BASEBOARD_FAB2_LIB.BASEBOARD_FAB2(SCH_1):PVNN_PCH_STBY
  AE36  PVNN_PCH_STBY  VCCPRIM_AVID<27>  @BASEBOARD_FAB2_LIB.BASEBOARD_FAB2(SCH_1):PVNN_PCH_STBY
  AE37  PVNN_PCH_STBY  VCCPRIM_AVID<26>  @BASEBOARD_FAB2_LIB.BASEBOARD_FAB2(SCH_1):PVNN_PCH_STBY
  AE39  PVNN_PCH_STBY  VCCPRIM_AVID<25>  @BASEBOARD_FAB2_LIB.BASEBOARD_FAB2(SCH_1):PVNN_PCH_STBY
  AE41  PVNN_PCH_STBY  VCCPRIM_AVID<24>  @BASEBOARD_FAB2_LIB.BASEBOARD_FAB2(SCH_1):PVNN_PCH_STBY
  AG32  PVNN_PCH_STBY  VCCPRIM_AVID<23>  @BASEBOARD_FAB2_LIB.BASEBOARD_FAB2(SCH_1):PVNN_PCH_STBY
  AG34  PVNN_PCH_STBY  VCCPRIM_AVID<22>  @BASEBOARD_FAB2_LIB.BASEBOARD_FAB2(SCH_1):PVNN_PCH_STBY
  AG36  PVNN_PCH_STBY  VCCPRIM_AVID<21>  @BASEBOARD_FAB2_LIB.BASEBOARD_FAB2(SCH_1):PVNN_PCH_STBY
  AG37  PVNN_PCH_STBY  VCCPRIM_AVID<20>  @BASEBOARD_FAB2_LIB.BASEBOARD_FAB2(SCH_1):PVNN_PCH_STBY
  AG39  PVNN_PCH_STBY  VCCPRIM_AVID<19>  @BASEBOARD_FAB2_LIB.BASEBOARD_FAB2(SCH_1):PVNN_PCH_STBY
  AK34  PVNN_PCH_STBY  VCCPRIM_AVID<18>  @BASEBOARD_FAB2_LIB.BASEBOARD_FAB2(SCH_1):PVNN_PCH_STBY
  AK37  PVNN_PCH_STBY  VCCPRIM_AVID<17>  @BASEBOARD_FAB2_LIB.BASEBOARD_FAB2(SCH_1):PVNN_PCH_STBY
  AK39  PVNN_PCH_STBY  VCCPRIM_AVID<16>  @BASEBOARD_FAB2_LIB.BASEBOARD_FAB2(SCH_1):PVNN_PCH_STBY
  AM32  PVNN_PCH_STBY  VCCPRIM_AVID<15>  @BASEBOARD_FAB2_LIB.BASEBOARD_FAB2(SCH_1):PVNN_PCH_STBY
  AM34  PVNN_PCH_STBY  VCCPRIM_AVID<14>  @BASEBOARD_FAB2_LIB.BASEBOARD_FAB2(SCH_1):PVNN_PCH_STBY
  AM36  PVNN_PCH_STBY  VCCPRIM_AVID<13>  @BASEBOARD_FAB2_LIB.BASEBOARD_FAB2(SCH_1):PVNN_PCH_STBY
  AM37  PVNN_PCH_STBY  VCCPRIM_AVID<12>  @BASEBOARD_FAB2_LIB.BASEBOARD_FAB2(SCH_1):PVNN_PCH_STBY
  AM39  PVNN_PCH_STBY  VCCPRIM_AVID<11>  @BASEBOARD_FAB2_LIB.BASEBOARD_FAB2(SCH_1):PVNN_PCH_STBY
  AP32  PVNN_PCH_STBY  VCCPRIM_AVID<10>  @BASEBOARD_FAB2_LIB.BASEBOARD_FAB2(SCH_1):PVNN_PCH_STBY
  AP34  PVNN_PCH_STBY  VCCPRIM_AVID<9>  @BASEBOARD_FAB2_LIB.BASEBOARD_FAB2(SCH_1):PVNN_PCH_STBY
  AP36  PVNN_PCH_STBY  VCCPRIM_AVID<8>  @BASEBOARD_FAB2_LIB.BASEBOARD_FAB2(SCH_1):PVNN_PCH_STBY
  AP37  PVNN_PCH_STBY  VCCPRIM_AVID<7>  @BASEBOARD_FAB2_LIB.BASEBOARD_FAB2(SCH_1):PVNN_PCH_STBY
  AP39  PVNN_PCH_STBY  VCCPRIM_AVID<6>  @BASEBOARD_FAB2_LIB.BASEBOARD_FAB2(SCH_1):PVNN_PCH_STBY
  AT32  PVNN_PCH_STBY  VCCPRIM_AVID<5>  @BASEBOARD_FAB2_LIB.BASEBOARD_FAB2(SCH_1):PVNN_PCH_STBY
  AT34  PVNN_PCH_STBY  VCCPRIM_AVID<4>  @BASEBOARD_FAB2_LIB.BASEBOARD_FAB2(SCH_1):PVNN_PCH_STBY
  AT36  PVNN_PCH_STBY  VCCPRIM_AVID<3>  @BASEBOARD_FAB2_LIB.BASEBOARD_FAB2(SCH_1):PVNN_PCH_STBY
  AU32  PVNN_PCH_STBY  VCCPRIM_AVID<2>  @BASEBOARD_FAB2_LIB.BASEBOARD_FAB2(SCH_1):PVNN_PCH_STBY
  AU34  PVNN_PCH_STBY  VCCPRIM_AVID<1>  @BASEBOARD_FAB2_LIB.BASEBOARD_FAB2(SCH_1):PVNN_PCH_STBY
  AU36  PVNN_PCH_STBY  VCCPRIM_AVID<0>  @BASEBOARD_FAB2_LIB.BASEBOARD_FAB2(SCH_1):PVNN_PCH_STBY
  AE27  P1V05_PCH_STBY  VCCMPHY_1P05<13>  @BASEBOARD_FAB2_LIB.BASEBOARD_FAB2(SCH_1):P1V05_PCH_STBY

LBG_CORE_QAT_EXT_D  I63  U7C1   [LBG_CORE_QAT_EXT_D_BGA1-IC,H91A]
  AT27  TP_PCH_RSVD59  RSVD<59>  @BASEBOARD_FAB2_LIB.BASEBOARD_FAB2(SCH_1):TP_PCH_RSVD59
  AP27  TP_PCH_RSVD58  RSVD<58>  @BASEBOARD_FAB2_LIB.BASEBOARD_FAB2(SCH_1):TP_PCH_RSVD58
  P29  TP_PCH_RSVD31  RSVD<31>  @BASEBOARD_FAB2_LIB.BASEBOARD_FAB2(SCH_1):TP_PCH_RSVD31
  R31  TP_PCH_RSVD30  RSVD<30>  @BASEBOARD_FAB2_LIB.BASEBOARD_FAB2(SCH_1):TP_PCH_RSVD30
  P33  TP_PCH_RSVD29  RSVD<29>  @BASEBOARD_FAB2_LIB.BASEBOARD_FAB2(SCH_1):TP_PCH_RSVD29
  R35  TP_PCH_RSVD28  RSVD<28>  @BASEBOARD_FAB2_LIB.BASEBOARD_FAB2(SCH_1):TP_PCH_RSVD28
  BA48  P3V3_STBY      VCCPUSBDSW_3P3  @BASEBOARD_FAB2_LIB.BASEBOARD_FAB2(SCH_1):P3V3_STBY
  AR24  P3V3_STBY      VCCPSPI  @BASEBOARD_FAB2_LIB.BASEBOARD_FAB2(SCH_1):P3V3_STBY
  AG29  P3V3_STBY      VCCPRTCPRIM_3P3  @BASEBOARD_FAB2_LIB.BASEBOARD_FAB2(SCH_1):P3V3_STBY
  AU24  P3V3_STBY      VCCPGPPK  @BASEBOARD_FAB2_LIB.BASEBOARD_FAB2(SCH_1):P3V3_STBY
  BB26  P3V3_STBY      VCCPGPPJ  @BASEBOARD_FAB2_LIB.BASEBOARD_FAB2(SCH_1):P3V3_STBY
  BA24  P3V3_STBY      VCCPGPPH  @BASEBOARD_FAB2_LIB.BASEBOARD_FAB2(SCH_1):P3V3_STBY
  BA26  P3V3_STBY      VCCPGPPG  @BASEBOARD_FAB2_LIB.BASEBOARD_FAB2(SCH_1):P3V3_STBY
  AU27  P3V3_STBY      VCCPGPPF  @BASEBOARD_FAB2_LIB.BASEBOARD_FAB2(SCH_1):P3V3_STBY
  BE44  P3V3_STBY      VCCPGPPE  @BASEBOARD_FAB2_LIB.BASEBOARD_FAB2(SCH_1):P3V3_STBY
  BA43  P3V3_STBY      VCCPGPPD  @BASEBOARD_FAB2_LIB.BASEBOARD_FAB2(SCH_1):P3V3_STBY
  BE40  P3V3_STBY      VCCPGPPC  @BASEBOARD_FAB2_LIB.BASEBOARD_FAB2(SCH_1):P3V3_STBY
  BE26  P3V3_STBY      VCCPGPPB  @BASEBOARD_FAB2_LIB.BASEBOARD_FAB2(SCH_1):P3V3_STBY
  AW24  P3V3_STBY      VCCPGPPA  @BASEBOARD_FAB2_LIB.BASEBOARD_FAB2(SCH_1):P3V3_STBY
  AH24  P3V3_STBY      VCCPDSW_3P3  @BASEBOARD_FAB2_LIB.BASEBOARD_FAB2(SCH_1):P3V3_STBY
  AN24  P3V3_STBY      VCCP_3P3<5>  @BASEBOARD_FAB2_LIB.BASEBOARD_FAB2(SCH_1):P3V3_STBY
  AD24  P3V3_STBY      VCCP_3P3<2>  @BASEBOARD_FAB2_LIB.BASEBOARD_FAB2(SCH_1):P3V3_STBY
  BA45  P3V3_STBY      VCCP_3P3<1>  @BASEBOARD_FAB2_LIB.BASEBOARD_FAB2(SCH_1):P3V3_STBY
  BA46  P3V3_STBY      VCCP_3P3<0>  @BASEBOARD_FAB2_LIB.BASEBOARD_FAB2(SCH_1):P3V3_STBY
  AJ27  P3V3_RTC_STBY  VCCPRTC  @BASEBOARD_FAB2_LIB.BASEBOARD_FAB2(SCH_1):P3V3_RTC_STBY
  AK29  P1V8_PCH_STBY  VCCPSPI_1P8  @BASEBOARD_FAB2_LIB.BASEBOARD_FAB2(SCH_1):P1V8_PCH_STBY
  AG27  P1V8_PCH_STBY  VCCPHDA_1P8  @BASEBOARD_FAB2_LIB.BASEBOARD_FAB2(SCH_1):P1V8_PCH_STBY
  AK24  P1V8_PCH_STBY  VCCPGPP_1P8<6>  @BASEBOARD_FAB2_LIB.BASEBOARD_FAB2(SCH_1):P1V8_PCH_STBY
  AW27  P1V8_PCH_STBY  VCCPGPP_1P8<5>  @BASEBOARD_FAB2_LIB.BASEBOARD_FAB2(SCH_1):P1V8_PCH_STBY
  AP29  P1V8_PCH_STBY  VCCPGPP_1P8<4>  @BASEBOARD_FAB2_LIB.BASEBOARD_FAB2(SCH_1):P1V8_PCH_STBY
  AM29  P1V8_PCH_STBY  VCCPGPP_1P8<3>  @BASEBOARD_FAB2_LIB.BASEBOARD_FAB2(SCH_1):P1V8_PCH_STBY
  AT29  P1V8_PCH_STBY  VCCPGPP_1P8<2>  @BASEBOARD_FAB2_LIB.BASEBOARD_FAB2(SCH_1):P1V8_PCH_STBY
  AW29  P1V8_PCH_STBY  VCCPGPP_1P8<1>  @BASEBOARD_FAB2_LIB.BASEBOARD_FAB2(SCH_1):P1V8_PCH_STBY
  AU29  P1V8_PCH_STBY  VCCPGPP_1P8<0>  @BASEBOARD_FAB2_LIB.BASEBOARD_FAB2(SCH_1):P1V8_PCH_STBY
  AE26  P1V8_PCH_STBY  VCCP_1P8<1>  @BASEBOARD_FAB2_LIB.BASEBOARD_FAB2(SCH_1):P1V8_PCH_STBY
  BD46  P1V8_PCH_STBY  VCCP_1P8<0>  @BASEBOARD_FAB2_LIB.BASEBOARD_FAB2(SCH_1):P1V8_PCH_STBY
  BA27  P1V8_PCH_STBY  VCCP10GBE_HV_1P8<1>  @BASEBOARD_FAB2_LIB.BASEBOARD_FAB2(SCH_1):P1V8_PCH_STBY
  BA29  P1V8_PCH_STBY  VCCP10GBE_HV_1P8<0>  @BASEBOARD_FAB2_LIB.BASEBOARD_FAB2(SCH_1):P1V8_PCH_STBY
  AP48  P1V05_PCH_STBY_WM26_PLL  VCCP_HSIOPLL_1P05<3>  @BASEBOARD_FAB2_LIB.BASEBOARD_FAB2(SCH_1):P1V05_PCH_STBY_WM26_PLL
  AU48  P1V05_PCH_STBY_WM26_PLL  VCCP_HSIOPLL_1P05<2>  @BASEBOARD_FAB2_LIB.BASEBOARD_FAB2(SCH_1):P1V05_PCH_STBY_WM26_PLL
  AW48  P1V05_PCH_STBY_WM26_PLL  VCCP_HSIOPLL_1P05<0>  @BASEBOARD_FAB2_LIB.BASEBOARD_FAB2(SCH_1):P1V05_PCH_STBY_WM26_PLL
  AK50  P1V05_PCH_STBY_WM20_PLL  VCCP_UPPLL_1P05<2>  @BASEBOARD_FAB2_LIB.BASEBOARD_FAB2(SCH_1):P1V05_PCH_STBY_WM20_PLL
  AN50  P1V05_PCH_STBY_WM20_PLL  VCCP_UPPLL_1P05<0>  @BASEBOARD_FAB2_LIB.BASEBOARD_FAB2(SCH_1):P1V05_PCH_STBY_WM20_PLL
  AD50  P1V05_PCH_STBY_VCCA_XTAL  VCCA_CLKXTAL_1P05  @BASEBOARD_FAB2_LIB.BASEBOARD_FAB2(SCH_1):P1V05_PCH_STBY_VCCA_XTAL
  AE45  P1V05_PCH_STBY_VCCA_PLL1  VCCA_PLL1_1P05  @BASEBOARD_FAB2_LIB.BASEBOARD_FAB2(SCH_1):P1V05_PCH_STBY_VCCA_PLL1
  AG48  P1V05_PCH_STBY_VCCA_PLL0  VCCA_PLL0_1P05  @BASEBOARD_FAB2_LIB.BASEBOARD_FAB2(SCH_1):P1V05_PCH_STBY_VCCA_PLL0
  BA39  P1V05_PCH_STBY_KR_PLL  VCCP10GBEPLL_1P05<3>  @BASEBOARD_FAB2_LIB.BASEBOARD_FAB2(SCH_1):P1V05_PCH_STBY_KR_PLL
  BA41  P1V05_PCH_STBY_KR_PLL  VCCP10GBEPLL_1P05<2>  @BASEBOARD_FAB2_LIB.BASEBOARD_FAB2(SCH_1):P1V05_PCH_STBY_KR_PLL
  BB40  P1V05_PCH_STBY_KR_PLL  VCCP10GBEPLL_1P05<1>  @BASEBOARD_FAB2_LIB.BASEBOARD_FAB2(SCH_1):P1V05_PCH_STBY_KR_PLL
  BD38  P1V05_PCH_STBY_KR_PLL  VCCP10GBEPLL_1P05<0>  @BASEBOARD_FAB2_LIB.BASEBOARD_FAB2(SCH_1):P1V05_PCH_STBY_KR_PLL
  AE46  P1V05_PCH_STBY_ISCLK_PLL  VCCA_CLKFILT_1P05<4>  @BASEBOARD_FAB2_LIB.BASEBOARD_FAB2(SCH_1):P1V05_PCH_STBY_ISCLK_PLL
  AJ48  P1V05_PCH_STBY_ISCLK_PLL  VCCA_CLKFILT_1P05<3>  @BASEBOARD_FAB2_LIB.BASEBOARD_FAB2(SCH_1):P1V05_PCH_STBY_ISCLK_PLL
  AJ46  P1V05_PCH_STBY_ISCLK_PLL  VCCA_CLKFILT_1P05<2>  @BASEBOARD_FAB2_LIB.BASEBOARD_FAB2(SCH_1):P1V05_PCH_STBY_ISCLK_PLL
  AG45  P1V05_PCH_STBY_ISCLK_PLL  VCCA_CLKFILT_1P05<1>  @BASEBOARD_FAB2_LIB.BASEBOARD_FAB2(SCH_1):P1V05_PCH_STBY_ISCLK_PLL
  W50  P1V05_PCH_STBY_ISCLK_PLL  VCCA_CLKFILT_1P05<0>  @BASEBOARD_FAB2_LIB.BASEBOARD_FAB2(SCH_1):P1V05_PCH_STBY_ISCLK_PLL
  Y26  P1V05_PCH_STBY  VCCPRIM_1P05<19>  @BASEBOARD_FAB2_LIB.BASEBOARD_FAB2(SCH_1):P1V05_PCH_STBY
  AA24  P1V05_PCH_STBY  VCCPRIM_1P05<18>  @BASEBOARD_FAB2_LIB.BASEBOARD_FAB2(SCH_1):P1V05_PCH_STBY
  AK27  P1V05_PCH_STBY  VCCPRIM_1P05<17>  @BASEBOARD_FAB2_LIB.BASEBOARD_FAB2(SCH_1):P1V05_PCH_STBY
  R42  P1V05_PCH_STBY  VCCPRIM_1P05<16>  @BASEBOARD_FAB2_LIB.BASEBOARD_FAB2(SCH_1):P1V05_PCH_STBY
  R46  P1V05_PCH_STBY  VCCPRIM_1P05<15>  @BASEBOARD_FAB2_LIB.BASEBOARD_FAB2(SCH_1):P1V05_PCH_STBY
  T44  P1V05_PCH_STBY  VCCPRIM_1P05<14>  @BASEBOARD_FAB2_LIB.BASEBOARD_FAB2(SCH_1):P1V05_PCH_STBY
  U46  P1V05_PCH_STBY  VCCPRIM_1P05<13>  @BASEBOARD_FAB2_LIB.BASEBOARD_FAB2(SCH_1):P1V05_PCH_STBY
  V44  P1V05_PCH_STBY  VCCPRIM_1P05<12>  @BASEBOARD_FAB2_LIB.BASEBOARD_FAB2(SCH_1):P1V05_PCH_STBY
  Y45  P1V05_PCH_STBY  VCCPRIM_1P05<11>  @BASEBOARD_FAB2_LIB.BASEBOARD_FAB2(SCH_1):P1V05_PCH_STBY
  Y46  P1V05_PCH_STBY  VCCPRIM_1P05<10>  @BASEBOARD_FAB2_LIB.BASEBOARD_FAB2(SCH_1):P1V05_PCH_STBY
  AA45  P1V05_PCH_STBY  VCCPRIM_1P05<9>  @BASEBOARD_FAB2_LIB.BASEBOARD_FAB2(SCH_1):P1V05_PCH_STBY
  AA46  P1V05_PCH_STBY  VCCPRIM_1P05<8>  @BASEBOARD_FAB2_LIB.BASEBOARD_FAB2(SCH_1):P1V05_PCH_STBY
  AC26  P1V05_PCH_STBY  VCCPRIM_1P05<7>  @BASEBOARD_FAB2_LIB.BASEBOARD_FAB2(SCH_1):P1V05_PCH_STBY
  AJ29  P1V05_PCH_STBY  VCCPRIM_1P05<6>  @BASEBOARD_FAB2_LIB.BASEBOARD_FAB2(SCH_1):P1V05_PCH_STBY
  AM27  P1V05_PCH_STBY  VCCPRIM_1P05<5>  @BASEBOARD_FAB2_LIB.BASEBOARD_FAB2(SCH_1):P1V05_PCH_STBY
  AT39  P1V05_PCH_STBY  VCCPRIM_1P05<4>  @BASEBOARD_FAB2_LIB.BASEBOARD_FAB2(SCH_1):P1V05_PCH_STBY
  AU37  P1V05_PCH_STBY  VCCPRIM_1P05<3>  @BASEBOARD_FAB2_LIB.BASEBOARD_FAB2(SCH_1):P1V05_PCH_STBY
  AU39  P1V05_PCH_STBY  VCCPRIM_1P05<2>  @BASEBOARD_FAB2_LIB.BASEBOARD_FAB2(SCH_1):P1V05_PCH_STBY
  BE48  P1V05_PCH_STBY  VCCPRIM_1P05<1>  @BASEBOARD_FAB2_LIB.BASEBOARD_FAB2(SCH_1):P1V05_PCH_STBY
  BF46  P1V05_PCH_STBY  VCCPRIM_1P05<0>  @BASEBOARD_FAB2_LIB.BASEBOARD_FAB2(SCH_1):P1V05_PCH_STBY
  AM48  P1V05_PCH_STBY  VCCP_UPPLLUNF_1P05  @BASEBOARD_FAB2_LIB.BASEBOARD_FAB2(SCH_1):P1V05_PCH_STBY
  AT48  P1V05_PCH_STBY  VCCP_HSIOPLLUNF_1P05  @BASEBOARD_FAB2_LIB.BASEBOARD_FAB2(SCH_1):P1V05_PCH_STBY
  BA30  P1V05_PCH_STBY  VCCP10GBE_LV_1P05<6>  @BASEBOARD_FAB2_LIB.BASEBOARD_FAB2(SCH_1):P1V05_PCH_STBY
  BA32  P1V05_PCH_STBY  VCCP10GBE_LV_1P05<5>  @BASEBOARD_FAB2_LIB.BASEBOARD_FAB2(SCH_1):P1V05_PCH_STBY
  BA34  P1V05_PCH_STBY  VCCP10GBE_LV_1P05<4>  @BASEBOARD_FAB2_LIB.BASEBOARD_FAB2(SCH_1):P1V05_PCH_STBY
  BA36  P1V05_PCH_STBY  VCCP10GBE_LV_1P05<3>  @BASEBOARD_FAB2_LIB.BASEBOARD_FAB2(SCH_1):P1V05_PCH_STBY
  BA37  P1V05_PCH_STBY  VCCP10GBE_LV_1P05<2>  @BASEBOARD_FAB2_LIB.BASEBOARD_FAB2(SCH_1):P1V05_PCH_STBY
  BB33  P1V05_PCH_STBY  VCCP10GBE_LV_1P05<1>  @BASEBOARD_FAB2_LIB.BASEBOARD_FAB2(SCH_1):P1V05_PCH_STBY
  BB37  P1V05_PCH_STBY  VCCP10GBE_LV_1P05<0>  @BASEBOARD_FAB2_LIB.BASEBOARD_FAB2(SCH_1):P1V05_PCH_STBY
  AK43  P1V05_PCH_STBY  VCCMPHY_1P05<12>  @BASEBOARD_FAB2_LIB.BASEBOARD_FAB2(SCH_1):P1V05_PCH_STBY
  AK45  P1V05_PCH_STBY  VCCMPHY_1P05<11>  @BASEBOARD_FAB2_LIB.BASEBOARD_FAB2(SCH_1):P1V05_PCH_STBY
  AM43  P1V05_PCH_STBY  VCCMPHY_1P05<10>  @BASEBOARD_FAB2_LIB.BASEBOARD_FAB2(SCH_1):P1V05_PCH_STBY
  AM45  P1V05_PCH_STBY  VCCMPHY_1P05<9>  @BASEBOARD_FAB2_LIB.BASEBOARD_FAB2(SCH_1):P1V05_PCH_STBY
  AP43  P1V05_PCH_STBY  VCCMPHY_1P05<8>  @BASEBOARD_FAB2_LIB.BASEBOARD_FAB2(SCH_1):P1V05_PCH_STBY
  AP45  P1V05_PCH_STBY  VCCMPHY_1P05<7>  @BASEBOARD_FAB2_LIB.BASEBOARD_FAB2(SCH_1):P1V05_PCH_STBY
  AT43  P1V05_PCH_STBY  VCCMPHY_1P05<6>  @BASEBOARD_FAB2_LIB.BASEBOARD_FAB2(SCH_1):P1V05_PCH_STBY
  AT45  P1V05_PCH_STBY  VCCMPHY_1P05<5>  @BASEBOARD_FAB2_LIB.BASEBOARD_FAB2(SCH_1):P1V05_PCH_STBY
  AU43  P1V05_PCH_STBY  VCCMPHY_1P05<4>  @BASEBOARD_FAB2_LIB.BASEBOARD_FAB2(SCH_1):P1V05_PCH_STBY
  AU45  P1V05_PCH_STBY  VCCMPHY_1P05<3>  @BASEBOARD_FAB2_LIB.BASEBOARD_FAB2(SCH_1):P1V05_PCH_STBY
  AJ43  P1V05_PCH_STBY  VCCMPHY_1P05<2>  @BASEBOARD_FAB2_LIB.BASEBOARD_FAB2(SCH_1):P1V05_PCH_STBY
  AW43  P1V05_PCH_STBY  VCCMPHY_1P05<1>  @BASEBOARD_FAB2_LIB.BASEBOARD_FAB2(SCH_1):P1V05_PCH_STBY
  AW45  P1V05_PCH_STBY  VCCMPHY_1P05<0>  @BASEBOARD_FAB2_LIB.BASEBOARD_FAB2(SCH_1):P1V05_PCH_STBY
  U50  P1V05_PCH_STBY  VCCA_CLKUNF_1P05<1>  @BASEBOARD_FAB2_LIB.BASEBOARD_FAB2(SCH_1):P1V05_PCH_STBY
  AH50  P1V05_PCH_STBY  VCCA_CLKUNF_1P05<0>  @BASEBOARD_FAB2_LIB.BASEBOARD_FAB2(SCH_1):P1V05_PCH_STBY
  AG22  A_PVCCRTC_EXT_CAP  VCCRTCEXT  @BASEBOARD_FAB2_LIB.BASEBOARD_FAB2(SCH_1):A_PVCCRTC_EXT_CAP

LBG_CORE_QAT_EXT_D  I34  U7C1   [LBG_CORE_QAT_EXT_D_BGA1-IC,H91A]
   G7  TP_SPI_PCH_CS1_R1_N  SPI0_FLASH_CS1_N  @BASEBOARD_FAB2_LIB.BASEBOARD_FAB2(SCH_1):TP_SPI_PCH_CS1_R1_N
  F66  TP_PCH_RSVD9   RSVD<9>  @BASEBOARD_FAB2_LIB.BASEBOARD_FAB2(SCH_1):TP_PCH_RSVD9
  F69  TP_PCH_RSVD8   RSVD<8>  @BASEBOARD_FAB2_LIB.BASEBOARD_FAB2(SCH_1):TP_PCH_RSVD8
   F8  TP_PCH_RSVD7   RSVD<7>  @BASEBOARD_FAB2_LIB.BASEBOARD_FAB2(SCH_1):TP_PCH_RSVD7
  AT69  TP_PCH_RSVD6   RSVD<6>  @BASEBOARD_FAB2_LIB.BASEBOARD_FAB2(SCH_1):TP_PCH_RSVD6
  AG15  TP_PCH_RSVD5   RSVD<5>  @BASEBOARD_FAB2_LIB.BASEBOARD_FAB2(SCH_1):TP_PCH_RSVD5
  BW3  TP_PCH_RSVD46  RSVD<46>  @BASEBOARD_FAB2_LIB.BASEBOARD_FAB2(SCH_1):TP_PCH_RSVD46
  P37  TP_PCH_RSVD4   RSVD<4>  @BASEBOARD_FAB2_LIB.BASEBOARD_FAB2(SCH_1):TP_PCH_RSVD4
  V11  TP_PCH_RSVD3   RSVD<3>  @BASEBOARD_FAB2_LIB.BASEBOARD_FAB2(SCH_1):TP_PCH_RSVD3
  BG26  TP_PCH_RSVD27  RSVD<27>  @BASEBOARD_FAB2_LIB.BASEBOARD_FAB2(SCH_1):TP_PCH_RSVD27
  BH24  TP_PCH_RSVD26  RSVD<26>  @BASEBOARD_FAB2_LIB.BASEBOARD_FAB2(SCH_1):TP_PCH_RSVD26
  P48  TP_PCH_RSVD25  RSVD<25>  @BASEBOARD_FAB2_LIB.BASEBOARD_FAB2(SCH_1):TP_PCH_RSVD25
  P44  TP_PCH_RSVD24  RSVD<24>  @BASEBOARD_FAB2_LIB.BASEBOARD_FAB2(SCH_1):TP_PCH_RSVD24
  P40  TP_PCH_RSVD23  RSVD<23>  @BASEBOARD_FAB2_LIB.BASEBOARD_FAB2(SCH_1):TP_PCH_RSVD23
  AT71  TP_PCH_RSVD22  RSVD<22>  @BASEBOARD_FAB2_LIB.BASEBOARD_FAB2(SCH_1):TP_PCH_RSVD22
  A11  TP_PCH_RSVD21  RSVD<21>  @BASEBOARD_FAB2_LIB.BASEBOARD_FAB2(SCH_1):TP_PCH_RSVD21
  D10  TP_PCH_RSVD20  RSVD<20>  @BASEBOARD_FAB2_LIB.BASEBOARD_FAB2(SCH_1):TP_PCH_RSVD20
  AA58  TP_PCH_RSVD2   RSVD<2>  @BASEBOARD_FAB2_LIB.BASEBOARD_FAB2(SCH_1):TP_PCH_RSVD2
   C9  TP_PCH_RSVD19  RSVD<19>  @BASEBOARD_FAB2_LIB.BASEBOARD_FAB2(SCH_1):TP_PCH_RSVD19
  C11  TP_PCH_RSVD18  RSVD<18>  @BASEBOARD_FAB2_LIB.BASEBOARD_FAB2(SCH_1):TP_PCH_RSVD18
  B10  TP_PCH_RSVD17  RSVD<17>  @BASEBOARD_FAB2_LIB.BASEBOARD_FAB2(SCH_1):TP_PCH_RSVD17
   C5  TP_PCH_RSVD16  RSVD<16>  @BASEBOARD_FAB2_LIB.BASEBOARD_FAB2(SCH_1):TP_PCH_RSVD16
   C6  TP_PCH_RSVD15  RSVD<15>  @BASEBOARD_FAB2_LIB.BASEBOARD_FAB2(SCH_1):TP_PCH_RSVD15
  E18  TP_PCH_RSVD14  RSVD<14>  @BASEBOARD_FAB2_LIB.BASEBOARD_FAB2(SCH_1):TP_PCH_RSVD14
  C67  TP_PCH_RSVD13  RSVD<13>  @BASEBOARD_FAB2_LIB.BASEBOARD_FAB2(SCH_1):TP_PCH_RSVD13
  C68  TP_PCH_RSVD12  RSVD<12>  @BASEBOARD_FAB2_LIB.BASEBOARD_FAB2(SCH_1):TP_PCH_RSVD12
  AC56  TP_PCH_RSVD1   RSVD<1>  @BASEBOARD_FAB2_LIB.BASEBOARD_FAB2(SCH_1):TP_PCH_RSVD1
  AF61  TP_PCH_RSVD0   RSVD<0>  @BASEBOARD_FAB2_LIB.BASEBOARD_FAB2(SCH_1):TP_PCH_RSVD0
  M18  TP_PCH_HSA_RST_N  HDA_RST_N  @BASEBOARD_FAB2_LIB.BASEBOARD_FAB2(SCH_1):TP_PCH_HSA_RST_N
  H20  TP_PCH_HDA_SYNC  HDA_SYNC  @BASEBOARD_FAB2_LIB.BASEBOARD_FAB2(SCH_1):TP_PCH_HDA_SYNC
  V18  TP_PCH_HDA_SDI_1  HDA_SDI_1  @BASEBOARD_FAB2_LIB.BASEBOARD_FAB2(SCH_1):TP_PCH_HDA_SDI_1
  K20  TP_PCH_HDA_SDI_0  HDA_SDI_0  @BASEBOARD_FAB2_LIB.BASEBOARD_FAB2(SCH_1):TP_PCH_HDA_SDI_0
  P18  TP_PCH_HDA_BCLK  HDA_BCLK  @BASEBOARD_FAB2_LIB.BASEBOARD_FAB2(SCH_1):TP_PCH_HDA_BCLK
  AD20  TP_PCH_GPP_L11  GPP_L11_TESTCH1_D0  @BASEBOARD_FAB2_LIB.BASEBOARD_FAB2(SCH_1):TP_PCH_GPP_L11
  AF20  TP_PCH_GPP_L10  GPP_L10_TESTCH0_CLK  @BASEBOARD_FAB2_LIB.BASEBOARD_FAB2(SCH_1):TP_PCH_GPP_L10
  V22  TP_PCH_DISPA_SDO  RSVD<68>  @BASEBOARD_FAB2_LIB.BASEBOARD_FAB2(SCH_1):TP_PCH_DISPA_SDO
  R20  TP_PCH_DISPA_SDI  RSVD<67>  @BASEBOARD_FAB2_LIB.BASEBOARD_FAB2(SCH_1):TP_PCH_DISPA_SDI
  U20  TP_PCH_DISPA_BCLK  RSVD<66>  @BASEBOARD_FAB2_LIB.BASEBOARD_FAB2(SCH_1):TP_PCH_DISPA_BCLK
   K4  SPI_PCH_TPM_CS_N  SPI0_TPM_CS_N  @BASEBOARD_FAB2_LIB.BASEBOARD_FAB2(SCH_1):SPI_PCH_TPM_CS_N
   H4  SPI_PCH_MOSI_R  SPI0_MOSI_IO0  @BASEBOARD_FAB2_LIB.BASEBOARD_FAB2(SCH_1):SPI_PCH_MOSI_R
   L3  SPI_PCH_MISO   SPI0_MISO_IO1  @BASEBOARD_FAB2_LIB.BASEBOARD_FAB2(SCH_1):SPI_PCH_MISO
   L1  SPI_PCH_IO3    SPI0_IO3  @BASEBOARD_FAB2_LIB.BASEBOARD_FAB2(SCH_1):SPI_PCH_IO3
   F5  SPI_PCH_IO2    SPI0_IO2  @BASEBOARD_FAB2_LIB.BASEBOARD_FAB2(SCH_1):SPI_PCH_IO2
   J3  SPI_PCH_CS0_R_N  SPI0_FLASH_CS0_N  @BASEBOARD_FAB2_LIB.BASEBOARD_FAB2(SCH_1):SPI_PCH_CS0_R_N
   K2  SPI_PCH_CLK    SPI0_CLK  @BASEBOARD_FAB2_LIB.BASEBOARD_FAB2(SCH_1):SPI_PCH_CLK
  G18  RST_SRTCRST_N  SRTCRST_N  @BASEBOARD_FAB2_LIB.BASEBOARD_FAB2(SCH_1):RST_SRTCRST_N
  P11  RST_RTCRST_N   RTCRST_N  @BASEBOARD_FAB2_LIB.BASEBOARD_FAB2(SCH_1):RST_RTCRST_N
  AH4  RST_PCIE_PCH_PERST_N  GPP_K10_PE_RST_N  @BASEBOARD_FAB2_LIB.BASEBOARD_FAB2(SCH_1):RST_PCIE_PCH_PERST_N
  AN1  RMII_SPRNGVLLE_BMC_PCH_RXD1_R1  GPP_K6_LAN_NCSI_RXD1  @BASEBOARD_FAB2_LIB.BASEBOARD_FAB2(SCH_1):RMII_SPRNGVLLE_BMC_PCH_RXD1_R1
  AL1  RMII_SPRNGVLLE_BMC_PCH_RXD0_R1  GPP_K5_LAN_NCSI_RXD0  @BASEBOARD_FAB2_LIB.BASEBOARD_FAB2(SCH_1):RMII_SPRNGVLLE_BMC_PCH_RXD0_R1
  AK4  RMII_PCH_SPRNGVLLE_ARB_OUT_R  GPP_K9_LAN_NCSI_ARB_OUT  @BASEBOARD_FAB2_LIB.BASEBOARD_FAB2(SCH_1):RMII_PCH_SPRNGVLLE_ARB_OUT_R
  AJ3  RMII_PCH_SPRNGVLLE_ARB_IN  GPP_K8_LAN_NCSI_ARB_IN  @BASEBOARD_FAB2_LIB.BASEBOARD_FAB2(SCH_1):RMII_PCH_SPRNGVLLE_ARB_IN
  AL3  RMII_BMC_PCH_SPRNGVLLE_TXEN  GPP_K3_LAN_NCSI_TX_EN  @BASEBOARD_FAB2_LIB.BASEBOARD_FAB2(SCH_1):RMII_BMC_PCH_SPRNGVLLE_TXEN
  AK2  RMII_BMC_PCH_SPRNGVLLE_TXD1  GPP_K2_LAN_NCSI_TXD1  @BASEBOARD_FAB2_LIB.BASEBOARD_FAB2(SCH_1):RMII_BMC_PCH_SPRNGVLLE_TXD1
  AM2  RMII_BMC_PCH_SPRNGVLLE_TXD0  GPP_K1_LAN_NCSI_TXD0  @BASEBOARD_FAB2_LIB.BASEBOARD_FAB2(SCH_1):RMII_BMC_PCH_SPRNGVLLE_TXD0
  AH2  RMII_BMC_PCH_SPRNGVLLE_RXER_R  GPP_K7  @BASEBOARD_FAB2_LIB.BASEBOARD_FAB2(SCH_1):RMII_BMC_PCH_SPRNGVLLE_RXER_R
  AN3  RMII_BMC_PCH_SPRNGVLLE_CRSDV_R1  GPP_K4_LAN_NCSI_CRS_DV  @BASEBOARD_FAB2_LIB.BASEBOARD_FAB2(SCH_1):RMII_BMC_PCH_SPRNGVLLE_CRSDV_R1
  Y11  H_CPU1_MEMKLM_MEMHOT_PCH_N  GPP_L15_TESTCH1_D4  @BASEBOARD_FAB2_LIB.BASEBOARD_FAB2(SCH_1):H_CPU1_MEMKLM_MEMHOT_PCH_N
  AA13  H_CPU1_MEMGHJ_MEMHOT_PCH_N  GPP_L14_TESTCH1_D3  @BASEBOARD_FAB2_LIB.BASEBOARD_FAB2(SCH_1):H_CPU1_MEMGHJ_MEMHOT_PCH_N
  AD13  H_CPU0_MEMDEF_MEMHOT_PCH_N  GPP_L13_TESTCH1_D2  @BASEBOARD_FAB2_LIB.BASEBOARD_FAB2(SCH_1):H_CPU0_MEMDEF_MEMHOT_PCH_N
  Y15  H_CPU0_MEMABC_MEMHOT_PCH_N  GPP_L12_TESTCH1_D1  @BASEBOARD_FAB2_LIB.BASEBOARD_FAB2(SCH_1):H_CPU0_MEMABC_MEMHOT_PCH_N
   D8  FM_WBG_PRSNT_N  RSVD<10>  @BASEBOARD_FAB2_LIB.BASEBOARD_FAB2(SCH_1):FM_WBG_PRSNT_N
  C18  FM_SINT_PRSNT_N  RSVD<11>  @BASEBOARD_FAB2_LIB.BASEBOARD_FAB2(SCH_1):FM_SINT_PRSNT_N
  AA17  FM_PRSNT_2_6_N  GPP_L7_TESTCH0_D5  @BASEBOARD_FAB2_LIB.BASEBOARD_FAB2(SCH_1):FM_PRSNT_2_6_N
  AA20  FM_PRSNT_2_5_N  GPP_L6_TESTCH0_D4  @BASEBOARD_FAB2_LIB.BASEBOARD_FAB2(SCH_1):FM_PRSNT_2_5_N
  Y18  FM_PRSNT_2_4_N  GPP_L5_TESTCH0_D3  @BASEBOARD_FAB2_LIB.BASEBOARD_FAB2(SCH_1):FM_PRSNT_2_4_N
  AE11  FM_PRSNT_2_3_N  GPP_L4_TESTCH0_D2  @BASEBOARD_FAB2_LIB.BASEBOARD_FAB2(SCH_1):FM_PRSNT_2_3_N
  AE15  FM_PRSNT_2_2_N  GPP_L3_TESTCH0_D1  @BASEBOARD_FAB2_LIB.BASEBOARD_FAB2(SCH_1):FM_PRSNT_2_2_N
  AE18  FM_PRSNT_2_1_N  GPP_L2_TESTCH0_D0  @BASEBOARD_FAB2_LIB.BASEBOARD_FAB2(SCH_1):FM_PRSNT_2_1_N
  C70  FM_PCH_PRSNT_N  CGC_DUT_DETECT_N  @BASEBOARD_FAB2_LIB.BASEBOARD_FAB2(SCH_1):FM_PCH_PRSNT_N
  AD17  FM_OCP_MEZZC_PRES_N  GPP_L9_TESTCH0_D7  @BASEBOARD_FAB2_LIB.BASEBOARD_FAB2(SCH_1):FM_OCP_MEZZC_PRES_N
  AD9  FM_OCP_MEZZB_PRES_N  GPP_L8_TESTCH0_D6  @BASEBOARD_FAB2_LIB.BASEBOARD_FAB2(SCH_1):FM_OCP_MEZZB_PRES_N
  AG18  FM_INTRUDER_HDR_PCH_N  INTRUDER_N  @BASEBOARD_FAB2_LIB.BASEBOARD_FAB2(SCH_1):FM_INTRUDER_HDR_PCH_N
  U24  FM_FLASH_DESC_OVERRIDE  HDA_SDO  @BASEBOARD_FAB2_LIB.BASEBOARD_FAB2(SCH_1):FM_FLASH_DESC_OVERRIDE
  AG11  FM_CPU_ERR1_PCH_N  GPP_L19_TESTCH1_CLK  @BASEBOARD_FAB2_LIB.BASEBOARD_FAB2(SCH_1):FM_CPU_ERR1_PCH_N
  AE7  FM_CPU_ERR0_PCH_N  GPP_L18_TESTCH1_D7  @BASEBOARD_FAB2_LIB.BASEBOARD_FAB2(SCH_1):FM_CPU_ERR0_PCH_N
  AA9  FM_CPU1_PROCHOT_PCH_N  GPP_L17_TESTCH1_D6  @BASEBOARD_FAB2_LIB.BASEBOARD_FAB2(SCH_1):FM_CPU1_PROCHOT_PCH_N
   Y7  FM_CPU0_PROCHOT_PCH_N  GPP_L16_TESTCH1_D5  @BASEBOARD_FAB2_LIB.BASEBOARD_FAB2(SCH_1):FM_CPU0_PROCHOT_PCH_N
  AJ1  CLK_50M_CKMNG_PCH_10GBE  GPP_K0_LAN_NCSI_CLK_IN  @BASEBOARD_FAB2_LIB.BASEBOARD_FAB2(SCH_1):CLK_50M_CKMNG_PCH_10GBE
  AM4  A_1P8_3P3_RCOMP  GPIO_RCOMP_1P8_3P3  @BASEBOARD_FAB2_LIB.BASEBOARD_FAB2(SCH_1):A_1P8_3P3_RCOMP

LBG_CORE_QAT_EXT_D  I147  U7C1   [LBG_CORE_QAT_EXT_D_BGA1-IC,H91A]
  BV14  TP_PCH_GPP_J23  GPP_J23_LAN_SDP_P3_1  @BASEBOARD_FAB2_LIB.BASEBOARD_FAB2(SCH_1):TP_PCH_GPP_J23
  BV12  TP_PCH_GPP_J21  GPP_J21_LAN_SDP_P2_1  @BASEBOARD_FAB2_LIB.BASEBOARD_FAB2(SCH_1):TP_PCH_GPP_J21
  BY14  TP_PCH_GPP_J19  GPP_J19_LAN_SDP_P1_1  @BASEBOARD_FAB2_LIB.BASEBOARD_FAB2(SCH_1):TP_PCH_GPP_J19
  CA11  TP_PCH_GPP_J17  GPP_J17_LAN_SDP_P0_1  @BASEBOARD_FAB2_LIB.BASEBOARD_FAB2(SCH_1):TP_PCH_GPP_J17
  AP7  TP_PCH_GPP_F12  GPP_F12_SATA_SDATAOUT1  @BASEBOARD_FAB2_LIB.BASEBOARD_FAB2(SCH_1):TP_PCH_GPP_F12
  BD1  SMB_VR_STBY_LVC3_SDA_R1  GPP_H11_SML2DATA_IE  @BASEBOARD_FAB2_LIB.BASEBOARD_FAB2(SCH_1):SMB_VR_STBY_LVC3_SDA_R1
  BA4  SMB_VR_STBY_LVC3_SCL_R1  GPP_H10_SML2CLK_IE  @BASEBOARD_FAB2_LIB.BASEBOARD_FAB2(SCH_1):SMB_VR_STBY_LVC3_SCL_R1
  BC2  SMB_SENSOR_STBY_LVC3_SDA_R1  GPP_H14_SML3DATA_IE  @BASEBOARD_FAB2_LIB.BASEBOARD_FAB2(SCH_1):SMB_SENSOR_STBY_LVC3_SDA_R1
  AY1  SMB_SENSOR_STBY_LVC3_SCL_R1  GPP_H13_SML3CLK_IE  @BASEBOARD_FAB2_LIB.BASEBOARD_FAB2(SCH_1):SMB_SENSOR_STBY_LVC3_SCL_R1
  BW9  SMB_PCH_MEZZ_LOM3_SDA  GPP_J15_LAN_I2C_SDA_MDIO_P3  @BASEBOARD_FAB2_LIB.BASEBOARD_FAB2(SCH_1):SMB_PCH_MEZZ_LOM3_SDA
  BW6  SMB_PCH_MEZZ_LOM3_SCL  GPP_J14_LAN_I2C_SCL_MDC_P3  @BASEBOARD_FAB2_LIB.BASEBOARD_FAB2(SCH_1):SMB_PCH_MEZZ_LOM3_SCL
  BW11  SMB_PCH_MEZZ_LOM2_SDA  GPP_J13_LAN_I2C_SDA_MDIO_P2  @BASEBOARD_FAB2_LIB.BASEBOARD_FAB2(SCH_1):SMB_PCH_MEZZ_LOM2_SDA
  BT5  SMB_PCH_MEZZ_LOM2_SCL  GPP_J12_LAN_I2C_SCL_MDC_P2  @BASEBOARD_FAB2_LIB.BASEBOARD_FAB2(SCH_1):SMB_PCH_MEZZ_LOM2_SCL
  BV8  SMB_PCH_MEZZ_LOM1_SDA  GPP_J11_LAN_I2C_SDA_MDIO_P1  @BASEBOARD_FAB2_LIB.BASEBOARD_FAB2(SCH_1):SMB_PCH_MEZZ_LOM1_SDA
  BW5  SMB_PCH_MEZZ_LOM1_SCL  GPP_J10_LAN_I2C_SCL_MDC_P1  @BASEBOARD_FAB2_LIB.BASEBOARD_FAB2(SCH_1):SMB_PCH_MEZZ_LOM1_SCL
  BN3  SMB_PCH_MEZZ_LOM0_SDA  GPP_J9_LAN_I2C_SDA_MDIO_P0  @BASEBOARD_FAB2_LIB.BASEBOARD_FAB2(SCH_1):SMB_PCH_MEZZ_LOM0_SDA
  BM4  SMB_PCH_MEZZ_LOM0_SCL  GPP_J8_LAN_I2C_SCL_MDC_P0  @BASEBOARD_FAB2_LIB.BASEBOARD_FAB2(SCH_1):SMB_PCH_MEZZ_LOM0_SCL
  AU20  SMB_LAN_STBY_LVC3_SDA_R2  GPP_F20_LAN_SMBDATA  @BASEBOARD_FAB2_LIB.BASEBOARD_FAB2(SCH_1):SMB_LAN_STBY_LVC3_SDA_R2
  BE4  SMB_LAN_STBY_LVC3_SDA_R1  GPP_H17_SML4DATA_IE  @BASEBOARD_FAB2_LIB.BASEBOARD_FAB2(SCH_1):SMB_LAN_STBY_LVC3_SDA_R1
  AU9  SMB_LAN_STBY_LVC3_SCL_R2  GPP_F19_LAN_SMBCLK  @BASEBOARD_FAB2_LIB.BASEBOARD_FAB2(SCH_1):SMB_LAN_STBY_LVC3_SCL_R2
  BF1  SMB_LAN_STBY_LVC3_SCL_R1  GPP_H16_SML4CLK_IE  @BASEBOARD_FAB2_LIB.BASEBOARD_FAB2(SCH_1):SMB_LAN_STBY_LVC3_SCL_R1
  AU17  SGPIO_PCH_SSATA_LOAD  GPP_F23_SSATA_SLOAD  @BASEBOARD_FAB2_LIB.BASEBOARD_FAB2(SCH_1):SGPIO_PCH_SSATA_LOAD
  AP18  SGPIO_PCH_SSATA_CLOCK  GPP_F22_SSATA_SCLOCK  @BASEBOARD_FAB2_LIB.BASEBOARD_FAB2(SCH_1):SGPIO_PCH_SSATA_CLOCK
  AR9  SGPIO_PCH_SATA_LOAD  GPP_F11_SATA_SLOAD  @BASEBOARD_FAB2_LIB.BASEBOARD_FAB2(SCH_1):SGPIO_PCH_SATA_LOAD
  AP11  SGPIO_PCH_SATA_DOUT0  GPP_F13_SATA_SDATAOUT0  @BASEBOARD_FAB2_LIB.BASEBOARD_FAB2(SCH_1):SGPIO_PCH_SATA_DOUT0
  AL7  SGPIO_PCH_SATA_CLOCK  GPP_F10_SATA_SCLOCK  @BASEBOARD_FAB2_LIB.BASEBOARD_FAB2(SCH_1):SGPIO_PCH_SATA_CLOCK
  BB3  PU_ADR_TIMER_HOLD_OFF_N  GPP_H15_SML3ALERT_N_IE_N  @BASEBOARD_FAB2_LIB.BASEBOARD_FAB2(SCH_1):PU_ADR_TIMER_HOLD_OFF_N
  BW22  PU_10GBE_LOM_PCI_DISABLE_N  GPP_I8_PCI_DIS_N  @BASEBOARD_FAB2_LIB.BASEBOARD_FAB2(SCH_1):PU_10GBE_LOM_PCI_DISABLE_N
  BE2  LED_POSTCODE_7  GPP_H9_SRCCLKREQ15_N  @BASEBOARD_FAB2_LIB.BASEBOARD_FAB2(SCH_1):LED_POSTCODE_7
  AR3  LED_POSTCODE_6  GPP_H8_SRCCLKREQ14_N  @BASEBOARD_FAB2_LIB.BASEBOARD_FAB2(SCH_1):LED_POSTCODE_6
  AV1  LED_POSTCODE_5  GPP_H7_SRCCLKREQ13_N  @BASEBOARD_FAB2_LIB.BASEBOARD_FAB2(SCH_1):LED_POSTCODE_5
  AW2  LED_POSTCODE_4  GPP_H6_SRCCLKREQ12_N  @BASEBOARD_FAB2_LIB.BASEBOARD_FAB2(SCH_1):LED_POSTCODE_4
  AY3  LED_POSTCODE_3  GPP_H5_SRCCLKREQ11_N  @BASEBOARD_FAB2_LIB.BASEBOARD_FAB2(SCH_1):LED_POSTCODE_3
  AT2  LED_POSTCODE_2  GPP_H4_SRCCLKREQ10_N  @BASEBOARD_FAB2_LIB.BASEBOARD_FAB2(SCH_1):LED_POSTCODE_2
  AR1  LED_POSTCODE_1  GPP_H3_SRCCLKREQ9_N  @BASEBOARD_FAB2_LIB.BASEBOARD_FAB2(SCH_1):LED_POSTCODE_1
  AV3  LED_POSTCODE_0  GPP_H2_SRCCLKREQ8_N  @BASEBOARD_FAB2_LIB.BASEBOARD_FAB2(SCH_1):LED_POSTCODE_0
  AL11  LED_PCH_SSATA_HDD_N  GPP_F14_SSATA_LED_N  @BASEBOARD_FAB2_LIB.BASEBOARD_FAB2(SCH_1):LED_PCH_SSATA_HDD_N
  AV56  LED_PCH_SATA_HDD_N  GPP_E8_SATA_LED_N  @BASEBOARD_FAB2_LIB.BASEBOARD_FAB2(SCH_1):LED_PCH_SATA_HDD_N
  BM2  LED_GBE_P3_1   GPP_J7_LAN_LED_P3_1  @BASEBOARD_FAB2_LIB.BASEBOARD_FAB2(SCH_1):LED_GBE_P3_1
  CA13  LED_GBE_P3_0   GPP_J6_LAN_LED_P3_0  @BASEBOARD_FAB2_LIB.BASEBOARD_FAB2(SCH_1):LED_GBE_P3_0
  BU6  LED_GBE_P2_1   GPP_J5_LAN_LED_P2_1  @BASEBOARD_FAB2_LIB.BASEBOARD_FAB2(SCH_1):LED_GBE_P2_1
  BL3  LED_GBE_P2_0   GPP_J4_LAN_LED_P2_0  @BASEBOARD_FAB2_LIB.BASEBOARD_FAB2(SCH_1):LED_GBE_P2_0
  BK2  LED_GBE_P1_1   GPP_J3_LAN_LED_P1_1  @BASEBOARD_FAB2_LIB.BASEBOARD_FAB2(SCH_1):LED_GBE_P1_1
  BP4  LED_GBE_P1_0   GPP_J2_LAN_LED_P1_0  @BASEBOARD_FAB2_LIB.BASEBOARD_FAB2(SCH_1):LED_GBE_P1_0
  BK4  LED_GBE_P0_1   GPP_J1_LAN_LED_P0_1  @BASEBOARD_FAB2_LIB.BASEBOARD_FAB2(SCH_1):LED_GBE_P0_1
  BL1  LED_GBE_P0_0   GPP_J0_LAN_LED_P0_0  @BASEBOARD_FAB2_LIB.BASEBOARD_FAB2(SCH_1):LED_GBE_P0_0
  AH9  JTAG_PCH_PLD_TMS  GPP_F8_SATA_DEVSLP6  @BASEBOARD_FAB2_LIB.BASEBOARD_FAB2(SCH_1):JTAG_PCH_PLD_TMS
  AR20  JTAG_PCH_PLD_TDO  GPP_F9_SATA_DEVSLP7  @BASEBOARD_FAB2_LIB.BASEBOARD_FAB2(SCH_1):JTAG_PCH_PLD_TDO
  AK17  JTAG_PCH_PLD_TDI  GPP_F7_SATA_DEVSLP5  @BASEBOARD_FAB2_LIB.BASEBOARD_FAB2(SCH_1):JTAG_PCH_PLD_TDI
  AL18  JTAG_PCH_PLD_TCK  GPP_F6_SATA_DEVSLP4  @BASEBOARD_FAB2_LIB.BASEBOARD_FAB2(SCH_1):JTAG_PCH_PLD_TCK
  CA24  JTAG_PCH_GBE_TRST_N  GPP_I7_LAN_TRST_N  @BASEBOARD_FAB2_LIB.BASEBOARD_FAB2(SCH_1):JTAG_PCH_GBE_TRST_N
  CA22  JTAG_PCH_GBE_TMS  GPP_I2_LAN_TMS  @BASEBOARD_FAB2_LIB.BASEBOARD_FAB2(SCH_1):JTAG_PCH_GBE_TMS
  CA20  JTAG_PCH_GBE_TDO  GPP_I0_LAN_TDO  @BASEBOARD_FAB2_LIB.BASEBOARD_FAB2(SCH_1):JTAG_PCH_GBE_TDO
  BY23  JTAG_PCH_GBE_TDI  GPP_I3_LAN_TDI  @BASEBOARD_FAB2_LIB.BASEBOARD_FAB2(SCH_1):JTAG_PCH_GBE_TDI
  BV21  JTAG_PCH_GBE_CLK  GPP_I1_LAN_TCK  @BASEBOARD_FAB2_LIB.BASEBOARD_FAB2(SCH_1):JTAG_PCH_GBE_CLK
  AU58  IRQ_UV_DETECT_N  GPP_E12_USB2_OC3_N  @BASEBOARD_FAB2_LIB.BASEBOARD_FAB2(SCH_1):IRQ_UV_DETECT_N
  AW20  IRQ_PVCCIN_CPU1_VRHOT_LVC3_N  GPP_G5_FANTACH5_FANTACH5IE  @BASEBOARD_FAB2_LIB.BASEBOARD_FAB2(SCH_1):IRQ_PVCCIN_CPU1_VRHOT_LVC3_N
  BA9  IRQ_PVCCIN_CPU0_VRHOT_LVC3_N  GPP_G4_FANTACH4_FANTACH4IE  @BASEBOARD_FAB2_LIB.BASEBOARD_FAB2(SCH_1):IRQ_PVCCIN_CPU0_VRHOT_LVC3_N
  AR17  IRQ_PCH_NIC_ALERT_N  GPP_F21_LAN_SMBALRT_N  @BASEBOARD_FAB2_LIB.BASEBOARD_FAB2(SCH_1):IRQ_PCH_NIC_ALERT_N
  AG7  IRQ_OC_DETECT_N  GPP_F0_SATAXPCIE3_SATAGP3  @BASEBOARD_FAB2_LIB.BASEBOARD_FAB2(SCH_1):IRQ_OC_DETECT_N
  BA17  IRQ_FORCE_NM_THROTTLE_N  GPP_G20_SSATA_DEVSLP0  @BASEBOARD_FAB2_LIB.BASEBOARD_FAB2(SCH_1):IRQ_FORCE_NM_THROTTLE_N
  BW20  IRQ_DIMM_SAVE_LVT3_N  GPP_I4_DO_RESET_IN_N  @BASEBOARD_FAB2_LIB.BASEBOARD_FAB2(SCH_1):IRQ_DIMM_SAVE_LVT3_N
  BW24  IRQ_BOARD_BMC_ALERT_N  GPP_I5_DO_RESET_OUT_N  @BASEBOARD_FAB2_LIB.BASEBOARD_FAB2(SCH_1):IRQ_BOARD_BMC_ALERT_N
  AW54  IRQ_BMC_PCH_SMI_LPC_N  GPP_E11_USB2_OC2_N  @BASEBOARD_FAB2_LIB.BASEBOARD_FAB2(SCH_1):IRQ_BMC_PCH_SMI_LPC_N
  BN48  IRQ_BMC_PCH_SCI_LPC_N  GPP_E10_USB2_OC1_N  @BASEBOARD_FAB2_LIB.BASEBOARD_FAB2(SCH_1):IRQ_BMC_PCH_SCI_LPC_N
  BB52  IRQ_BMC_PCH_NMI_STBY_N  GPP_E6_SATA_DEVSLP2  @BASEBOARD_FAB2_LIB.BASEBOARD_FAB2(SCH_1):IRQ_BMC_PCH_NMI_STBY_N
  BD3  FP_PWR_ID_LED_N  GPP_H19_SSATAXPCIE1_SSATAGP1  @BASEBOARD_FAB2_LIB.BASEBOARD_FAB2(SCH_1):FP_PWR_ID_LED_N
  BA13  FM_UARTSW_MSB_N  GPP_G23_SSATAXPCIE0_SSATAGP0  @BASEBOARD_FAB2_LIB.BASEBOARD_FAB2(SCH_1):FM_UARTSW_MSB_N
  AT4  FM_UARTSW_LSB_N  GPP_H0_SRCCLKREQ6_N  @BASEBOARD_FAB2_LIB.BASEBOARD_FAB2(SCH_1):FM_UARTSW_LSB_N
  AY15  FM_THROTTLE_N  GPP_G7_FANTACH7_FANTACH7IE  @BASEBOARD_FAB2_LIB.BASEBOARD_FAB2(SCH_1):FM_THROTTLE_N
  BH4  FM_SSATA_PCIE_M2_SEL  GPP_H23_SSATAXPCIE5_SSATAGP5  @BASEBOARD_FAB2_LIB.BASEBOARD_FAB2(SCH_1):FM_SSATA_PCIE_M2_SEL
  BG7  FM_SOL_UART_CH_SEL  GPP_G21_SSATA_DEVSLP1  @BASEBOARD_FAB2_LIB.BASEBOARD_FAB2(SCH_1):FM_SOL_UART_CH_SEL
  BG52  FM_POST_CARD_PRES_BMC_N  GPP_E2_SATAXPCIE2_SATAGP2  @BASEBOARD_FAB2_LIB.BASEBOARD_FAB2(SCH_1):FM_POST_CARD_PRES_BMC_N
  BH2  FM_PCH_BMC_THERMTRIP_N  GPP_H22_SSATAXPCIE4_SSATAGP4  @BASEBOARD_FAB2_LIB.BASEBOARD_FAB2(SCH_1):FM_PCH_BMC_THERMTRIP_N
  BC4  FM_OC_DETECT_EN_N  GPP_H18_SML4ALERT_N_IE_N  @BASEBOARD_FAB2_LIB.BASEBOARD_FAB2(SCH_1):FM_OC_DETECT_EN_N
  BL48  FM_OC0_USB_N   GPP_E9_USB2_OC0_N  @BASEBOARD_FAB2_LIB.BASEBOARD_FAB2(SCH_1):FM_OC0_USB_N
  BE7  FM_NMI_EVENT_N  GPP_G18_NMI_N  @BASEBOARD_FAB2_LIB.BASEBOARD_FAB2(SCH_1):FM_NMI_EVENT_N
  AK13  FM_MP_PS_REDUNDANT_LOST_N  GPP_F3_SATAXPCIE6_SATAGP6  @BASEBOARD_FAB2_LIB.BASEBOARD_FAB2(SCH_1):FM_MP_PS_REDUNDANT_LOST_N
  AK20  FM_MP_PS_FAIL_N  GPP_F2_SATAXPCIE5_SATAGP5  @BASEBOARD_FAB2_LIB.BASEBOARD_FAB2(SCH_1):FM_MP_PS_FAIL_N
  AL15  FM_MEM_THERM_EVENT_PCH_N  GPP_F18_USB2_OC7_N  @BASEBOARD_FAB2_LIB.BASEBOARD_FAB2(SCH_1):FM_MEM_THERM_EVENT_PCH_N
  AU13  FM_IE_DISABLE_N  GPP_F16_USB2_OC5_N  @BASEBOARD_FAB2_LIB.BASEBOARD_FAB2(SCH_1):FM_IE_DISABLE_N
  AK9  FM_HSC_TIMER_EXP_N  GPP_F1_SATAXPCIE4_SATAGP4  @BASEBOARD_FAB2_LIB.BASEBOARD_FAB2(SCH_1):FM_HSC_TIMER_EXP_N
  BY12  FM_GBE3_LVC3_MOD_ABS  GPP_J22_LAN_SDP_P3_0  @BASEBOARD_FAB2_LIB.BASEBOARD_FAB2(SCH_1):FM_GBE3_LVC3_MOD_ABS
  BW13  FM_GBE2_LVC3_MOD_ABS  GPP_J20_LAN_SDP_P2_0  @BASEBOARD_FAB2_LIB.BASEBOARD_FAB2(SCH_1):FM_GBE2_LVC3_MOD_ABS
  BY10  FM_GBE1_LVC3_MOD_ABS  GPP_J18_LAN_SDP_P1_0  @BASEBOARD_FAB2_LIB.BASEBOARD_FAB2(SCH_1):FM_GBE1_LVC3_MOD_ABS
  BV10  FM_GBE0_LVC3_MOD_ABS  GPP_J16_LAN_SDP_P0_0  @BASEBOARD_FAB2_LIB.BASEBOARD_FAB2(SCH_1):FM_GBE0_LVC3_MOD_ABS
  AR13  FM_FORCE_ADR_N  GPP_F15_USB2_OC4_N  @BASEBOARD_FAB2_LIB.BASEBOARD_FAB2(SCH_1):FM_FORCE_ADR_N
  BB1  FM_FLASH_ATTACH_CFG_STRAP  GPP_H12_SML2ALERT_N_IE_N  @BASEBOARD_FAB2_LIB.BASEBOARD_FAB2(SCH_1):FM_FLASH_ATTACH_CFG_STRAP
  AT52  FM_CPU_MSMI_LVT3_N  GPP_E5_SATA_DEVSLP1  @BASEBOARD_FAB2_LIB.BASEBOARD_FAB2(SCH_1):FM_CPU_MSMI_LVT3_N
  AV52  FM_CPU_ERR2_LVT3_N  GPP_E4_SATA_DEVSLP0  @BASEBOARD_FAB2_LIB.BASEBOARD_FAB2(SCH_1):FM_CPU_ERR2_LVT3_N
  AV18  FM_CPU1_THERMTRIP_LATCH_LVT3_N  GPP_G6_FANTACH6_FANTACH6IE  @BASEBOARD_FAB2_LIB.BASEBOARD_FAB2(SCH_1):FM_CPU1_THERMTRIP_LATCH_LVT3_N
  BV23  FM_CPU1_RC_ERROR_N  GPP_I6_RESET_DONE  @BASEBOARD_FAB2_LIB.BASEBOARD_FAB2(SCH_1):FM_CPU1_RC_ERROR_N
  AY52  FM_CPU1_RC_ERROR_N  GPP_E1_SATAXPCIE1_SATAGP1  @BASEBOARD_FAB2_LIB.BASEBOARD_FAB2(SCH_1):FM_CPU1_RC_ERROR_N
  BA20  FM_CPU1_FIVR_FAULT_LVT3_N  GPP_G11_FANPWM3_FANPMW3IE  @BASEBOARD_FAB2_LIB.BASEBOARD_FAB2(SCH_1):FM_CPU1_FIVR_FAULT_LVT3_N
  BH50  FM_CPU0_RC_ERROR_N  GPP_E0_SATAXPCIE0_SATAGP0  @BASEBOARD_FAB2_LIB.BASEBOARD_FAB2(SCH_1):FM_CPU0_RC_ERROR_N
  BD20  FM_CPU0_RC_EN  GPP_G22_SSATA_DEVSLP2  @BASEBOARD_FAB2_LIB.BASEBOARD_FAB2(SCH_1):FM_CPU0_RC_EN
  BE11  FM_CPU0_FIVR_FAULT_LVT3_N  GPP_G10_FANPWM2_FANPWM2IE  @BASEBOARD_FAB2_LIB.BASEBOARD_FAB2(SCH_1):FM_CPU0_FIVR_FAULT_LVT3_N
  BE52  FM_CPLD_ADR_TRIGGER_R_N  GPP_E3_CPU_GP0  @BASEBOARD_FAB2_LIB.BASEBOARD_FAB2(SCH_1):FM_CPLD_ADR_TRIGGER_R_N
  BD17  FM_BOARD_SKU_ID4  GPP_G16  @BASEBOARD_FAB2_LIB.BASEBOARD_FAB2(SCH_1):FM_BOARD_SKU_ID4
  BE18  FM_BOARD_SKU_ID3  GPP_G15  @BASEBOARD_FAB2_LIB.BASEBOARD_FAB2(SCH_1):FM_BOARD_SKU_ID3
  AV7  FM_BOARD_SKU_ID2  GPP_G14  @BASEBOARD_FAB2_LIB.BASEBOARD_FAB2(SCH_1):FM_BOARD_SKU_ID2
  AY18  FM_BOARD_SKU_ID1  GPP_G13  @BASEBOARD_FAB2_LIB.BASEBOARD_FAB2(SCH_1):FM_BOARD_SKU_ID1
  BD13  FM_BOARD_SKU_ID0  GPP_G12  @BASEBOARD_FAB2_LIB.BASEBOARD_FAB2(SCH_1):FM_BOARD_SKU_ID0
  AH13  FM_BMC_READY_N  GPP_F4_SATAXPCIE7_SATAGP7  @BASEBOARD_FAB2_LIB.BASEBOARD_FAB2(SCH_1):FM_BMC_READY_N
  BF3  FM_BMC_NMI_N   GPP_H20_SSATAXPCIE2_SSATAGP2  @BASEBOARD_FAB2_LIB.BASEBOARD_FAB2(SCH_1):FM_BMC_NMI_N
  AH17  FM_BIOS_USB_RECOVERY  GPP_F5_SATA_DEVSLP3  @BASEBOARD_FAB2_LIB.BASEBOARD_FAB2(SCH_1):FM_BIOS_USB_RECOVERY
  AP15  FM_BIOS_TOP_SWAP  GPP_F17_USB2_OC6_N  @BASEBOARD_FAB2_LIB.BASEBOARD_FAB2(SCH_1):FM_BIOS_TOP_SWAP
  BA2  FM_BIOS_SMI_ACTIVE_N  GPP_H21_SSATAXPCIE3_SSATAGP3  @BASEBOARD_FAB2_LIB.BASEBOARD_FAB2(SCH_1):FM_BIOS_SMI_ACTIVE_N
  BE15  FM_BIOS_SMI_ACTIVE_N  GPP_G19_SMI_N  @BASEBOARD_FAB2_LIB.BASEBOARD_FAB2(SCH_1):FM_BIOS_SMI_ACTIVE_N
  BV25  FM_BIOS_MRC_DEBUG_MSG_DIS_N  GPP_I10  @BASEBOARD_FAB2_LIB.BASEBOARD_FAB2(SCH_1):FM_BIOS_MRC_DEBUG_MSG_DIS_N
  AW4  FM_BACKUP_BIOS_SEL_N  GPP_H1_SRCCLKREQ7_N  @BASEBOARD_FAB2_LIB.BASEBOARD_FAB2(SCH_1):FM_BACKUP_BIOS_SEL_N
  BJ48  FM_ADR_SMI_GPIO_N  GPP_E7_CPU_GP1  @BASEBOARD_FAB2_LIB.BASEBOARD_FAB2(SCH_1):FM_ADR_SMI_GPIO_N
  BD9  FM_ADR_COMPLETE_R1  GPP_G17_ADR_COMPLETE  @BASEBOARD_FAB2_LIB.BASEBOARD_FAB2(SCH_1):FM_ADR_COMPLETE_R1
  BY21  FM_10GBE_LOM_DISABLE_N  GPP_I9_LAN_DIS_N  @BASEBOARD_FAB2_LIB.BASEBOARD_FAB2(SCH_1):FM_10GBE_LOM_DISABLE_N
  AY7  FAN_TACH3      GPP_G3_FANTACH3_FANTACH3IE  @BASEBOARD_FAB2_LIB.BASEBOARD_FAB2(SCH_1):FAN_TACH3
  BE22  FAN_TACH2      GPP_G2_FANTACH2_FANTACH2IE  @BASEBOARD_FAB2_LIB.BASEBOARD_FAB2(SCH_1):FAN_TACH2
  AV15  FAN_TACH1      GPP_G1_FANTACH1_FANTACH1IE  @BASEBOARD_FAB2_LIB.BASEBOARD_FAB2(SCH_1):FAN_TACH1
  AY11  FAN_TACH0      GPP_G0_FANTACH0_FANTACH0IE  @BASEBOARD_FAB2_LIB.BASEBOARD_FAB2(SCH_1):FAN_TACH0
  AV11  FAN_PWM_OUT_SYS1  GPP_G9_FANPWM1_FAMPWM1IE  @BASEBOARD_FAB2_LIB.BASEBOARD_FAB2(SCH_1):FAN_PWM_OUT_SYS1
  BG11  FAN_PWM_OUT_SYS0  GPP_G8_FANPWM0_FANPWM0IE  @BASEBOARD_FAB2_LIB.BASEBOARD_FAB2(SCH_1):FAN_PWM_OUT_SYS0
  BY25  A_RCOMP_3P3    GPIO_RCOMP_3P3  @BASEBOARD_FAB2_LIB.BASEBOARD_FAB2(SCH_1):A_RCOMP_3P3

LBG_CORE_QAT_EXT_D  I115  U7C1   [LBG_CORE_QAT_EXT_D_BGA1-IC,H91A]
  BH9  VID_PCH_CORE_PVNN_AUX_VID_1  GPP_B1_CORE_VID1  @BASEBOARD_FAB2_LIB.BASEBOARD_FAB2(SCH_1):VID_PCH_CORE_PVNN_AUX_VID_1
  BL7  VID_PCH_CORE_PVNN_AUX_VID_0  GPP_B0_CORE_VID0  @BASEBOARD_FAB2_LIB.BASEBOARD_FAB2(SCH_1):VID_PCH_CORE_PVNN_AUX_VID_0
  BN40  TP_PCH_GPP_D12  GPP_D12_SSATA_SDATAOUT1  @BASEBOARD_FAB2_LIB.BASEBOARD_FAB2(SCH_1):TP_PCH_GPP_D12
  BR46  SP2_BMC_CM_UART_TX  GPP_D22_IE_UART_TX  @BASEBOARD_FAB2_LIB.BASEBOARD_FAB2(SCH_1):SP2_BMC_CM_UART_TX
  BV44  SP2_BMC_CM_UART_RX  GPP_D21_IE_UART_RX  @BASEBOARD_FAB2_LIB.BASEBOARD_FAB2(SCH_1):SP2_BMC_CM_UART_RX
  BW30  SMB_SMLINK0_STBY_LVC3_SDA_R1  GPP_C4_SML0DATA_IE  @BASEBOARD_FAB2_LIB.BASEBOARD_FAB2(SCH_1):SMB_SMLINK0_STBY_LVC3_SDA_R1
  BV29  SMB_SMLINK0_STBY_LVC3_SCL_R1  GPP_C3_SML0CLK_IE  @BASEBOARD_FAB2_LIB.BASEBOARD_FAB2(SCH_1):SMB_SMLINK0_STBY_LVC3_SCL_R1
  BL44  SMB_SLOTX24_STBY_LVC3_SDA_R1  GPP_D14_SML0BDATA_IE  @BASEBOARD_FAB2_LIB.BASEBOARD_FAB2(SCH_1):SMB_SLOTX24_STBY_LVC3_SDA_R1
  BY44  SMB_SLOTX24_STBY_LVC3_SCL_R1  GPP_D13_SML0BCLK_IE  @BASEBOARD_FAB2_LIB.BASEBOARD_FAB2(SCH_1):SMB_SLOTX24_STBY_LVC3_SCL_R1
  BV35  SMB_PMBUS_BMC_STBY_LVC3_SDA_R1  GPP_C7_SML1DATA_IE  @BASEBOARD_FAB2_LIB.BASEBOARD_FAB2(SCH_1):SMB_PMBUS_BMC_STBY_LVC3_SDA_R1
  CA28  SMB_PMBUS_BMC_STBY_LVC3_SCL_R1  GPP_C6_SML1CLK_IE  @BASEBOARD_FAB2_LIB.BASEBOARD_FAB2(SCH_1):SMB_PMBUS_BMC_STBY_LVC3_SCL_R1
  BV27  SMB_HOST_STBY_LVC3_SDA_R1  GPP_C1_SMBDATA  @BASEBOARD_FAB2_LIB.BASEBOARD_FAB2(SCH_1):SMB_HOST_STBY_LVC3_SDA_R1
  BW28  SMB_HOST_STBY_LVC3_SCL_R1  GPP_C0_SMBCLK  @BASEBOARD_FAB2_LIB.BASEBOARD_FAB2(SCH_1):SMB_HOST_STBY_LVC3_SCL_R1
  BW43  SGPIO_PCH_SSATA_DOUT0  GPP_D15_SSATA_SDATAOUT0  @BASEBOARD_FAB2_LIB.BASEBOARD_FAB2(SCH_1):SGPIO_PCH_SSATA_DOUT0
  BL11  RST_SYSTEM_BTN_N  GPP_B10_SRCCLKREQ5_N  @BASEBOARD_FAB2_LIB.BASEBOARD_FAB2(SCH_1):RST_SYSTEM_BTN_N
  BN18  RST_PLTRST_N   GPP_B13_PLTRST_N  @BASEBOARD_FAB2_LIB.BASEBOARD_FAB2(SCH_1):RST_PLTRST_N
  AD3  RST_PCH_SYSRST_BTN_OUT_N  GPP_A18  @BASEBOARD_FAB2_LIB.BASEBOARD_FAB2(SCH_1):RST_PCH_SYSRST_BTN_OUT_N
  BY27  PU_PCH_TLS_ENABLE_STRAP  GPP_C2_SMBALERT_N  @BASEBOARD_FAB2_LIB.BASEBOARD_FAB2(SCH_1):PU_PCH_TLS_ENABLE_STRAP
  AC2  PU_LPC_PME_N   GPP_A11_PME_N  @BASEBOARD_FAB2_LIB.BASEBOARD_FAB2(SCH_1):PU_LPC_PME_N
  AB1  PU_LPC_CLKRUN_N  GPP_A8_CLKRUN_N  @BASEBOARD_FAB2_LIB.BASEBOARD_FAB2(SCH_1):PU_LPC_CLKRUN_N
  BN15  PU_IRQ_VRALERT_N  GPP_B2  @BASEBOARD_FAB2_LIB.BASEBOARD_FAB2(SCH_1):PU_IRQ_VRALERT_N
   R1  PU_IRQ_PCH_SCI_WHEA_N  GPP_A12_BMBUSY_N_SXEXITHLDOFF_N  @BASEBOARD_FAB2_LIB.BASEBOARD_FAB2(SCH_1):PU_IRQ_PCH_SCI_WHEA_N
   N3  PU_FM_RCIN_N   GPP_A0_RCIN_N_ESPI_ALERT1_N  @BASEBOARD_FAB2_LIB.BASEBOARD_FAB2(SCH_1):PU_FM_RCIN_N
   P4  LPC_LFRAME_N_CS0_N  GPP_A5_LFRAME_N_ESPI_CS0_N  @BASEBOARD_FAB2_LIB.BASEBOARD_FAB2(SCH_1):LPC_LFRAME_N_CS0_N
   Y1  LPC_LAD3_IO3   GPP_A4_LAD3_ESPI_IO3  @BASEBOARD_FAB2_LIB.BASEBOARD_FAB2(SCH_1):LPC_LAD3_IO3
   W2  LPC_LAD2_IO2   GPP_A3_LAD2_ESPI_IO2  @BASEBOARD_FAB2_LIB.BASEBOARD_FAB2(SCH_1):LPC_LAD2_IO2
   N1  LPC_LAD1_IO1   GPP_A2_LAD1_ESPI_IO1  @BASEBOARD_FAB2_LIB.BASEBOARD_FAB2(SCH_1):LPC_LAD1_IO1
   Y3  LPC_LAD0_IO0   GPP_A1_LAD0_ESPI_IO0  @BASEBOARD_FAB2_LIB.BASEBOARD_FAB2(SCH_1):LPC_LAD0_IO0
  AA4  IRQ_VM_INT_N   GPP_A10_CLKOUT_LPC1  @BASEBOARD_FAB2_LIB.BASEBOARD_FAB2(SCH_1):IRQ_VM_INT_N
  BW34  IRQ_SML0_ALERT_N  GPP_C5_SML0ALERT_IE_N  @BASEBOARD_FAB2_LIB.BASEBOARD_FAB2(SCH_1):IRQ_SML0_ALERT_N
  BR13  IRQ_PVDDQ_KLM_VRHOT_LVT3_N  GPP_B7_SRCCLKREQ2_N  @BASEBOARD_FAB2_LIB.BASEBOARD_FAB2(SCH_1):IRQ_PVDDQ_KLM_VRHOT_LVT3_N
  BG18  IRQ_PVDDQ_GHJ_VRHOT_LVT3_N  GPP_B6_SRCCLKREQ1_N  @BASEBOARD_FAB2_LIB.BASEBOARD_FAB2(SCH_1):IRQ_PVDDQ_GHJ_VRHOT_LVT3_N
  BK17  IRQ_PVDDQ_DEF_VRHOT_LVT3_N  GPP_B5_SRCCLKREQ0_N  @BASEBOARD_FAB2_LIB.BASEBOARD_FAB2(SCH_1):IRQ_PVDDQ_DEF_VRHOT_LVT3_N
  BN7  IRQ_PVDDQ_ABC_VRHOT_LVT3_N  GPP_B4_CPU_GP3  @BASEBOARD_FAB2_LIB.BASEBOARD_FAB2(SCH_1):IRQ_PVDDQ_ABC_VRHOT_LVT3_N
  AA2  IRQ_PIRQA_SPI_TPM_N  GPP_A7_PIRQA_N_ESPI_ALERT0_N  @BASEBOARD_FAB2_LIB.BASEBOARD_FAB2(SCH_1):IRQ_PIRQA_SPI_TPM_N
  BG22  IRQ_PCH_NIC_ALERT_N  GPP_B16  @BASEBOARD_FAB2_LIB.BASEBOARD_FAB2(SCH_1):IRQ_PCH_NIC_ALERT_N
  BV42  IRQ_OOB_MGMT_RISER_ALERT_N  GPP_D16_SML0BALERT_IE_N  @BASEBOARD_FAB2_LIB.BASEBOARD_FAB2(SCH_1):IRQ_OOB_MGMT_RISER_ALERT_N
  BW45  IRQ_MEZZ_LAN_ALERT_N  GPP_D3  @BASEBOARD_FAB2_LIB.BASEBOARD_FAB2(SCH_1):IRQ_MEZZ_LAN_ALERT_N
   P2  IRQ_LPC_SERIRQ_N  GPP_A6_SERIRQ_ESPI_CS1_N  @BASEBOARD_FAB2_LIB.BASEBOARD_FAB2(SCH_1):IRQ_LPC_SERIRQ_N
  BY47  IRQ_LOM_ALERT_N  GPP_D11_SSATA_DEVSLP5  @BASEBOARD_FAB2_LIB.BASEBOARD_FAB2(SCH_1):IRQ_LOM_ALERT_N
  BJ44  IRQ_HSC_FAULT_N  GPP_D2  @BASEBOARD_FAB2_LIB.BASEBOARD_FAB2(SCH_1):IRQ_HSC_FAULT_N
  BY42  IRQ_FORCE_NM_THROTTLE_N  GPP_D9_SSATA_DEVSLP3  @BASEBOARD_FAB2_LIB.BASEBOARD_FAB2(SCH_1):IRQ_FORCE_NM_THROTTLE_N
  CA34  IRQ_BMC_PCH_SMI_LPC_N  GPP_C22  @BASEBOARD_FAB2_LIB.BASEBOARD_FAB2(SCH_1):IRQ_BMC_PCH_SMI_LPC_N
  BY38  IRQ_BMC_PCH_SCI_LPC_N  GPP_C14  @BASEBOARD_FAB2_LIB.BASEBOARD_FAB2(SCH_1):IRQ_BMC_PCH_SCI_LPC_N
  BR42  IRQ_BMC_PCH_NMI_STBY_R_N  GPP_D0  @BASEBOARD_FAB2_LIB.BASEBOARD_FAB2(SCH_1):IRQ_BMC_PCH_NMI_STBY_R_N
  BV47  H_CPU0_FAST_WAKE_LVT3_N  GPP_D10_SSATA_DEVSLP4  @BASEBOARD_FAB2_LIB.BASEBOARD_FAB2(SCH_1):H_CPU0_FAST_WAKE_LVT3_N
  BN11  FP_NMI_BTN_N   GPP_B8_SRCCLKREQ3_N  @BASEBOARD_FAB2_LIB.BASEBOARD_FAB2(SCH_1):FP_NMI_BTN_N
  CA41  FM_XRC_READY_N  GPP_D18  @BASEBOARD_FAB2_LIB.BASEBOARD_FAB2(SCH_1):FM_XRC_READY_N
  BW48  FM_XRC_PRESENT_N  GPP_D17  @BASEBOARD_FAB2_LIB.BASEBOARD_FAB2(SCH_1):FM_XRC_PRESENT_N
  BL15  FM_UV_ADR_TRIGGER_EN  GPP_B18  @BASEBOARD_FAB2_LIB.BASEBOARD_FAB2(SCH_1):FM_UV_ADR_TRIGGER_EN
  BR17  FM_USB_P0_EN_BOOT_BIOS_STRAP_N  GPP_B22  @BASEBOARD_FAB2_LIB.BASEBOARD_FAB2(SCH_1):FM_USB_P0_EN_BOOT_BIOS_STRAP_N
   T2  FM_UART_PRES_N  GPP_A16_CLKOUT_LPC2  @BASEBOARD_FAB2_LIB.BASEBOARD_FAB2(SCH_1):FM_UART_PRES_N
  BK13  FM_UART_ALERT_N  GPP_B15  @BASEBOARD_FAB2_LIB.BASEBOARD_FAB2(SCH_1):FM_UART_ALERT_N
  AE4  FM_TPM_PRES_N  GPP_A22  @BASEBOARD_FAB2_LIB.BASEBOARD_FAB2(SCH_1):FM_TPM_PRES_N
  CA39  FM_THROTTLE_N  GPP_C20  @BASEBOARD_FAB2_LIB.BASEBOARD_FAB2(SCH_1):FM_THROTTLE_N
  BY31  FM_SLT_CFG2_R  GPP_C17  @BASEBOARD_FAB2_LIB.BASEBOARD_FAB2(SCH_1):FM_SLT_CFG2_R
  BW37  FM_SLT_CFG1    GPP_C16  @BASEBOARD_FAB2_LIB.BASEBOARD_FAB2(SCH_1):FM_SLT_CFG1
  CA32  FM_SLT_CFG0    GPP_C15  @BASEBOARD_FAB2_LIB.BASEBOARD_FAB2(SCH_1):FM_SLT_CFG0
  BR9  FM_QAT_EN_N    GPP_B3_CPU_GP2  @BASEBOARD_FAB2_LIB.BASEBOARD_FAB2(SCH_1):FM_QAT_EN_N
  BK46  FM_PWR_LED_N   GPP_D1  @BASEBOARD_FAB2_LIB.BASEBOARD_FAB2(SCH_1):FM_PWR_LED_N
  BH20  FM_PWR_BTN_N   GPP_B9_SRCCLKREQ4_N  @BASEBOARD_FAB2_LIB.BASEBOARD_FAB2(SCH_1):FM_PWR_BTN_N
   W4  FM_POST_CARD_PRES_BMC_N  GPP_A20  @BASEBOARD_FAB2_LIB.BASEBOARD_FAB2(SCH_1):FM_POST_CARD_PRES_BMC_N
  BY35  FM_PMBUS_ALERT_BUF_EN_N  GPP_C18  @BASEBOARD_FAB2_LIB.BASEBOARD_FAB2(SCH_1):FM_PMBUS_ALERT_BUF_EN_N
  BK9  FM_PMBUS_ALERT_BUF_EN_N  GPP_B11  @BASEBOARD_FAB2_LIB.BASEBOARD_FAB2(SCH_1):FM_PMBUS_ALERT_BUF_EN_N
  BV31  FM_PCH_SATA_RAID_KEY  GPP_C10  @BASEBOARD_FAB2_LIB.BASEBOARD_FAB2(SCH_1):FM_PCH_SATA_RAID_KEY
  BG15  FM_PCH_PWRBTN_OUT_N  GPP_B17  @BASEBOARD_FAB2_LIB.BASEBOARD_FAB2(SCH_1):FM_PCH_PWRBTN_OUT_N
  BM42  FM_PCH_PLD_DATA_R  GPP_D4  @BASEBOARD_FAB2_LIB.BASEBOARD_FAB2(SCH_1):FM_PCH_PLD_DATA_R
  BM20  FM_PCH_BMC_THERMTRIP_EXI_STRAP_  GPP_B23_MEIE_SML1ALRT_N_PHOT_N  @BASEBOARD_FAB2_LIB.BASEBOARD_FAB2(SCH_1):FM_PCH_BMC_THERMTRIP_EXI_STRAP_N
  BW32  FM_PASSWORD_CLEAR_N  GPP_C8  @BASEBOARD_FAB2_LIB.BASEBOARD_FAB2(SCH_1):FM_PASSWORD_CLEAR_N
  AE2  FM_OCP_MEZZA_PRES_N  GPP_A21  @BASEBOARD_FAB2_LIB.BASEBOARD_FAB2(SCH_1):FM_OCP_MEZZA_PRES_N
   V3  FM_ME_RECOVER_N  GPP_A19  @BASEBOARD_FAB2_LIB.BASEBOARD_FAB2(SCH_1):FM_ME_RECOVER_N
  AC4  FM_MB_SLOT_ID2  GPP_A15_SUSACK_N  @BASEBOARD_FAB2_LIB.BASEBOARD_FAB2(SCH_1):FM_MB_SLOT_ID2
  AB3  FM_MB_SLOT_ID1  GPP_A14_ESPI_RESET_N  @BASEBOARD_FAB2_LIB.BASEBOARD_FAB2(SCH_1):FM_MB_SLOT_ID1
   T4  FM_MB_SLOT_ID0  GPP_A13_SUSWARN_N_SUSPWRDNACK  @BASEBOARD_FAB2_LIB.BASEBOARD_FAB2(SCH_1):FM_MB_SLOT_ID0
  BL18  FM_GLOBAL_RST_WARN_N  GPP_B12_GLB_RST_WARN_N  @BASEBOARD_FAB2_LIB.BASEBOARD_FAB2(SCH_1):FM_GLOBAL_RST_WARN_N
  BH17  FM_FAST_PROCHOT_EN_N  GPP_B21  @BASEBOARD_FAB2_LIB.BASEBOARD_FAB2(SCH_1):FM_FAST_PROCHOT_EN_N
  CA37  FM_CPU_CATERR_DLY_LVT3_R_N  GPP_C23  @BASEBOARD_FAB2_LIB.BASEBOARD_FAB2(SCH_1):FM_CPU_CATERR_DLY_LVT3_R_N
  AD1  FM_CPU_BMC_INIT  GPP_A17  @BASEBOARD_FAB2_LIB.BASEBOARD_FAB2(SCH_1):FM_CPU_BMC_INIT
  BY29  FM_CPU1_RC_EN  GPP_C9  @BASEBOARD_FAB2_LIB.BASEBOARD_FAB2(SCH_1):FM_CPU1_RC_EN
  BN44  FM_CPU0_THERMTRIP_LATCH_LVT3_N  GPP_D23  @BASEBOARD_FAB2_LIB.BASEBOARD_FAB2(SCH_1):FM_CPU0_THERMTRIP_LATCH_LVT3_N
  BW41  FM_CPLD_BMC_PWRDN_N  GPP_D6  @BASEBOARD_FAB2_LIB.BASEBOARD_FAB2(SCH_1):FM_CPLD_BMC_PWRDN_N
  BV33  FM_BOARD_REV_ID2  GPP_C11  @BASEBOARD_FAB2_LIB.BASEBOARD_FAB2(SCH_1):FM_BOARD_REV_ID2
  BV38  FM_BOARD_REV_ID1  GPP_C13  @BASEBOARD_FAB2_LIB.BASEBOARD_FAB2(SCH_1):FM_BOARD_REV_ID1
  CA30  FM_BOARD_REV_ID0  GPP_C12  @BASEBOARD_FAB2_LIB.BASEBOARD_FAB2(SCH_1):FM_BOARD_REV_ID0
   V1  FM_BMC_READY_N  GPP_A23  @BASEBOARD_FAB2_LIB.BASEBOARD_FAB2(SCH_1):FM_BMC_READY_N
  CA48  FM_BMC_HEARTBEAT_N  GPP_D20  @BASEBOARD_FAB2_LIB.BASEBOARD_FAB2(SCH_1):FM_BMC_HEARTBEAT_N
  BR38  FM_BMC_FAULT_LED_N  GPP_D8  @BASEBOARD_FAB2_LIB.BASEBOARD_FAB2(SCH_1):FM_BMC_FAULT_LED_N
  BM38  FM_BMC_ENABLE_N  GPP_D5  @BASEBOARD_FAB2_LIB.BASEBOARD_FAB2(SCH_1):FM_BMC_ENABLE_N
  CA45  FM_BMC_CPLD_GPO  GPP_D7  @BASEBOARD_FAB2_LIB.BASEBOARD_FAB2(SCH_1):FM_BMC_CPLD_GPO
  BH13  FM_BIOS_TOP_SWAP_SPKR  GPP_B14_SPKR  @BASEBOARD_FAB2_LIB.BASEBOARD_FAB2(SCH_1):FM_BIOS_TOP_SWAP_SPKR
  BK20  FM_BIOS_PREFRB2_GOOD  GPP_B19  @BASEBOARD_FAB2_LIB.BASEBOARD_FAB2(SCH_1):FM_BIOS_PREFRB2_GOOD
  BY33  FM_BIOS_POST_CMPLT_N  GPP_C21  @BASEBOARD_FAB2_LIB.BASEBOARD_FAB2(SCH_1):FM_BIOS_POST_CMPLT_N
  BJ22  FM_BIOS_POST_CMPLT_N  GPP_B20  @BASEBOARD_FAB2_LIB.BASEBOARD_FAB2(SCH_1):FM_BIOS_POST_CMPLT_N
  BW39  FM_BB_BMC_MP_GPIO  GPP_C19  @BASEBOARD_FAB2_LIB.BASEBOARD_FAB2(SCH_1):FM_BB_BMC_MP_GPIO
  CA43  FM_ADR_MODE_SEL_R  GPP_D19  @BASEBOARD_FAB2_LIB.BASEBOARD_FAB2(SCH_1):FM_ADR_MODE_SEL_R
   R3  CLK_24M_BMC_LPC_R  GPP_A9_CLKOUT_LPC0_ESPI_CLK  @BASEBOARD_FAB2_LIB.BASEBOARD_FAB2(SCH_1):CLK_24M_BMC_LPC_R

LBG_CORE_QAT_EXT_D  I73  U7C1   [LBG_CORE_QAT_EXT_D_BGA1-IC,H91A]
  BY16  XTAL_KR_25M_OUT  LAN_XTAL_OUT  @BASEBOARD_FAB2_LIB.BASEBOARD_FAB2(SCH_1):XTAL_KR_25M_OUT
  BV16  XTAL_KR_25M_IN  LAN_XTAL_IN  @BASEBOARD_FAB2_LIB.BASEBOARD_FAB2(SCH_1):XTAL_KR_25M_IN
  AT56  XDP_TRST_N     CPU_TRST_N  @BASEBOARD_FAB2_LIB.BASEBOARD_FAB2(SCH_1):XDP_TRST_N
  AH54  XDP_TMS        JTAG_TMS  @BASEBOARD_FAB2_LIB.BASEBOARD_FAB2(SCH_1):XDP_TMS
  AP56  XDP_TDO        JTAG_TDO  @BASEBOARD_FAB2_LIB.BASEBOARD_FAB2(SCH_1):XDP_TDO
  AN54  XDP_TDI        JTAG_TDI  @BASEBOARD_FAB2_LIB.BASEBOARD_FAB2(SCH_1):XDP_TDI
  U54  XDP_PREQ_N     PREQ_N  @BASEBOARD_FAB2_LIB.BASEBOARD_FAB2(SCH_1):XDP_PREQ_N
  AD54  XDP_PRDY_N     PRDY_N  @BASEBOARD_FAB2_LIB.BASEBOARD_FAB2(SCH_1):XDP_PRDY_N
  AL56  XDP_PCH_TCK1   JTAG_TCK  @BASEBOARD_FAB2_LIB.BASEBOARD_FAB2(SCH_1):XDP_PCH_TCK1
  G15  XDP_PCH_PWR_DEBUG_N   GPD0  @BASEBOARD_FAB2_LIB.BASEBOARD_FAB2(SCH_1):XDP_PCH_PWR_DEBUG_N
  AF54  XDP_PCH_CPU_TCK0  JTAGX  @BASEBOARD_FAB2_LIB.BASEBOARD_FAB2(SCH_1):XDP_PCH_CPU_TCK0
  AR54  XDP_ITP_PMODE  ITP_PMODE  @BASEBOARD_FAB2_LIB.BASEBOARD_FAB2(SCH_1):XDP_ITP_PMODE
  M15  TP_SLP_LAN_N   SLP_GBE_N  @BASEBOARD_FAB2_LIB.BASEBOARD_FAB2(SCH_1):TP_SLP_LAN_N
   V7  TP_PM_SYNC_GTL  PM_SYNC2  @BASEBOARD_FAB2_LIB.BASEBOARD_FAB2(SCH_1):TP_PM_SYNC_GTL
  U17  TP_PLTRST_CPU_N  PLTRST_CPU_N  @BASEBOARD_FAB2_LIB.BASEBOARD_FAB2(SCH_1):TP_PLTRST_CPU_N
  R24  TP_PCH_RSVD54  RSVD<54>  @BASEBOARD_FAB2_LIB.BASEBOARD_FAB2(SCH_1):TP_PCH_RSVD54
  P26  TP_PCH_RSVD53  RSVD<53>  @BASEBOARD_FAB2_LIB.BASEBOARD_FAB2(SCH_1):TP_PCH_RSVD53
  P22  TP_PCH_RSVD45  RSVD<45>  @BASEBOARD_FAB2_LIB.BASEBOARD_FAB2(SCH_1):TP_PCH_RSVD45
  BG40  TP_PCH_RSVD42  RSVD<42>  @BASEBOARD_FAB2_LIB.BASEBOARD_FAB2(SCH_1):TP_PCH_RSVD42
  BJ40  TP_PCH_RSVD41  RSVD<41>  @BASEBOARD_FAB2_LIB.BASEBOARD_FAB2(SCH_1):TP_PCH_RSVD41
  BL29  TP_PCH_RSVD38  RSVD<38>  @BASEBOARD_FAB2_LIB.BASEBOARD_FAB2(SCH_1):TP_PCH_RSVD38
  BN29  TP_PCH_RSVD37  RSVD<37>  @BASEBOARD_FAB2_LIB.BASEBOARD_FAB2(SCH_1):TP_PCH_RSVD37
  AK54  TP_PCH_RSVD36  RSVD<36>  @BASEBOARD_FAB2_LIB.BASEBOARD_FAB2(SCH_1):TP_PCH_RSVD36
  W54  TP_PCH_RSVD35  RSVD<35>  @BASEBOARD_FAB2_LIB.BASEBOARD_FAB2(SCH_1):TP_PCH_RSVD35
  Y56  TP_PCH_RSVD34  RSVD<34>  @BASEBOARD_FAB2_LIB.BASEBOARD_FAB2(SCH_1):TP_PCH_RSVD34
  V56  TP_PCH_RSVD33  RSVD<33>  @BASEBOARD_FAB2_LIB.BASEBOARD_FAB2(SCH_1):TP_PCH_RSVD33
  AA54  TP_PCH_RSVD32  RSVD<32>  @BASEBOARD_FAB2_LIB.BASEBOARD_FAB2(SCH_1):TP_PCH_RSVD32
  R13  TP_CPU_PCH_TRIGGER_OUT  TRIGGER_OUT  @BASEBOARD_FAB2_LIB.BASEBOARD_FAB2(SCH_1):TP_CPU_PCH_TRIGGER_OUT
   M7  TP_CPU_PCH_TRIGGER_IN  TRIGGER_IN  @BASEBOARD_FAB2_LIB.BASEBOARD_FAB2(SCH_1):TP_CPU_PCH_TRIGGER_IN
  BN33  TP_10GBE_KR1_MON_DP  RSVD<44>  @BASEBOARD_FAB2_LIB.BASEBOARD_FAB2(SCH_1):TP_10GBE_KR1_MON_DP
  BL33  TP_10GBE_KR1_MON_DN  RSVD<43>  @BASEBOARD_FAB2_LIB.BASEBOARD_FAB2(SCH_1):TP_10GBE_KR1_MON_DN
  BN26  TP_10GBE_KR0_MON_DP  RSVD<40>  @BASEBOARD_FAB2_LIB.BASEBOARD_FAB2(SCH_1):TP_10GBE_KR0_MON_DP
  BL26  TP_10GBE_KR0_MON_DN  RSVD<39>  @BASEBOARD_FAB2_LIB.BASEBOARD_FAB2(SCH_1):TP_10GBE_KR0_MON_DN
  P15  RST_RSMRST_N   RSMRST_N  @BASEBOARD_FAB2_LIB.BASEBOARD_FAB2(SCH_1):RST_RSMRST_N
  BV19  RST_BMC_SYSRST_BTN_OUT_B_N  SYS_RESET_N  @BASEBOARD_FAB2_LIB.BASEBOARD_FAB2(SCH_1):RST_BMC_SYSRST_BTN_OUT_B_N
  M11  RST_BMC_SRST_R_N  GPD2_GBE_WAKE_N  @BASEBOARD_FAB2_LIB.BASEBOARD_FAB2(SCH_1):RST_BMC_SRST_R_N
  BY19  PWRGD_SYS_PWROK  SYS_PWROK  @BASEBOARD_FAB2_LIB.BASEBOARD_FAB2(SCH_1):PWRGD_SYS_PWROK
  R17  PWRGD_PCH_PWROK  PCH_PWROK  @BASEBOARD_FAB2_LIB.BASEBOARD_FAB2(SCH_1):PWRGD_PCH_PWROK
  K13  PWRGD_DSW_PWROK  DSW_PWROK  @BASEBOARD_FAB2_LIB.BASEBOARD_FAB2(SCH_1):PWRGD_DSW_PWROK
   R9  PWRGD_CPUPWRGD_GTL  PROC_PWRGD  @BASEBOARD_FAB2_LIB.BASEBOARD_FAB2(SCH_1):PWRGD_CPUPWRGD_GTL
   U9  PECI_PCH        PECI  @BASEBOARD_FAB2_LIB.BASEBOARD_FAB2(SCH_1):PECI_PCH
  BM31  KR_P3_OCP_TX_DP  LAN_TX_P3P  @BASEBOARD_FAB2_LIB.BASEBOARD_FAB2(SCH_1):KR_P3_OCP_TX_DP
  BR31  KR_P3_OCP_TX_DN  LAN_TX_P3N  @BASEBOARD_FAB2_LIB.BASEBOARD_FAB2(SCH_1):KR_P3_OCP_TX_DN
  BH35  KR_P3_OCP_RX_C_DP  LAN_RX_P3P  @BASEBOARD_FAB2_LIB.BASEBOARD_FAB2(SCH_1):KR_P3_OCP_RX_C_DP
  BF35  KR_P3_OCP_RX_C_DN  LAN_RX_P3N  @BASEBOARD_FAB2_LIB.BASEBOARD_FAB2(SCH_1):KR_P3_OCP_RX_C_DN
  BR35  KR_P2_OCP_TX_DP  LAN_TX_P2P  @BASEBOARD_FAB2_LIB.BASEBOARD_FAB2(SCH_1):KR_P2_OCP_TX_DP
  BM35  KR_P2_OCP_TX_DN  LAN_TX_P2N  @BASEBOARD_FAB2_LIB.BASEBOARD_FAB2(SCH_1):KR_P2_OCP_TX_DN
  BG37  KR_P2_OCP_RX_C_DP  LAN_RX_P2P  @BASEBOARD_FAB2_LIB.BASEBOARD_FAB2(SCH_1):KR_P2_OCP_RX_C_DP
  BJ37  KR_P2_OCP_RX_C_DN  LAN_RX_P2N  @BASEBOARD_FAB2_LIB.BASEBOARD_FAB2(SCH_1):KR_P2_OCP_RX_C_DN
  BR24  KR_P1_OCP_TX_DP  LAN_TX_P1P  @BASEBOARD_FAB2_LIB.BASEBOARD_FAB2(SCH_1):KR_P1_OCP_TX_DP
  BM24  KR_P1_OCP_TX_DN  LAN_TX_P1N  @BASEBOARD_FAB2_LIB.BASEBOARD_FAB2(SCH_1):KR_P1_OCP_TX_DN
  BJ29  KR_P1_OCP_RX_C_DP  LAN_RX_P1P  @BASEBOARD_FAB2_LIB.BASEBOARD_FAB2(SCH_1):KR_P1_OCP_RX_C_DP
  BG29  KR_P1_OCP_RX_C_DN  LAN_RX_P1N  @BASEBOARD_FAB2_LIB.BASEBOARD_FAB2(SCH_1):KR_P1_OCP_RX_C_DN
  BR27  KR_P0_OCP_TX_DP  LAN_TX_P0P  @BASEBOARD_FAB2_LIB.BASEBOARD_FAB2(SCH_1):KR_P0_OCP_TX_DP
  BM27  KR_P0_OCP_TX_DN  LAN_TX_P0N  @BASEBOARD_FAB2_LIB.BASEBOARD_FAB2(SCH_1):KR_P0_OCP_TX_DN
  BF31  KR_P0_OCP_RX_C_DP  LAN_RX_P0P  @BASEBOARD_FAB2_LIB.BASEBOARD_FAB2(SCH_1):KR_P0_OCP_RX_C_DP
  BH31  KR_P0_OCP_RX_C_DN  LAN_RX_P0N  @BASEBOARD_FAB2_LIB.BASEBOARD_FAB2(SCH_1):KR_P0_OCP_RX_C_DN
  C13  IRQ_SML1_PMBUS_ALERT_N  GPD8_SUSCLK  @BASEBOARD_FAB2_LIB.BASEBOARD_FAB2(SCH_1):IRQ_SML1_PMBUS_ALERT_N
   K9  IRQ_LVC3_WAKE_N  WAKE_N  @BASEBOARD_FAB2_LIB.BASEBOARD_FAB2(SCH_1):IRQ_LVC3_WAKE_N
  U13  H_PM_SYNC1_GTL_R  PM_SYNC  @BASEBOARD_FAB2_LIB.BASEBOARD_FAB2(SCH_1):H_PM_SYNC1_GTL_R
   P7  FM_SLP_SUS_N   SLP_SUS_N  @BASEBOARD_FAB2_LIB.BASEBOARD_FAB2(SCH_1):FM_SLP_SUS_N
  B16  FM_SLPS4_N     GPD5_SLP_S4_N  @BASEBOARD_FAB2_LIB.BASEBOARD_FAB2(SCH_1):FM_SLPS4_N
  D14  FM_SLPS3_N     GPD4_SLP_S3_N  @BASEBOARD_FAB2_LIB.BASEBOARD_FAB2(SCH_1):FM_SLPS3_N
  C15  FM_PCH_PWRBTN_N  GPD3_PWRBTN_N  @BASEBOARD_FAB2_LIB.BASEBOARD_FAB2(SCH_1):FM_PCH_PWRBTN_N
  V15  FM_PCH_LVC1_THERMTRIP_N  THRMTRIP_N  @BASEBOARD_FAB2_LIB.BASEBOARD_FAB2(SCH_1):FM_PCH_LVC1_THERMTRIP_N
  A13  FM_GBE_LOM_DISABLE_N  GPD11_GBEPHY  @BASEBOARD_FAB2_LIB.BASEBOARD_FAB2(SCH_1):FM_GBE_LOM_DISABLE_N
  H13  FM_CPU1_SKTOCC_LVT3_N  GPD1_ACPRESENT  @BASEBOARD_FAB2_LIB.BASEBOARD_FAB2(SCH_1):FM_CPU1_SKTOCC_LVT3_N
  G11  FM_CPU0_SKTOCC_LVT3_N  GPD6_SLP_A_N  @BASEBOARD_FAB2_LIB.BASEBOARD_FAB2(SCH_1):FM_CPU0_SKTOCC_LVT3_N
  B14  FM_CPU0_RC_ERROR_N  GPD10_SLP_S5_N  @BASEBOARD_FAB2_LIB.BASEBOARD_FAB2(SCH_1):FM_CPU0_RC_ERROR_N
  A15  FM_BMC_CPLD_MP_RST_N   GPD9  @BASEBOARD_FAB2_LIB.BASEBOARD_FAB2(SCH_1):FM_BMC_CPLD_MP_RST_N
   H9  FM_BATTERY_SENSE_EN_N   GPD7  @BASEBOARD_FAB2_LIB.BASEBOARD_FAB2(SCH_1):FM_BATTERY_SENSE_EN_N
  BD42  A_KR1_RBIAS    LAN_RBIAS_1  @BASEBOARD_FAB2_LIB.BASEBOARD_FAB2(SCH_1):A_KR1_RBIAS
  BB29  A_KR0_RBIAS    LAN_RBIAS_0  @BASEBOARD_FAB2_LIB.BASEBOARD_FAB2(SCH_1):A_KR0_RBIAS

LBG_CORE_QAT_EXT_D  I9   U7C1   [LBG_CORE_QAT_EXT_D_BGA1-IC,H91A]
  B55  P3E_CPU0_PE1_PCH_TXP<7>  PCIEUP_7_RXP  @BASEBOARD_FAB2_LIB.BASEBOARD_FAB2(SCH_1):P3E_CPU0_PE1_PCH_TXP<7>
  A54  P3E_CPU0_PE1_PCH_TXP<6>  PCIEUP_6_RXP  @BASEBOARD_FAB2_LIB.BASEBOARD_FAB2(SCH_1):P3E_CPU0_PE1_PCH_TXP<6>
  B53  P3E_CPU0_PE1_PCH_TXP<5>  PCIEUP_5_RXP  @BASEBOARD_FAB2_LIB.BASEBOARD_FAB2(SCH_1):P3E_CPU0_PE1_PCH_TXP<5>
  A52  P3E_CPU0_PE1_PCH_TXP<4>  PCIEUP_4_RXP  @BASEBOARD_FAB2_LIB.BASEBOARD_FAB2(SCH_1):P3E_CPU0_PE1_PCH_TXP<4>
  B51  P3E_CPU0_PE1_PCH_TXP<3>  PCIEUP_3_RXP  @BASEBOARD_FAB2_LIB.BASEBOARD_FAB2(SCH_1):P3E_CPU0_PE1_PCH_TXP<3>
  A50  P3E_CPU0_PE1_PCH_TXP<2>  PCIEUP_2_RXP  @BASEBOARD_FAB2_LIB.BASEBOARD_FAB2(SCH_1):P3E_CPU0_PE1_PCH_TXP<2>
  B49  P3E_CPU0_PE1_PCH_TXP<1>  PCIEUP_1_RXP  @BASEBOARD_FAB2_LIB.BASEBOARD_FAB2(SCH_1):P3E_CPU0_PE1_PCH_TXP<1>
  A48  P3E_CPU0_PE1_PCH_TXP<0>  PCIEUP_0_RXP  @BASEBOARD_FAB2_LIB.BASEBOARD_FAB2(SCH_1):P3E_CPU0_PE1_PCH_TXP<0>
  D55  P3E_CPU0_PE1_PCH_TXN<7>  PCIEUP_7_RXN  @BASEBOARD_FAB2_LIB.BASEBOARD_FAB2(SCH_1):P3E_CPU0_PE1_PCH_TXN<7>
  C54  P3E_CPU0_PE1_PCH_TXN<6>  PCIEUP_6_RXN  @BASEBOARD_FAB2_LIB.BASEBOARD_FAB2(SCH_1):P3E_CPU0_PE1_PCH_TXN<6>
  D53  P3E_CPU0_PE1_PCH_TXN<5>  PCIEUP_5_RXN  @BASEBOARD_FAB2_LIB.BASEBOARD_FAB2(SCH_1):P3E_CPU0_PE1_PCH_TXN<5>
  C52  P3E_CPU0_PE1_PCH_TXN<4>  PCIEUP_4_RXN  @BASEBOARD_FAB2_LIB.BASEBOARD_FAB2(SCH_1):P3E_CPU0_PE1_PCH_TXN<4>
  D51  P3E_CPU0_PE1_PCH_TXN<3>  PCIEUP_3_RXN  @BASEBOARD_FAB2_LIB.BASEBOARD_FAB2(SCH_1):P3E_CPU0_PE1_PCH_TXN<3>
  C50  P3E_CPU0_PE1_PCH_TXN<2>  PCIEUP_2_RXN  @BASEBOARD_FAB2_LIB.BASEBOARD_FAB2(SCH_1):P3E_CPU0_PE1_PCH_TXN<2>
  D49  P3E_CPU0_PE1_PCH_TXN<1>  PCIEUP_1_RXN  @BASEBOARD_FAB2_LIB.BASEBOARD_FAB2(SCH_1):P3E_CPU0_PE1_PCH_TXN<1>
  C48  P3E_CPU0_PE1_PCH_TXN<0>  PCIEUP_0_RXN  @BASEBOARD_FAB2_LIB.BASEBOARD_FAB2(SCH_1):P3E_CPU0_PE1_PCH_TXN<0>
  M66  P3E_CPU0_PE1_PCH_R_RXP<9>  PCIEUP_9_TXP  @BASEBOARD_FAB2_LIB.BASEBOARD_FAB2(SCH_1):P3E_CPU0_PE1_PCH_R_RXP<9>
  M63  P3E_CPU0_PE1_PCH_R_RXP<8>  PCIEUP_8_TXP  @BASEBOARD_FAB2_LIB.BASEBOARD_FAB2(SCH_1):P3E_CPU0_PE1_PCH_R_RXP<8>
  AA65  P3E_CPU0_PE1_PCH_R_RXP<15>  PCIEUP_15_TXP  @BASEBOARD_FAB2_LIB.BASEBOARD_FAB2(SCH_1):P3E_CPU0_PE1_PCH_R_RXP<15>
  V63  P3E_CPU0_PE1_PCH_R_RXP<14>  PCIEUP_14_TXP  @BASEBOARD_FAB2_LIB.BASEBOARD_FAB2(SCH_1):P3E_CPU0_PE1_PCH_R_RXP<14>
  U61  P3E_CPU0_PE1_PCH_R_RXP<13>  PCIEUP_13_TXP  @BASEBOARD_FAB2_LIB.BASEBOARD_FAB2(SCH_1):P3E_CPU0_PE1_PCH_R_RXP<13>
  U65  P3E_CPU0_PE1_PCH_R_RXP<12>  PCIEUP_12_TXP  @BASEBOARD_FAB2_LIB.BASEBOARD_FAB2(SCH_1):P3E_CPU0_PE1_PCH_R_RXP<12>
  V59  P3E_CPU0_PE1_PCH_R_RXP<11>  PCIEUP_11_TXP  @BASEBOARD_FAB2_LIB.BASEBOARD_FAB2(SCH_1):P3E_CPU0_PE1_PCH_R_RXP<11>
  P66  P3E_CPU0_PE1_PCH_R_RXP<10>  PCIEUP_10_TXP  @BASEBOARD_FAB2_LIB.BASEBOARD_FAB2(SCH_1):P3E_CPU0_PE1_PCH_R_RXP<10>
  J66  P3E_CPU0_PE1_PCH_R_RXN<9>  PCIEUP_9_TXN  @BASEBOARD_FAB2_LIB.BASEBOARD_FAB2(SCH_1):P3E_CPU0_PE1_PCH_R_RXN<9>
  K65  P3E_CPU0_PE1_PCH_R_RXN<8>  PCIEUP_8_TXN  @BASEBOARD_FAB2_LIB.BASEBOARD_FAB2(SCH_1):P3E_CPU0_PE1_PCH_R_RXN<8>
  Y66  P3E_CPU0_PE1_PCH_R_RXN<15>  PCIEUP_15_TXN  @BASEBOARD_FAB2_LIB.BASEBOARD_FAB2(SCH_1):P3E_CPU0_PE1_PCH_R_RXN<15>
  W65  P3E_CPU0_PE1_PCH_R_RXN<14>  PCIEUP_14_TXN  @BASEBOARD_FAB2_LIB.BASEBOARD_FAB2(SCH_1):P3E_CPU0_PE1_PCH_R_RXN<14>
  T63  P3E_CPU0_PE1_PCH_R_RXN<13>  PCIEUP_13_TXN  @BASEBOARD_FAB2_LIB.BASEBOARD_FAB2(SCH_1):P3E_CPU0_PE1_PCH_R_RXN<13>
  R65  P3E_CPU0_PE1_PCH_R_RXN<12>  PCIEUP_12_TXN  @BASEBOARD_FAB2_LIB.BASEBOARD_FAB2(SCH_1):P3E_CPU0_PE1_PCH_R_RXN<12>
  T59  P3E_CPU0_PE1_PCH_R_RXN<11>  PCIEUP_11_TXN  @BASEBOARD_FAB2_LIB.BASEBOARD_FAB2(SCH_1):P3E_CPU0_PE1_PCH_R_RXN<11>
  N65  P3E_CPU0_PE1_PCH_R_RXN<10>  PCIEUP_10_TXN  @BASEBOARD_FAB2_LIB.BASEBOARD_FAB2(SCH_1):P3E_CPU0_PE1_PCH_R_RXN<10>
  R61  P3E_CPU0_PE1_PCH_RXP<7>  PCIEUP_7_TXP  @BASEBOARD_FAB2_LIB.BASEBOARD_FAB2(SCH_1):P3E_CPU0_PE1_PCH_RXP<7>
  J63  P3E_CPU0_PE1_PCH_RXP<6>  PCIEUP_6_TXP  @BASEBOARD_FAB2_LIB.BASEBOARD_FAB2(SCH_1):P3E_CPU0_PE1_PCH_RXP<6>
  K61  P3E_CPU0_PE1_PCH_RXP<5>  PCIEUP_5_TXP  @BASEBOARD_FAB2_LIB.BASEBOARD_FAB2(SCH_1):P3E_CPU0_PE1_PCH_RXP<5>
  M59  P3E_CPU0_PE1_PCH_RXP<4>  PCIEUP_4_TXP  @BASEBOARD_FAB2_LIB.BASEBOARD_FAB2(SCH_1):P3E_CPU0_PE1_PCH_RXP<4>
  K58  P3E_CPU0_PE1_PCH_RXP<3>  PCIEUP_3_TXP  @BASEBOARD_FAB2_LIB.BASEBOARD_FAB2(SCH_1):P3E_CPU0_PE1_PCH_RXP<3>
  G56  P3E_CPU0_PE1_PCH_RXP<2>  PCIEUP_2_TXP  @BASEBOARD_FAB2_LIB.BASEBOARD_FAB2(SCH_1):P3E_CPU0_PE1_PCH_RXP<2>
  M56  P3E_CPU0_PE1_PCH_RXP<1>  PCIEUP_1_TXP  @BASEBOARD_FAB2_LIB.BASEBOARD_FAB2(SCH_1):P3E_CPU0_PE1_PCH_RXP<1>
  G52  P3E_CPU0_PE1_PCH_RXP<0>  PCIEUP_0_TXP  @BASEBOARD_FAB2_LIB.BASEBOARD_FAB2(SCH_1):P3E_CPU0_PE1_PCH_RXP<0>
  P59  P3E_CPU0_PE1_PCH_RXN<7>  PCIEUP_7_TXN  @BASEBOARD_FAB2_LIB.BASEBOARD_FAB2(SCH_1):P3E_CPU0_PE1_PCH_RXN<7>
  H61  P3E_CPU0_PE1_PCH_RXN<6>  PCIEUP_6_TXN  @BASEBOARD_FAB2_LIB.BASEBOARD_FAB2(SCH_1):P3E_CPU0_PE1_PCH_RXN<6>
  N61  P3E_CPU0_PE1_PCH_RXN<5>  PCIEUP_5_TXN  @BASEBOARD_FAB2_LIB.BASEBOARD_FAB2(SCH_1):P3E_CPU0_PE1_PCH_RXN<5>
  N58  P3E_CPU0_PE1_PCH_RXN<4>  PCIEUP_4_TXN  @BASEBOARD_FAB2_LIB.BASEBOARD_FAB2(SCH_1):P3E_CPU0_PE1_PCH_RXN<4>
  J56  P3E_CPU0_PE1_PCH_RXN<3>  PCIEUP_3_TXN  @BASEBOARD_FAB2_LIB.BASEBOARD_FAB2(SCH_1):P3E_CPU0_PE1_PCH_RXN<3>
  H54  P3E_CPU0_PE1_PCH_RXN<2>  PCIEUP_2_TXN  @BASEBOARD_FAB2_LIB.BASEBOARD_FAB2(SCH_1):P3E_CPU0_PE1_PCH_RXN<2>
  P56  P3E_CPU0_PE1_PCH_RXN<1>  PCIEUP_1_TXN  @BASEBOARD_FAB2_LIB.BASEBOARD_FAB2(SCH_1):P3E_CPU0_PE1_PCH_RXN<1>
  J52  P3E_CPU0_PE1_PCH_RXN<0>  PCIEUP_0_TXN  @BASEBOARD_FAB2_LIB.BASEBOARD_FAB2(SCH_1):P3E_CPU0_PE1_PCH_RXN<0>
  D58  P3E_CPU0_PE1_PCH_C_TXP<9>  PCIEUP_9_RXN  @BASEBOARD_FAB2_LIB.BASEBOARD_FAB2(SCH_1):P3E_CPU0_PE1_PCH_C_TXP<9>
  C57  P3E_CPU0_PE1_PCH_C_TXP<8>  PCIEUP_8_RXN  @BASEBOARD_FAB2_LIB.BASEBOARD_FAB2(SCH_1):P3E_CPU0_PE1_PCH_C_TXP<8>
  D64  P3E_CPU0_PE1_PCH_C_TXP<15>  PCIEUP_15_RXN  @BASEBOARD_FAB2_LIB.BASEBOARD_FAB2(SCH_1):P3E_CPU0_PE1_PCH_C_TXP<15>
  C63  P3E_CPU0_PE1_PCH_C_TXP<14>  PCIEUP_14_RXN  @BASEBOARD_FAB2_LIB.BASEBOARD_FAB2(SCH_1):P3E_CPU0_PE1_PCH_C_TXP<14>
  D62  P3E_CPU0_PE1_PCH_C_TXP<13>  PCIEUP_13_RXN  @BASEBOARD_FAB2_LIB.BASEBOARD_FAB2(SCH_1):P3E_CPU0_PE1_PCH_C_TXP<13>
  C61  P3E_CPU0_PE1_PCH_C_TXP<12>  PCIEUP_12_RXN  @BASEBOARD_FAB2_LIB.BASEBOARD_FAB2(SCH_1):P3E_CPU0_PE1_PCH_C_TXP<12>
  B60  P3E_CPU0_PE1_PCH_C_TXP<11>  PCIEUP_11_RXP  @BASEBOARD_FAB2_LIB.BASEBOARD_FAB2(SCH_1):P3E_CPU0_PE1_PCH_C_TXP<11>
  C59  P3E_CPU0_PE1_PCH_C_TXP<10>  PCIEUP_10_RXN  @BASEBOARD_FAB2_LIB.BASEBOARD_FAB2(SCH_1):P3E_CPU0_PE1_PCH_C_TXP<10>
  B58  P3E_CPU0_PE1_PCH_C_TXN<9>  PCIEUP_9_RXP  @BASEBOARD_FAB2_LIB.BASEBOARD_FAB2(SCH_1):P3E_CPU0_PE1_PCH_C_TXN<9>
  A57  P3E_CPU0_PE1_PCH_C_TXN<8>  PCIEUP_8_RXP  @BASEBOARD_FAB2_LIB.BASEBOARD_FAB2(SCH_1):P3E_CPU0_PE1_PCH_C_TXN<8>
  B64  P3E_CPU0_PE1_PCH_C_TXN<15>  PCIEUP_15_RXP  @BASEBOARD_FAB2_LIB.BASEBOARD_FAB2(SCH_1):P3E_CPU0_PE1_PCH_C_TXN<15>
  A63  P3E_CPU0_PE1_PCH_C_TXN<14>  PCIEUP_14_RXP  @BASEBOARD_FAB2_LIB.BASEBOARD_FAB2(SCH_1):P3E_CPU0_PE1_PCH_C_TXN<14>
  B62  P3E_CPU0_PE1_PCH_C_TXN<13>  PCIEUP_13_RXP  @BASEBOARD_FAB2_LIB.BASEBOARD_FAB2(SCH_1):P3E_CPU0_PE1_PCH_C_TXN<13>
  A61  P3E_CPU0_PE1_PCH_C_TXN<12>  PCIEUP_12_RXP  @BASEBOARD_FAB2_LIB.BASEBOARD_FAB2(SCH_1):P3E_CPU0_PE1_PCH_C_TXN<12>
  D60  P3E_CPU0_PE1_PCH_C_TXN<11>  PCIEUP_11_RXN  @BASEBOARD_FAB2_LIB.BASEBOARD_FAB2(SCH_1):P3E_CPU0_PE1_PCH_C_TXN<11>
  A59  P3E_CPU0_PE1_PCH_C_TXN<10>  PCIEUP_10_RXP  @BASEBOARD_FAB2_LIB.BASEBOARD_FAB2(SCH_1):P3E_CPU0_PE1_PCH_C_TXN<10>
  A45  DMI_CPU0_PCH_TX_C_DP<3>  DMI_RXP<3>  @BASEBOARD_FAB2_LIB.BASEBOARD_FAB2(SCH_1):DMI_CPU0_PCH_TX_C_DP<3>
  B44  DMI_CPU0_PCH_TX_C_DP<2>  DMI_RXP<2>  @BASEBOARD_FAB2_LIB.BASEBOARD_FAB2(SCH_1):DMI_CPU0_PCH_TX_C_DP<2>
  A43  DMI_CPU0_PCH_TX_C_DP<1>  DMI_RXP<1>  @BASEBOARD_FAB2_LIB.BASEBOARD_FAB2(SCH_1):DMI_CPU0_PCH_TX_C_DP<1>
  B42  DMI_CPU0_PCH_TX_C_DP<0>  DMI_RXP<0>  @BASEBOARD_FAB2_LIB.BASEBOARD_FAB2(SCH_1):DMI_CPU0_PCH_TX_C_DP<0>
  C45  DMI_CPU0_PCH_TX_C_DN<3>  DMI_RXN<3>  @BASEBOARD_FAB2_LIB.BASEBOARD_FAB2(SCH_1):DMI_CPU0_PCH_TX_C_DN<3>
  D44  DMI_CPU0_PCH_TX_C_DN<2>  DMI_RXN<2>  @BASEBOARD_FAB2_LIB.BASEBOARD_FAB2(SCH_1):DMI_CPU0_PCH_TX_C_DN<2>
  C43  DMI_CPU0_PCH_TX_C_DN<1>  DMI_RXN<1>  @BASEBOARD_FAB2_LIB.BASEBOARD_FAB2(SCH_1):DMI_CPU0_PCH_TX_C_DN<1>
  D42  DMI_CPU0_PCH_TX_C_DN<0>  DMI_RXN<0>  @BASEBOARD_FAB2_LIB.BASEBOARD_FAB2(SCH_1):DMI_CPU0_PCH_TX_C_DN<0>
  N54  DMI_CPU0_PCH_RX_DP<3>  DMI_TXP<3>  @BASEBOARD_FAB2_LIB.BASEBOARD_FAB2(SCH_1):DMI_CPU0_PCH_RX_DP<3>
  M52  DMI_CPU0_PCH_RX_DP<2>  DMI_TXP<2>  @BASEBOARD_FAB2_LIB.BASEBOARD_FAB2(SCH_1):DMI_CPU0_PCH_RX_DP<2>
  H50  DMI_CPU0_PCH_RX_DP<1>  DMI_TXP<1>  @BASEBOARD_FAB2_LIB.BASEBOARD_FAB2(SCH_1):DMI_CPU0_PCH_RX_DP<1>
  K46  DMI_CPU0_PCH_RX_DP<0>  DMI_TXP<0>  @BASEBOARD_FAB2_LIB.BASEBOARD_FAB2(SCH_1):DMI_CPU0_PCH_RX_DP<0>
  P52  DMI_CPU0_PCH_RX_DN<3>  DMI_TXN<3>  @BASEBOARD_FAB2_LIB.BASEBOARD_FAB2(SCH_1):DMI_CPU0_PCH_RX_DN<3>
  K50  DMI_CPU0_PCH_RX_DN<2>  DMI_TXN<2>  @BASEBOARD_FAB2_LIB.BASEBOARD_FAB2(SCH_1):DMI_CPU0_PCH_RX_DN<2>
  J48  DMI_CPU0_PCH_RX_DN<1>  DMI_TXN<1>  @BASEBOARD_FAB2_LIB.BASEBOARD_FAB2(SCH_1):DMI_CPU0_PCH_RX_DN<1>
  H46  DMI_CPU0_PCH_RX_DN<0>  DMI_TXN<0>  @BASEBOARD_FAB2_LIB.BASEBOARD_FAB2(SCH_1):DMI_CPU0_PCH_RX_DN<0>

LBG_CORE_QAT_EXT_D  I220  U7C1   [LBG_CORE_QAT_EXT_D_BGA1-IC,H91A]
  AA71  TP_PCH_RSVD52  RSVD<52>  @BASEBOARD_FAB2_LIB.BASEBOARD_FAB2(SCH_1):TP_PCH_RSVD52
  AA69  TP_PCH_RSVD51  RSVD<51>  @BASEBOARD_FAB2_LIB.BASEBOARD_FAB2(SCH_1):TP_PCH_RSVD51
  H69  TP_PCH_RSVD50  RSVD<50>  @BASEBOARD_FAB2_LIB.BASEBOARD_FAB2(SCH_1):TP_PCH_RSVD50
  G67  TP_PCH_RSVD49  RSVD<49>  @BASEBOARD_FAB2_LIB.BASEBOARD_FAB2(SCH_1):TP_PCH_RSVD49
  AP71  TP_PCH_RSVD48  RSVD<48>  @BASEBOARD_FAB2_LIB.BASEBOARD_FAB2(SCH_1):TP_PCH_RSVD48
  AP69  TP_PCH_RSVD47  RSVD<47>  @BASEBOARD_FAB2_LIB.BASEBOARD_FAB2(SCH_1):TP_PCH_RSVD47
  AC71  SATA6G_TX_DP<3>  PCIE11_SSATA5_GBE_TXP  @BASEBOARD_FAB2_LIB.BASEBOARD_FAB2(SCH_1):SATA6G_TX_DP<3>
  AD72  SATA6G_TX_DP<2>  PCIE10_SSATA4_TXP  @BASEBOARD_FAB2_LIB.BASEBOARD_FAB2(SCH_1):SATA6G_TX_DP<2>
  AE71  SATA6G_TX_DP<1>  PCIE9_SSATA3_TXP  @BASEBOARD_FAB2_LIB.BASEBOARD_FAB2(SCH_1):SATA6G_TX_DP<1>
  AF72  SATA6G_TX_DP<0>  PCIE8_SSATA2_GBE_TXP  @BASEBOARD_FAB2_LIB.BASEBOARD_FAB2(SCH_1):SATA6G_TX_DP<0>
  AC69  SATA6G_TX_DN<3>  PCIE11_SSATA5_GBE_TXN  @BASEBOARD_FAB2_LIB.BASEBOARD_FAB2(SCH_1):SATA6G_TX_DN<3>
  AD70  SATA6G_TX_DN<2>  PCIE10_SSATA4_TXN  @BASEBOARD_FAB2_LIB.BASEBOARD_FAB2(SCH_1):SATA6G_TX_DN<2>
  AE69  SATA6G_TX_DN<1>  PCIE9_SSATA3_TXN  @BASEBOARD_FAB2_LIB.BASEBOARD_FAB2(SCH_1):SATA6G_TX_DN<1>
  AF70  SATA6G_TX_DN<0>  PCIE8_SSATA2_GBE_TXN  @BASEBOARD_FAB2_LIB.BASEBOARD_FAB2(SCH_1):SATA6G_TX_DN<0>
  AH71  SATA6G_S1_TX_DP  PCIE7_SSATA1_TXP  @BASEBOARD_FAB2_LIB.BASEBOARD_FAB2(SCH_1):SATA6G_S1_TX_DP
  AH69  SATA6G_S1_TX_DN  PCIE7_SSATA1_TXN  @BASEBOARD_FAB2_LIB.BASEBOARD_FAB2(SCH_1):SATA6G_S1_TX_DN
  BA61  SATA6G_S1_RX_DP  PCIE7_SSATA1_RXP  @BASEBOARD_FAB2_LIB.BASEBOARD_FAB2(SCH_1):SATA6G_S1_RX_DP
  AY59  SATA6G_S1_RX_DN  PCIE7_SSATA1_RXN  @BASEBOARD_FAB2_LIB.BASEBOARD_FAB2(SCH_1):SATA6G_S1_RX_DN
  AJ72  SATA6G_S0_TX_DP  PCIE6_SSATA0_TXP  @BASEBOARD_FAB2_LIB.BASEBOARD_FAB2(SCH_1):SATA6G_S0_TX_DP
  AJ70  SATA6G_S0_TX_DN  PCIE6_SSATA0_TXN  @BASEBOARD_FAB2_LIB.BASEBOARD_FAB2(SCH_1):SATA6G_S0_TX_DN
  BD61  SATA6G_S0_RX_DP  PCIE6_SSATA0_RXP  @BASEBOARD_FAB2_LIB.BASEBOARD_FAB2(SCH_1):SATA6G_S0_RX_DP
  BB63  SATA6G_S0_RX_DN  PCIE6_SSATA0_RXN  @BASEBOARD_FAB2_LIB.BASEBOARD_FAB2(SCH_1):SATA6G_S0_RX_DN
  AV66  SATA6G_RX_DP<3>  PCIE11_SSATA5_GBE_RXP  @BASEBOARD_FAB2_LIB.BASEBOARD_FAB2(SCH_1):SATA6G_RX_DP<3>
  AU65  SATA6G_RX_DP<2>  PCIE10_SSATA4_RXP  @BASEBOARD_FAB2_LIB.BASEBOARD_FAB2(SCH_1):SATA6G_RX_DP<2>
  AY66  SATA6G_RX_DP<1>  PCIE9_SSATA3_RXP  @BASEBOARD_FAB2_LIB.BASEBOARD_FAB2(SCH_1):SATA6G_RX_DP<1>
  BD65  SATA6G_RX_DP<0>  PCIE8_SSATA2_GBE_RXP  @BASEBOARD_FAB2_LIB.BASEBOARD_FAB2(SCH_1):SATA6G_RX_DP<0>
  AT66  SATA6G_RX_DN<3>  PCIE11_SSATA5_GBE_RXN  @BASEBOARD_FAB2_LIB.BASEBOARD_FAB2(SCH_1):SATA6G_RX_DN<3>
  AV63  SATA6G_RX_DN<2>  PCIE10_SSATA4_RXN  @BASEBOARD_FAB2_LIB.BASEBOARD_FAB2(SCH_1):SATA6G_RX_DN<2>
  AW65  SATA6G_RX_DN<1>  PCIE9_SSATA3_RXN  @BASEBOARD_FAB2_LIB.BASEBOARD_FAB2(SCH_1):SATA6G_RX_DN<1>
  BA65  SATA6G_RX_DN<0>  PCIE8_SSATA2_GBE_RXN  @BASEBOARD_FAB2_LIB.BASEBOARD_FAB2(SCH_1):SATA6G_RX_DN<0>
  L72  SATA6G_PCH_PCIE_UP_SATA_TXP<7>  PCIE19_UP7_SATA7_TXP  @BASEBOARD_FAB2_LIB.BASEBOARD_FAB2(SCH_1):SATA6G_PCH_PCIE_UP_SATA_TXP<7>
  M71  SATA6G_PCH_PCIE_UP_SATA_TXP<6>  PCIE18_UP6_SATA6_TXP  @BASEBOARD_FAB2_LIB.BASEBOARD_FAB2(SCH_1):SATA6G_PCH_PCIE_UP_SATA_TXP<6>
  N72  SATA6G_PCH_PCIE_UP_SATA_TXP<5>  PCIE17_UP5_SATA5_TXP  @BASEBOARD_FAB2_LIB.BASEBOARD_FAB2(SCH_1):SATA6G_PCH_PCIE_UP_SATA_TXP<5>
  P71  SATA6G_PCH_PCIE_UP_SATA_TXP<4>  PCIE16_UP4_SATA4_TXP  @BASEBOARD_FAB2_LIB.BASEBOARD_FAB2(SCH_1):SATA6G_PCH_PCIE_UP_SATA_TXP<4>
  R72  SATA6G_PCH_PCIE_UP_SATA_TXP<3>  PCIE15_UP3_SATA3_TXP  @BASEBOARD_FAB2_LIB.BASEBOARD_FAB2(SCH_1):SATA6G_PCH_PCIE_UP_SATA_TXP<3>
  T71  SATA6G_PCH_PCIE_UP_SATA_TXP<2>  PCIE14_UP2_SATA2_TXP  @BASEBOARD_FAB2_LIB.BASEBOARD_FAB2(SCH_1):SATA6G_PCH_PCIE_UP_SATA_TXP<2>
  V72  SATA6G_PCH_PCIE_UP_SATA_TXP<1>  PCIE13_UP1_SATA1_TXP  @BASEBOARD_FAB2_LIB.BASEBOARD_FAB2(SCH_1):SATA6G_PCH_PCIE_UP_SATA_TXP<1>
  W71  SATA6G_PCH_PCIE_UP_SATA_TXP<0>  PCIE12_UP0_SATA0_TXP  @BASEBOARD_FAB2_LIB.BASEBOARD_FAB2(SCH_1):SATA6G_PCH_PCIE_UP_SATA_TXP<0>
  L70  SATA6G_PCH_PCIE_UP_SATA_TXN<7>  PCIE19_UP7_SATA7_TXN  @BASEBOARD_FAB2_LIB.BASEBOARD_FAB2(SCH_1):SATA6G_PCH_PCIE_UP_SATA_TXN<7>
  M69  SATA6G_PCH_PCIE_UP_SATA_TXN<6>  PCIE18_UP6_SATA6_TXN  @BASEBOARD_FAB2_LIB.BASEBOARD_FAB2(SCH_1):SATA6G_PCH_PCIE_UP_SATA_TXN<6>
  N70  SATA6G_PCH_PCIE_UP_SATA_TXN<5>  PCIE17_UP5_SATA5_TXN  @BASEBOARD_FAB2_LIB.BASEBOARD_FAB2(SCH_1):SATA6G_PCH_PCIE_UP_SATA_TXN<5>
  P69  SATA6G_PCH_PCIE_UP_SATA_TXN<4>  PCIE16_UP4_SATA4_TXN  @BASEBOARD_FAB2_LIB.BASEBOARD_FAB2(SCH_1):SATA6G_PCH_PCIE_UP_SATA_TXN<4>
  R70  SATA6G_PCH_PCIE_UP_SATA_TXN<3>  PCIE15_UP3_SATA3_TXN  @BASEBOARD_FAB2_LIB.BASEBOARD_FAB2(SCH_1):SATA6G_PCH_PCIE_UP_SATA_TXN<3>
  T69  SATA6G_PCH_PCIE_UP_SATA_TXN<2>  PCIE14_UP2_SATA2_TXN  @BASEBOARD_FAB2_LIB.BASEBOARD_FAB2(SCH_1):SATA6G_PCH_PCIE_UP_SATA_TXN<2>
  V70  SATA6G_PCH_PCIE_UP_SATA_TXN<1>  PCIE13_UP1_SATA1_TXN  @BASEBOARD_FAB2_LIB.BASEBOARD_FAB2(SCH_1):SATA6G_PCH_PCIE_UP_SATA_TXN<1>
  W69  SATA6G_PCH_PCIE_UP_SATA_TXN<0>  PCIE12_UP0_SATA0_TXN  @BASEBOARD_FAB2_LIB.BASEBOARD_FAB2(SCH_1):SATA6G_PCH_PCIE_UP_SATA_TXN<0>
  AD61  SATA6G_PCH_PCIE_UP_SATA_RXP<7>  PCIE19_UP7_SATA7_RXP  @BASEBOARD_FAB2_LIB.BASEBOARD_FAB2(SCH_1):SATA6G_PCH_PCIE_UP_SATA_RXP<7>
  AN61  SATA6G_PCH_PCIE_UP_SATA_RXP<6>  PCIE18_UP6_SATA6_RXP  @BASEBOARD_FAB2_LIB.BASEBOARD_FAB2(SCH_1):SATA6G_PCH_PCIE_UP_SATA_RXP<6>
  AG63  SATA6G_PCH_PCIE_UP_SATA_RXP<5>  PCIE17_UP5_SATA5_RXP  @BASEBOARD_FAB2_LIB.BASEBOARD_FAB2(SCH_1):SATA6G_PCH_PCIE_UP_SATA_RXP<5>
  AH65  SATA6G_PCH_PCIE_UP_SATA_RXP<4>  PCIE16_UP4_SATA4_RXP  @BASEBOARD_FAB2_LIB.BASEBOARD_FAB2(SCH_1):SATA6G_PCH_PCIE_UP_SATA_RXP<4>
  AL63  SATA6G_PCH_PCIE_UP_SATA_RXP<3>  PCIE15_UP3_SATA3_RXP  @BASEBOARD_FAB2_LIB.BASEBOARD_FAB2(SCH_1):SATA6G_PCH_PCIE_UP_SATA_RXP<3>
  AJ63  SATA6G_PCH_PCIE_UP_SATA_RXP<2>  PCIE14_UP2_SATA2_RXP  @BASEBOARD_FAB2_LIB.BASEBOARD_FAB2(SCH_1):SATA6G_PCH_PCIE_UP_SATA_RXP<2>
  AN65  SATA6G_PCH_PCIE_UP_SATA_RXP<1>  PCIE13_UP1_SATA1_RXP  @BASEBOARD_FAB2_LIB.BASEBOARD_FAB2(SCH_1):SATA6G_PCH_PCIE_UP_SATA_RXP<1>
  AT63  SATA6G_PCH_PCIE_UP_SATA_RXP<0>  PCIE12_UP0_SATA0_RXP  @BASEBOARD_FAB2_LIB.BASEBOARD_FAB2(SCH_1):SATA6G_PCH_PCIE_UP_SATA_RXP<0>
  AA61  SATA6G_PCH_PCIE_UP_SATA_RXN<7>  PCIE19_UP7_SATA7_RXN  @BASEBOARD_FAB2_LIB.BASEBOARD_FAB2(SCH_1):SATA6G_PCH_PCIE_UP_SATA_RXN<7>
  AP59  SATA6G_PCH_PCIE_UP_SATA_RXN<6>  PCIE18_UP6_SATA6_RXN  @BASEBOARD_FAB2_LIB.BASEBOARD_FAB2(SCH_1):SATA6G_PCH_PCIE_UP_SATA_RXN<6>
  AH61  SATA6G_PCH_PCIE_UP_SATA_RXN<5>  PCIE17_UP5_SATA5_RXN  @BASEBOARD_FAB2_LIB.BASEBOARD_FAB2(SCH_1):SATA6G_PCH_PCIE_UP_SATA_RXN<5>
  AF65  SATA6G_PCH_PCIE_UP_SATA_RXN<4>  PCIE16_UP4_SATA4_RXN  @BASEBOARD_FAB2_LIB.BASEBOARD_FAB2(SCH_1):SATA6G_PCH_PCIE_UP_SATA_RXN<4>
  AP63  SATA6G_PCH_PCIE_UP_SATA_RXN<3>  PCIE15_UP3_SATA3_RXN  @BASEBOARD_FAB2_LIB.BASEBOARD_FAB2(SCH_1):SATA6G_PCH_PCIE_UP_SATA_RXN<3>
  AK65  SATA6G_PCH_PCIE_UP_SATA_RXN<2>  PCIE14_UP2_SATA2_RXN  @BASEBOARD_FAB2_LIB.BASEBOARD_FAB2(SCH_1):SATA6G_PCH_PCIE_UP_SATA_RXN<2>
  AL66  SATA6G_PCH_PCIE_UP_SATA_RXN<1>  PCIE13_UP1_SATA1_RXN  @BASEBOARD_FAB2_LIB.BASEBOARD_FAB2(SCH_1):SATA6G_PCH_PCIE_UP_SATA_RXN<1>
  AR61  SATA6G_PCH_PCIE_UP_SATA_RXN<0>  PCIE12_UP0_SATA0_RXN  @BASEBOARD_FAB2_LIB.BASEBOARD_FAB2(SCH_1):SATA6G_PCH_PCIE_UP_SATA_RXN<0>
  BJ63  PE_PCH_SPRV_TX_DP  PCIE5_GBE_TXP  @BASEBOARD_FAB2_LIB.BASEBOARD_FAB2(SCH_1):PE_PCH_SPRV_TX_DP
  BH65  PE_PCH_SPRV_TX_DN  PCIE5_GBE_TXN  @BASEBOARD_FAB2_LIB.BASEBOARD_FAB2(SCH_1):PE_PCH_SPRV_TX_DN
  AM71  PE_PCH_SPRV_RX_C_DP  PCIE5_GBE_RXP  @BASEBOARD_FAB2_LIB.BASEBOARD_FAB2(SCH_1):PE_PCH_SPRV_RX_C_DP
  AM69  PE_PCH_SPRV_RX_C_DN  PCIE5_GBE_RXN  @BASEBOARD_FAB2_LIB.BASEBOARD_FAB2(SCH_1):PE_PCH_SPRV_RX_C_DN
  BN63  P3E_PCH_TX_0_DP  USB3_7_PCIE0_TXP  @BASEBOARD_FAB2_LIB.BASEBOARD_FAB2(SCH_1):P3E_PCH_TX_0_DP
  BR61  P3E_PCH_TX_0_DN  USB3_7_PCIE0_TXN  @BASEBOARD_FAB2_LIB.BASEBOARD_FAB2(SCH_1):P3E_PCH_TX_0_DN
  BA69  P3E_PCH_RX_0_DP  USB3_7_PCIE0_RXP  @BASEBOARD_FAB2_LIB.BASEBOARD_FAB2(SCH_1):P3E_PCH_RX_0_DP
  BA71  P3E_PCH_RX_0_DN  USB3_7_PCIE0_RXN  @BASEBOARD_FAB2_LIB.BASEBOARD_FAB2(SCH_1):P3E_PCH_RX_0_DN
  BK61  P3E_PCH_M2_TX_DP<3>  USB3_10_PCIE3_GBE_TXP  @BASEBOARD_FAB2_LIB.BASEBOARD_FAB2(SCH_1):P3E_PCH_M2_TX_DP<3>
  BL66  P3E_PCH_M2_TX_DP<2>  USB3_9_PCIE2_TXP  @BASEBOARD_FAB2_LIB.BASEBOARD_FAB2(SCH_1):P3E_PCH_M2_TX_DP<2>
  BR65  P3E_PCH_M2_TX_DP<1>  USB3_8_PCIE1_TXP  @BASEBOARD_FAB2_LIB.BASEBOARD_FAB2(SCH_1):P3E_PCH_M2_TX_DP<1>
  BH61  P3E_PCH_M2_TX_DN<3>  USB3_10_PCIE3_GBE_TXN  @BASEBOARD_FAB2_LIB.BASEBOARD_FAB2(SCH_1):P3E_PCH_M2_TX_DN<3>
  BK65  P3E_PCH_M2_TX_DN<2>  USB3_9_PCIE2_TXN  @BASEBOARD_FAB2_LIB.BASEBOARD_FAB2(SCH_1):P3E_PCH_M2_TX_DN<2>
  BM65  P3E_PCH_M2_TX_DN<1>  USB3_8_PCIE1_TXN  @BASEBOARD_FAB2_LIB.BASEBOARD_FAB2(SCH_1):P3E_PCH_M2_TX_DN<1>
  AV70  P3E_PCH_M2_RX_DP<3>  USB3_10_PCIE3_GBE_RXP  @BASEBOARD_FAB2_LIB.BASEBOARD_FAB2(SCH_1):P3E_PCH_M2_RX_DP<3>
  AW69  P3E_PCH_M2_RX_DP<2>  USB3_9_PCIE2_RXP  @BASEBOARD_FAB2_LIB.BASEBOARD_FAB2(SCH_1):P3E_PCH_M2_RX_DP<2>
  AY70  P3E_PCH_M2_RX_DP<1>  USB3_8_PCIE1_RXP  @BASEBOARD_FAB2_LIB.BASEBOARD_FAB2(SCH_1):P3E_PCH_M2_RX_DP<1>
  AV72  P3E_PCH_M2_RX_DN<3>  USB3_10_PCIE3_GBE_RXN  @BASEBOARD_FAB2_LIB.BASEBOARD_FAB2(SCH_1):P3E_PCH_M2_RX_DN<3>
  AW71  P3E_PCH_M2_RX_DN<2>  USB3_9_PCIE2_RXN  @BASEBOARD_FAB2_LIB.BASEBOARD_FAB2(SCH_1):P3E_PCH_M2_RX_DN<2>
  AY72  P3E_PCH_M2_RX_DN<1>  USB3_8_PCIE1_RXN  @BASEBOARD_FAB2_LIB.BASEBOARD_FAB2(SCH_1):P3E_PCH_M2_RX_DN<1>
  BJ66  P2E_SSB_BMC_TX_DP  PCIE4_GBE_TXP  @BASEBOARD_FAB2_LIB.BASEBOARD_FAB2(SCH_1):P2E_SSB_BMC_TX_DP
  BG66  P2E_SSB_BMC_TX_DN  PCIE4_GBE_TXN  @BASEBOARD_FAB2_LIB.BASEBOARD_FAB2(SCH_1):P2E_SSB_BMC_TX_DN
  AN72  P2E_SSB_BMC_RX_C_DP  PCIE4_GBE_RXP  @BASEBOARD_FAB2_LIB.BASEBOARD_FAB2(SCH_1):P2E_SSB_BMC_RX_C_DP
  AN70  P2E_SSB_BMC_RX_C_DN  PCIE4_GBE_RXN  @BASEBOARD_FAB2_LIB.BASEBOARD_FAB2(SCH_1):P2E_SSB_BMC_RX_C_DN
  BB56  A_PCIE_RCOMP_P  PCIE_RCOMPP  @BASEBOARD_FAB2_LIB.BASEBOARD_FAB2(SCH_1):A_PCIE_RCOMP_P
  BD58  A_PCIE_RCOMP_N  PCIE_RCOMPN  @BASEBOARD_FAB2_LIB.BASEBOARD_FAB2(SCH_1):A_PCIE_RCOMP_N
  AH58  A_PCIEUP_RCOMP_P  PCIEUP_RCOMPP  @BASEBOARD_FAB2_LIB.BASEBOARD_FAB2(SCH_1):A_PCIEUP_RCOMP_P
  AF58  A_PCIEUP_RCOMP_N  PCIEUP_RCOMPN  @BASEBOARD_FAB2_LIB.BASEBOARD_FAB2(SCH_1):A_PCIEUP_RCOMP_N
  E67  A_EXTCLKP      EXTCLKP  @BASEBOARD_FAB2_LIB.BASEBOARD_FAB2(SCH_1):A_EXTCLKP
  D66  A_EXTCLKN      EXTCLKN  @BASEBOARD_FAB2_LIB.BASEBOARD_FAB2(SCH_1):A_EXTCLKN

LBG_CORE_QAT_EXT_D  I74  U7C1   [LBG_CORE_QAT_EXT_D_BGA1-IC,H91A]
  BV62  USB_PCH_BMC_P4_DP  USB2P_4  @BASEBOARD_FAB2_LIB.BASEBOARD_FAB2(SCH_1):USB_PCH_BMC_P4_DP
  BY62  USB_PCH_BMC_P4_DN  USB2N_4  @BASEBOARD_FAB2_LIB.BASEBOARD_FAB2(SCH_1):USB_PCH_BMC_P4_DN
  BK54  USB3_P01_TXP   USB3_1_TXP  @BASEBOARD_FAB2_LIB.BASEBOARD_FAB2(SCH_1):USB3_P01_TXP
  BL52  USB3_P01_TXN   USB3_1_TXN  @BASEBOARD_FAB2_LIB.BASEBOARD_FAB2(SCH_1):USB3_P01_TXN
  BK69  USB3_P01_RXP   USB3_1_RXP  @BASEBOARD_FAB2_LIB.BASEBOARD_FAB2(SCH_1):USB3_P01_RXP
  BK71  USB3_P01_RXN   USB3_1_RXN  @BASEBOARD_FAB2_LIB.BASEBOARD_FAB2(SCH_1):USB3_P01_RXN
  BV58  USB2_PCH_BMC_P5_DP  USB2P_5  @BASEBOARD_FAB2_LIB.BASEBOARD_FAB2(SCH_1):USB2_PCH_BMC_P5_DP
  BY58  USB2_PCH_BMC_P5_DN  USB2N_5  @BASEBOARD_FAB2_LIB.BASEBOARD_FAB2(SCH_1):USB2_PCH_BMC_P5_DN
  BV60  USB2_P01_DP    USB2P_1  @BASEBOARD_FAB2_LIB.BASEBOARD_FAB2(SCH_1):USB2_P01_DP
  BY60  USB2_P01_DN    USB2N_1  @BASEBOARD_FAB2_LIB.BASEBOARD_FAB2(SCH_1):USB2_P01_DN
  BM61  TP_USB3_P06_TXP  USB3_6_TXP  @BASEBOARD_FAB2_LIB.BASEBOARD_FAB2(SCH_1):TP_USB3_P06_TXP
  BL59  TP_USB3_P06_TXN  USB3_6_TXN  @BASEBOARD_FAB2_LIB.BASEBOARD_FAB2(SCH_1):TP_USB3_P06_TXN
  BD70  TP_USB3_P06_RXP  USB3_6_RXP  @BASEBOARD_FAB2_LIB.BASEBOARD_FAB2(SCH_1):TP_USB3_P06_RXP
  BD72  TP_USB3_P06_RXN  USB3_6_RXN  @BASEBOARD_FAB2_LIB.BASEBOARD_FAB2(SCH_1):TP_USB3_P06_RXN
  BJ59  TP_USB3_P05_TXP  USB3_5_TXP  @BASEBOARD_FAB2_LIB.BASEBOARD_FAB2(SCH_1):TP_USB3_P05_TXP
  BK58  TP_USB3_P05_TXN  USB3_5_TXN  @BASEBOARD_FAB2_LIB.BASEBOARD_FAB2(SCH_1):TP_USB3_P05_TXN
  BE69  TP_USB3_P05_RXP  USB3_5_RXP  @BASEBOARD_FAB2_LIB.BASEBOARD_FAB2(SCH_1):TP_USB3_P05_RXP
  BE71  TP_USB3_P05_RXN  USB3_5_RXN  @BASEBOARD_FAB2_LIB.BASEBOARD_FAB2(SCH_1):TP_USB3_P05_RXN
  BG56  TP_USB3_P04_TXP  USB3_4_TXP  @BASEBOARD_FAB2_LIB.BASEBOARD_FAB2(SCH_1):TP_USB3_P04_TXP
  BH58  TP_USB3_P04_TXN  USB3_4_TXN  @BASEBOARD_FAB2_LIB.BASEBOARD_FAB2(SCH_1):TP_USB3_P04_TXN
  BF70  TP_USB3_P04_RXP  USB3_4_RXP  @BASEBOARD_FAB2_LIB.BASEBOARD_FAB2(SCH_1):TP_USB3_P04_RXP
  BF72  TP_USB3_P04_RXN  USB3_4_RXN  @BASEBOARD_FAB2_LIB.BASEBOARD_FAB2(SCH_1):TP_USB3_P04_RXN
  BN56  TP_USB3_P03_TXP  USB3_3_TXP  @BASEBOARD_FAB2_LIB.BASEBOARD_FAB2(SCH_1):TP_USB3_P03_TXP
  BM54  TP_USB3_P03_TXN  USB3_3_TXN  @BASEBOARD_FAB2_LIB.BASEBOARD_FAB2(SCH_1):TP_USB3_P03_TXN
  BH69  TP_USB3_P03_RXP  USB3_3_RXP  @BASEBOARD_FAB2_LIB.BASEBOARD_FAB2(SCH_1):TP_USB3_P03_RXP
  BH71  TP_USB3_P03_RXN  USB3_3_RXN  @BASEBOARD_FAB2_LIB.BASEBOARD_FAB2(SCH_1):TP_USB3_P03_RXN
  BJ56  TP_USB3_P02_TXP  USB3_2_TXP  @BASEBOARD_FAB2_LIB.BASEBOARD_FAB2(SCH_1):TP_USB3_P02_TXP
  BL56  TP_USB3_P02_TXN  USB3_2_TXN  @BASEBOARD_FAB2_LIB.BASEBOARD_FAB2(SCH_1):TP_USB3_P02_TXN
  BJ70  TP_USB3_P02_RXP  USB3_2_RXP  @BASEBOARD_FAB2_LIB.BASEBOARD_FAB2(SCH_1):TP_USB3_P02_RXP
  BJ72  TP_USB3_P02_RXN  USB3_2_RXN  @BASEBOARD_FAB2_LIB.BASEBOARD_FAB2(SCH_1):TP_USB3_P02_RXN
  BV55  TP_USB2_P9_DP  USB2P_9  @BASEBOARD_FAB2_LIB.BASEBOARD_FAB2(SCH_1):TP_USB2_P9_DP
  BY55  TP_USB2_P9_DN  USB2N_9  @BASEBOARD_FAB2_LIB.BASEBOARD_FAB2(SCH_1):TP_USB2_P9_DN
  BV64  TP_USB2_P8_DP  USB2P_8  @BASEBOARD_FAB2_LIB.BASEBOARD_FAB2(SCH_1):TP_USB2_P8_DP
  BY64  TP_USB2_P8_DN  USB2N_8  @BASEBOARD_FAB2_LIB.BASEBOARD_FAB2(SCH_1):TP_USB2_P8_DN
  BU67  TP_USB2_P14_DP  USB2P_14  @BASEBOARD_FAB2_LIB.BASEBOARD_FAB2(SCH_1):TP_USB2_P14_DP
  BW68  TP_USB2_P14_DN  USB2N_14  @BASEBOARD_FAB2_LIB.BASEBOARD_FAB2(SCH_1):TP_USB2_P14_DN
  BV53  TP_USB2_P13_DP  USB2P_13  @BASEBOARD_FAB2_LIB.BASEBOARD_FAB2(SCH_1):TP_USB2_P13_DP
  BY53  TP_USB2_P13_DN  USB2N_13  @BASEBOARD_FAB2_LIB.BASEBOARD_FAB2(SCH_1):TP_USB2_P13_DN
  BV66  TP_USB2_P12_DP  USB2P_12  @BASEBOARD_FAB2_LIB.BASEBOARD_FAB2(SCH_1):TP_USB2_P12_DP
  BW67  TP_USB2_P12_DN  USB2N_12  @BASEBOARD_FAB2_LIB.BASEBOARD_FAB2(SCH_1):TP_USB2_P12_DN
  BW54  TP_USB2_P11_DP  USB2P_11  @BASEBOARD_FAB2_LIB.BASEBOARD_FAB2(SCH_1):TP_USB2_P11_DP
  CA54  TP_USB2_P11_DN  USB2N_11  @BASEBOARD_FAB2_LIB.BASEBOARD_FAB2(SCH_1):TP_USB2_P11_DN
  BU65  TP_USB2_P10_DP  USB2P_10  @BASEBOARD_FAB2_LIB.BASEBOARD_FAB2(SCH_1):TP_USB2_P10_DP
  BW65  TP_USB2_P10_DN  USB2N_10  @BASEBOARD_FAB2_LIB.BASEBOARD_FAB2(SCH_1):TP_USB2_P10_DN
  BW57  TP_USB2_P07_DP  USB2P_7  @BASEBOARD_FAB2_LIB.BASEBOARD_FAB2(SCH_1):TP_USB2_P07_DP
  CA57  TP_USB2_P07_DN  USB2N_7  @BASEBOARD_FAB2_LIB.BASEBOARD_FAB2(SCH_1):TP_USB2_P07_DN
  BW63  TP_USB2_P06_DP  USB2P_6  @BASEBOARD_FAB2_LIB.BASEBOARD_FAB2(SCH_1):TP_USB2_P06_DP
  CA63  TP_USB2_P06_DN  USB2N_6  @BASEBOARD_FAB2_LIB.BASEBOARD_FAB2(SCH_1):TP_USB2_P06_DN
  BW59  TP_USB2_P03_DP  USB2P_3  @BASEBOARD_FAB2_LIB.BASEBOARD_FAB2(SCH_1):TP_USB2_P03_DP
  CA59  TP_USB2_P03_DN  USB2N_3  @BASEBOARD_FAB2_LIB.BASEBOARD_FAB2(SCH_1):TP_USB2_P03_DN
  BW61  TP_USB2_P02_DP  USB2P_2  @BASEBOARD_FAB2_LIB.BASEBOARD_FAB2(SCH_1):TP_USB2_P02_DP
  CA61  TP_USB2_P02_DN  USB2N_2  @BASEBOARD_FAB2_LIB.BASEBOARD_FAB2(SCH_1):TP_USB2_P02_DN
  BN68  TP_PCH_RSVD55  RSVD<55>  @BASEBOARD_FAB2_LIB.BASEBOARD_FAB2(SCH_1):TP_PCH_RSVD55
  BR67  A_USB2_VBUS    USB2_VBUS  @BASEBOARD_FAB2_LIB.BASEBOARD_FAB2(SCH_1):A_USB2_VBUS
  BN70  A_USB2_COMP    USB2_COMP  @BASEBOARD_FAB2_LIB.BASEBOARD_FAB2(SCH_1):A_USB2_COMP

LBG_CORE_QAT_EXT_D  I40  U7C1   [LBG_CORE_QAT_EXT_D_BGA1-IC,H91A]
  D35  XTAL_PCH_48M_OUT  XTAL_OUT  @BASEBOARD_FAB2_LIB.BASEBOARD_FAB2(SCH_1):XTAL_PCH_48M_OUT
  B35  XTAL_PCH_48M_IN  XTAL_IN  @BASEBOARD_FAB2_LIB.BASEBOARD_FAB2(SCH_1):XTAL_PCH_48M_IN
  H17  XTAL_33K_RTC2  RTCX2  @BASEBOARD_FAB2_LIB.BASEBOARD_FAB2(SCH_1):XTAL_33K_RTC2
  K17  XTAL_33K_RTC1  RTCX1  @BASEBOARD_FAB2_LIB.BASEBOARD_FAB2(SCH_1):XTAL_33K_RTC1
  A26  TP_PCH_RSVD65  RSVD<65>  @BASEBOARD_FAB2_LIB.BASEBOARD_FAB2(SCH_1):TP_PCH_RSVD65
  C26  TP_PCH_RSVD64  RSVD<64>  @BASEBOARD_FAB2_LIB.BASEBOARD_FAB2(SCH_1):TP_PCH_RSVD64
  BV51  TP_CLK_24M_PMSYNC2  CLOCKSE_PMSYNCCLK2  @BASEBOARD_FAB2_LIB.BASEBOARD_FAB2(SCH_1):TP_CLK_24M_PMSYNC2
  A24  TP_CLK_100M_SRC13_DP  CLKOUT_SRCP<13>  @BASEBOARD_FAB2_LIB.BASEBOARD_FAB2(SCH_1):TP_CLK_100M_SRC13_DP
  C24  TP_CLK_100M_SRC13_DN  CLKOUT_SRCN<13>  @BASEBOARD_FAB2_LIB.BASEBOARD_FAB2(SCH_1):TP_CLK_100M_SRC13_DN
  H24  TP_CLK_100M_SRC12_DP  CLKOUT_SRCP<12>  @BASEBOARD_FAB2_LIB.BASEBOARD_FAB2(SCH_1):TP_CLK_100M_SRC12_DP
  K24  TP_CLK_100M_SRC12_DN  CLKOUT_SRCN<12>  @BASEBOARD_FAB2_LIB.BASEBOARD_FAB2(SCH_1):TP_CLK_100M_SRC12_DN
  D40  TP_CLK_100M_PLAT1_DP  CLKOUT_PLAT1P  @BASEBOARD_FAB2_LIB.BASEBOARD_FAB2(SCH_1):TP_CLK_100M_PLAT1_DP
  B40  TP_CLK_100M_PLAT1_DN  CLKOUT_PLAT1N  @BASEBOARD_FAB2_LIB.BASEBOARD_FAB2(SCH_1):TP_CLK_100M_PLAT1_DN
  D38  TP_CLK_100M_NSSCC1_DP  CLKOUT_NSSCCAP1P  @BASEBOARD_FAB2_LIB.BASEBOARD_FAB2(SCH_1):TP_CLK_100M_NSSCC1_DP
  B38  TP_CLK_100M_NSSCC1_DN  CLKOUT_NSSCCAP1N  @BASEBOARD_FAB2_LIB.BASEBOARD_FAB2(SCH_1):TP_CLK_100M_NSSCC1_DN
  C32  TP_CLK_100M_NSSCC0_DP  CLKOUT_NSSCCAP0P  @BASEBOARD_FAB2_LIB.BASEBOARD_FAB2(SCH_1):TP_CLK_100M_NSSCC0_DP
  A32  TP_CLK_100M_NSSCC0_DN  CLKOUT_NSSCCAP0N  @BASEBOARD_FAB2_LIB.BASEBOARD_FAB2(SCH_1):TP_CLK_100M_NSSCC0_DN
  BY51  H_PMSYNC_CLK_24M_R  CLOCKSE_PMSYNCCLK1  @BASEBOARD_FAB2_LIB.BASEBOARD_FAB2(SCH_1):H_PMSYNC_CLK_24M_R
  BW50  CLK_48M_USB_BMC  CLOCKSE_BMCCLK  @BASEBOARD_FAB2_LIB.BASEBOARD_FAB2(SCH_1):CLK_48M_USB_BMC
  A20  CLK_100M_SPRV_DP  CLKOUT_SRCP<14>  @BASEBOARD_FAB2_LIB.BASEBOARD_FAB2(SCH_1):CLK_100M_SPRV_DP
  C20  CLK_100M_SPRV_DN  CLKOUT_SRCN<14>  @BASEBOARD_FAB2_LIB.BASEBOARD_FAB2(SCH_1):CLK_100M_SPRV_DN
  C39  CLK_100M_PCH_XDP_DP  CLKOUT_ITPXDPP  @BASEBOARD_FAB2_LIB.BASEBOARD_FAB2(SCH_1):CLK_100M_PCH_XDP_DP
  A39  CLK_100M_PCH_XDP_DN  CLKOUT_ITPXDPN  @BASEBOARD_FAB2_LIB.BASEBOARD_FAB2(SCH_1):CLK_100M_PCH_XDP_DN
  K31  CLK_100M_PCH_SLOTX24_S5_DP  CLKOUT_SRCP<7>  @BASEBOARD_FAB2_LIB.BASEBOARD_FAB2(SCH_1):CLK_100M_PCH_SLOTX24_S5_DP
  H31  CLK_100M_PCH_SLOTX24_S5_DN  CLKOUT_SRCN<7>  @BASEBOARD_FAB2_LIB.BASEBOARD_FAB2(SCH_1):CLK_100M_PCH_SLOTX24_S5_DN
  B33  CLK_100M_PCH_SLOTX24_S4_DP  CLKOUT_SRCP<6>  @BASEBOARD_FAB2_LIB.BASEBOARD_FAB2(SCH_1):CLK_100M_PCH_SLOTX24_S4_DP
  D33  CLK_100M_PCH_SLOTX24_S4_DN  CLKOUT_SRCN<6>  @BASEBOARD_FAB2_LIB.BASEBOARD_FAB2(SCH_1):CLK_100M_PCH_SLOTX24_S4_DN
  G40  CLK_100M_PCH_SLOTX24_S3_DP  CLKOUT_SRCP<5>  @BASEBOARD_FAB2_LIB.BASEBOARD_FAB2(SCH_1):CLK_100M_PCH_SLOTX24_S3_DP
  J40  CLK_100M_PCH_SLOTX24_S3_DN  CLKOUT_SRCN<5>  @BASEBOARD_FAB2_LIB.BASEBOARD_FAB2(SCH_1):CLK_100M_PCH_SLOTX24_S3_DN
  C28  CLK_100M_PCH_SLOTX24_S2_DP  CLKOUT_SRCP<4>  @BASEBOARD_FAB2_LIB.BASEBOARD_FAB2(SCH_1):CLK_100M_PCH_SLOTX24_S2_DP
  A28  CLK_100M_PCH_SLOTX24_S2_DN  CLKOUT_SRCN<4>  @BASEBOARD_FAB2_LIB.BASEBOARD_FAB2(SCH_1):CLK_100M_PCH_SLOTX24_S2_DN
  H42  CLK_100M_PCH_SLOTX24_S1_DP  CLKOUT_SRCP<3>  @BASEBOARD_FAB2_LIB.BASEBOARD_FAB2(SCH_1):CLK_100M_PCH_SLOTX24_S1_DP
  K42  CLK_100M_PCH_SLOTX24_S1_DN  CLKOUT_SRCN<3>  @BASEBOARD_FAB2_LIB.BASEBOARD_FAB2(SCH_1):CLK_100M_PCH_SLOTX24_S1_DN
  G33  CLK_100M_PCH_SLOTX24_S0_DP  CLKOUT_SRCP<2>  @BASEBOARD_FAB2_LIB.BASEBOARD_FAB2(SCH_1):CLK_100M_PCH_SLOTX24_S0_DP
  J33  CLK_100M_PCH_SLOTX24_S0_DN  CLKOUT_SRCN<2>  @BASEBOARD_FAB2_LIB.BASEBOARD_FAB2(SCH_1):CLK_100M_PCH_SLOTX24_S0_DN
  D21  CLK_100M_MEZZ4_DP  CLKOUT_SRCP<11>  @BASEBOARD_FAB2_LIB.BASEBOARD_FAB2(SCH_1):CLK_100M_MEZZ4_DP
  B21  CLK_100M_MEZZ4_DN  CLKOUT_SRCN<11>  @BASEBOARD_FAB2_LIB.BASEBOARD_FAB2(SCH_1):CLK_100M_MEZZ4_DN
  D23  CLK_100M_MEZZ3_DP  CLKOUT_SRCP<10>  @BASEBOARD_FAB2_LIB.BASEBOARD_FAB2(SCH_1):CLK_100M_MEZZ3_DP
  B23  CLK_100M_MEZZ3_DN  CLKOUT_SRCN<10>  @BASEBOARD_FAB2_LIB.BASEBOARD_FAB2(SCH_1):CLK_100M_MEZZ3_DN
  G26  CLK_100M_MEZZ2_DP  CLKOUT_SRCP<9>  @BASEBOARD_FAB2_LIB.BASEBOARD_FAB2(SCH_1):CLK_100M_MEZZ2_DP
  J26  CLK_100M_MEZZ2_DN  CLKOUT_SRCN<9>  @BASEBOARD_FAB2_LIB.BASEBOARD_FAB2(SCH_1):CLK_100M_MEZZ2_DN
  B31  CLK_100M_MEZZ1_DP  CLKOUT_SRCP<8>  @BASEBOARD_FAB2_LIB.BASEBOARD_FAB2(SCH_1):CLK_100M_MEZZ1_DP
  D31  CLK_100M_MEZZ1_DN  CLKOUT_SRCN<8>  @BASEBOARD_FAB2_LIB.BASEBOARD_FAB2(SCH_1):CLK_100M_MEZZ1_DN
  H27  CLK_100M_M2_DP  CLKOUT_SRCP<15>  @BASEBOARD_FAB2_LIB.BASEBOARD_FAB2(SCH_1):CLK_100M_M2_DP
  K27  CLK_100M_M2_DN  CLKOUT_SRCN<15>  @BASEBOARD_FAB2_LIB.BASEBOARD_FAB2(SCH_1):CLK_100M_M2_DN
  H35  CLK_100M_DB1200_DP  CLKOUT_SRCP<1>  @BASEBOARD_FAB2_LIB.BASEBOARD_FAB2(SCH_1):CLK_100M_DB1200_DP
  K35  CLK_100M_DB1200_DN  CLKOUT_SRCN<1>  @BASEBOARD_FAB2_LIB.BASEBOARD_FAB2(SCH_1):CLK_100M_DB1200_DN
  D29  CLK_100M_BMC_PE_DP  CLKOUT_PLAT0P  @BASEBOARD_FAB2_LIB.BASEBOARD_FAB2(SCH_1):CLK_100M_BMC_PE_DP
  B29  CLK_100M_BMC_PE_DN  CLKOUT_PLAT0N  @BASEBOARD_FAB2_LIB.BASEBOARD_FAB2(SCH_1):CLK_100M_BMC_PE_DN
  H38  CLK_100M_AIRMAX8_PE1_DP  CLKOUT_SRCP<0>  @BASEBOARD_FAB2_LIB.BASEBOARD_FAB2(SCH_1):CLK_100M_AIRMAX8_PE1_DP
  K38  CLK_100M_AIRMAX8_PE1_DN  CLKOUT_SRCN<0>  @BASEBOARD_FAB2_LIB.BASEBOARD_FAB2(SCH_1):CLK_100M_AIRMAX8_PE1_DN
  G44  A_PCH_XCLK_BIASREF  XCLK_BIASREF  @BASEBOARD_FAB2_LIB.BASEBOARD_FAB2(SCH_1):A_PCH_XCLK_BIASREF

74CBTLV1G125  I142  U7D1   [74CBTLV1G125_SMLF-IC,C88177-00A]
    2  XDP_PCH_PWR_DEBUG_N      A  @BASEBOARD_FAB2_LIB.BASEBOARD_FAB2(SCH_1):XDP_PCH_PWR_DEBUG_N
    4  XDP_CPU_PWR_DEBUG_N      B  @BASEBOARD_FAB2_LIB.BASEBOARD_FAB2(SCH_1):XDP_CPU_PWR_DEBUG_N
    1  PWRGD_PVCCIO_CPU0   OE_N  @BASEBOARD_FAB2_LIB.BASEBOARD_FAB2(SCH_1):PWRGD_PVCCIO_CPU0

GTL2014_SM  I32  U7D2   [GTL2014_SM-IC,D66151-001]
    1  PD_GTL2104_DIR_0    DIR  @BASEBOARD_FAB2_LIB.BASEBOARD_FAB2(SCH_1):PD_GTL2104_DIR_0
   14  P3V3             VCC  @BASEBOARD_FAB2_LIB.BASEBOARD_FAB2(SCH_1):P3V3
    4  P0V7_GTL2104_VREF_0   VREF  @BASEBOARD_FAB2_LIB.BASEBOARD_FAB2(SCH_1):P0V7_GTL2104_VREF_0
    2  H_CPU_MSMI_G_N     B0  @BASEBOARD_FAB2_LIB.BASEBOARD_FAB2(SCH_1):H_CPU_MSMI_G_N
    5  H_CPU_ERR2_GTL_N     B2  @BASEBOARD_FAB2_LIB.BASEBOARD_FAB2(SCH_1):H_CPU_ERR2_GTL_N
    6  H_CPU0_THERMTRIP_G_N     B3  @BASEBOARD_FAB2_LIB.BASEBOARD_FAB2(SCH_1):H_CPU0_THERMTRIP_G_N
    3  H_CPU0_FIVR_FAULT_G     B1  @BASEBOARD_FAB2_LIB.BASEBOARD_FAB2(SCH_1):H_CPU0_FIVR_FAULT_G
   11  GND            GND<2>  @BASEBOARD_FAB2_LIB.BASEBOARD_FAB2(SCH_1):GND
    8  GND            GND<1>  @BASEBOARD_FAB2_LIB.BASEBOARD_FAB2(SCH_1):GND
    7  GND            GND<0>  @BASEBOARD_FAB2_LIB.BASEBOARD_FAB2(SCH_1):GND
   13  FM_CPU_MSMI_LVT3_R_N     A0  @BASEBOARD_FAB2_LIB.BASEBOARD_FAB2(SCH_1):FM_CPU_MSMI_LVT3_R_N
   10  FM_CPU_ERR2_LVT3_R_N     A2  @BASEBOARD_FAB2_LIB.BASEBOARD_FAB2(SCH_1):FM_CPU_ERR2_LVT3_R_N
    9  FM_CPU0_THERMTRIP_LVT3_R_N     A3  @BASEBOARD_FAB2_LIB.BASEBOARD_FAB2(SCH_1):FM_CPU0_THERMTRIP_LVT3_R_N
   12  FM_CPU0_FIVR_FAULT_R_LVT3     A1  @BASEBOARD_FAB2_LIB.BASEBOARD_FAB2(SCH_1):FM_CPU0_FIVR_FAULT_R_LVT3

ADM1085_SMT  I70  U7D3   [ADM1085_SMT-IC,H46130-001]
    3  VSENSE_P12V_ADM1085    VIN  @BASEBOARD_FAB2_LIB.BASEBOARD_FAB2(SCH_1):VSENSE_P12V_ADM1085
    1  PWRGD_P3V3_STBY   ENIN  @BASEBOARD_FAB2_LIB.BASEBOARD_FAB2(SCH_1):PWRGD_P3V3_STBY
    4  PWRGD_DSW_PWROK  ENOUT  @BASEBOARD_FAB2_LIB.BASEBOARD_FAB2(SCH_1):PWRGD_DSW_PWROK
    6  P3V3_STBY        VCC  @BASEBOARD_FAB2_LIB.BASEBOARD_FAB2(SCH_1):P3V3_STBY
    2  GND              GND  @BASEBOARD_FAB2_LIB.BASEBOARD_FAB2(SCH_1):GND
    5  A_ADM1085_CEXT   CEXT  @BASEBOARD_FAB2_LIB.BASEBOARD_FAB2(SCH_1):A_ADM1085_CEXT

PCA9617_SSOP  I61  U7E1   [PCA9617_SSOP-IC,G81764-001-GNDA]
    5  TP_SMB_DDR_DEF_EN     EN  @BASEBOARD_FAB2_LIB.BASEBOARD_FAB2(SCH_1):TP_SMB_DDR_DEF_EN
    6  SMB_DDR_DEF_VPP_SDA_R   SDAB  @BASEBOARD_FAB2_LIB.BASEBOARD_FAB2(SCH_1):SMB_DDR_DEF_VPP_SDA_R
    7  SMB_DDR_DEF_VPP_SCL_R   SCLB  @BASEBOARD_FAB2_LIB.BASEBOARD_FAB2(SCH_1):SMB_DDR_DEF_VPP_SCL_R
    3  SMB_DDR_DEF_SDA_G   SDAA  @BASEBOARD_FAB2_LIB.BASEBOARD_FAB2(SCH_1):SMB_DDR_DEF_SDA_G
    2  SMB_DDR_DEF_SCL_G   SCLA  @BASEBOARD_FAB2_LIB.BASEBOARD_FAB2(SCH_1):SMB_DDR_DEF_SCL_G
    8  PVPP_DEF        VCCB  @BASEBOARD_FAB2_LIB.BASEBOARD_FAB2(SCH_1):PVPP_DEF
    1  PVCCIO_CPU0     VCCA  @BASEBOARD_FAB2_LIB.BASEBOARD_FAB2(SCH_1):PVCCIO_CPU0

TTL1G08  I117  U7E2   [TTL1G08_SOTLF-NC7SZ08,IC,D1032B]
    2  IRQ_PVCCIN_CPU0_VRHOT_LVC3_N   B<0>  @BASEBOARD_FAB2_LIB.BASEBOARD_FAB2(SCH_1):IRQ_PVCCIN_CPU0_VRHOT_LVC3_N
    4  IRQ_CPU0_PROCHOT_G_N   Y<0>  @BASEBOARD_FAB2_LIB.BASEBOARD_FAB2(SCH_1):IRQ_CPU0_PROCHOT_G_N
    1  FM_PVCCIN_CPU0_PWR_IN_ALERT_N   A<0>  @BASEBOARD_FAB2_LIB.BASEBOARD_FAB2(SCH_1):FM_PVCCIN_CPU0_PWR_IN_ALERT_N

TTL1G08  I118  U7E3   [TTL1G08_SOTLF-NC7SZ08,IC,D1032B]
    2  IRQ_PVCCIN_CPU1_VRHOT_LVC3_N   B<0>  @BASEBOARD_FAB2_LIB.BASEBOARD_FAB2(SCH_1):IRQ_PVCCIN_CPU1_VRHOT_LVC3_N
    4  IRQ_CPU1_PROCHOT_G_N   Y<0>  @BASEBOARD_FAB2_LIB.BASEBOARD_FAB2(SCH_1):IRQ_CPU1_PROCHOT_G_N
    1  FM_PVCCIN_CPU1_PWR_IN_ALERT_N   A<0>  @BASEBOARD_FAB2_LIB.BASEBOARD_FAB2(SCH_1):FM_PVCCIN_CPU1_PWR_IN_ALERT_N

W25Q256_XSOI  I146  U7F1   [W25Q256_XSOI-IC,H25002-001]
    4  TP_SPI_0_6     NC<6>  @BASEBOARD_FAB2_LIB.BASEBOARD_FAB2(SCH_1):TP_SPI_0_6
    5  TP_SPI_0_5     NC<5>  @BASEBOARD_FAB2_LIB.BASEBOARD_FAB2(SCH_1):TP_SPI_0_5
    6  TP_SPI_0_4     NC<4>  @BASEBOARD_FAB2_LIB.BASEBOARD_FAB2(SCH_1):TP_SPI_0_4
   11  TP_SPI_0_3     NC<3>  @BASEBOARD_FAB2_LIB.BASEBOARD_FAB2(SCH_1):TP_SPI_0_3
   12  TP_SPI_0_2     NC<2>  @BASEBOARD_FAB2_LIB.BASEBOARD_FAB2(SCH_1):TP_SPI_0_2
   13  TP_SPI_0_1     NC<1>  @BASEBOARD_FAB2_LIB.BASEBOARD_FAB2(SCH_1):TP_SPI_0_1
   14  TP_SPI_0_0     NC<0>  @BASEBOARD_FAB2_LIB.BASEBOARD_FAB2(SCH_1):TP_SPI_0_0
   15  SPI_SWITCH_MOSI_R0  DI_IO<0>  @BASEBOARD_FAB2_LIB.BASEBOARD_FAB2(SCH_1):SPI_SWITCH_MOSI_R0
    8  SPI_MISO_R0    DO_IO<1>  @BASEBOARD_FAB2_LIB.BASEBOARD_FAB2(SCH_1):SPI_MISO_R0
    7  SPI_CS0_PRIMARY_R_N   CS_N  @BASEBOARD_FAB2_LIB.BASEBOARD_FAB2(SCH_1):SPI_CS0_PRIMARY_R_N
   16  SPI_CLK_R0       CLK  @BASEBOARD_FAB2_LIB.BASEBOARD_FAB2(SCH_1):SPI_CLK_R0
    3  PU_SPI0_RST    RESET_N  @BASEBOARD_FAB2_LIB.BASEBOARD_FAB2(SCH_1):PU_SPI0_RST
    9  PU_BIOS_SPI_WP0_N  WP_N_IO<2>  @BASEBOARD_FAB2_LIB.BASEBOARD_FAB2(SCH_1):PU_BIOS_SPI_WP0_N
    1  PU_BIOS_SPI_HOLD0_N  HOLD_N_IO<3>  @BASEBOARD_FAB2_LIB.BASEBOARD_FAB2(SCH_1):PU_BIOS_SPI_HOLD0_N
    2  P3V3_STBY        VCC  @BASEBOARD_FAB2_LIB.BASEBOARD_FAB2(SCH_1):P3V3_STBY
   10  GND              GND  @BASEBOARD_FAB2_LIB.BASEBOARD_FAB2(SCH_1):GND

TTL1G07_A_SOP  I374  U8D2   [TTL1G07_A_SOP-74LVC1G07,IC,C88B]
    4  RST_BMC_SRST_R2_N      Y  @BASEBOARD_FAB2_LIB.BASEBOARD_FAB2(SCH_1):RST_BMC_SRST_R2_N
    2  PWRGD_DSW_PWROK      A  @BASEBOARD_FAB2_LIB.BASEBOARD_FAB2(SCH_1):PWRGD_DSW_PWROK

TTL1G07_A_SOP  I4   U8D3   [TTL1G07_A_SOP-74LVC1G07,IC,C88B]
    2  IRQ_SML1_PMBUS_ALERT_BUF_N      A  @BASEBOARD_FAB2_LIB.BASEBOARD_FAB2(SCH_1):IRQ_SML1_PMBUS_ALERT_BUF_N
    4  IRQ_FORCE_NM_THROTTLE_R_N      Y  @BASEBOARD_FAB2_LIB.BASEBOARD_FAB2(SCH_1):IRQ_FORCE_NM_THROTTLE_R_N

AT24C64  I49  U8D4   [AT24C64_SOICLF-IC,C47049-001-GA]
    5  SMB_SENSOR_STBY_LVC3_SDA_R2    SDA  @BASEBOARD_FAB2_LIB.BASEBOARD_FAB2(SCH_1):SMB_SENSOR_STBY_LVC3_SDA_R2
    6  SMB_SENSOR_STBY_LVC3_SCL_R2    SCL  @BASEBOARD_FAB2_LIB.BASEBOARD_FAB2(SCH_1):SMB_SENSOR_STBY_LVC3_SCL_R2
    3  PU_AT24C64_A2     A2  @BASEBOARD_FAB2_LIB.BASEBOARD_FAB2(SCH_1):PU_AT24C64_A2
    7  PD_FRU_WP         WP  @BASEBOARD_FAB2_LIB.BASEBOARD_FAB2(SCH_1):PD_FRU_WP
    2  GND               A1  @BASEBOARD_FAB2_LIB.BASEBOARD_FAB2(SCH_1):GND
    1  GND               A0  @BASEBOARD_FAB2_LIB.BASEBOARD_FAB2(SCH_1):GND

TTL1G126_A_SOT  I38  U8D5   [TTL1G126_A_SOT-74HC1G126,IC,A7B]
    2  IRQ_SML1_PMBUS_ALERT_N      A  @BASEBOARD_FAB2_LIB.BASEBOARD_FAB2(SCH_1):IRQ_SML1_PMBUS_ALERT_N
    4  IRQ_SML1_PMBUS_ALERT_BUF_N      Y  @BASEBOARD_FAB2_LIB.BASEBOARD_FAB2(SCH_1):IRQ_SML1_PMBUS_ALERT_BUF_N
    1  FM_PMBUS_ALERT_BUF_EN     OE  @BASEBOARD_FAB2_LIB.BASEBOARD_FAB2(SCH_1):FM_PMBUS_ALERT_BUF_EN

LCMXO2_A_256BGA  I14  U8D7   [LCMXO2_A_256BGA-IC,H63395-001]
   E4  P3V3_STBY      VCCIO5<0>  @BASEBOARD_FAB2_LIB.BASEBOARD_FAB2(SCH_1):P3V3_STBY
   H7  P3V3_STBY      VCCIO4<1>  @BASEBOARD_FAB2_LIB.BASEBOARD_FAB2(SCH_1):P3V3_STBY
   J7  P3V3_STBY      VCCIO4<0>  @BASEBOARD_FAB2_LIB.BASEBOARD_FAB2(SCH_1):P3V3_STBY
   M4  P3V3_STBY      VCCIO3<0>  @BASEBOARD_FAB2_LIB.BASEBOARD_FAB2(SCH_1):P3V3_STBY
   N5  P3V3_STBY      VCCIO2<3>  @BASEBOARD_FAB2_LIB.BASEBOARD_FAB2(SCH_1):P3V3_STBY
   K8  P3V3_STBY      VCCIO2<2>  @BASEBOARD_FAB2_LIB.BASEBOARD_FAB2(SCH_1):P3V3_STBY
  N12  P3V3_STBY      VCCIO2<1>  @BASEBOARD_FAB2_LIB.BASEBOARD_FAB2(SCH_1):P3V3_STBY
   K9  P3V3_STBY      VCCIO2<0>  @BASEBOARD_FAB2_LIB.BASEBOARD_FAB2(SCH_1):P3V3_STBY
  M13  P3V3_STBY      VCCIO1<3>  @BASEBOARD_FAB2_LIB.BASEBOARD_FAB2(SCH_1):P3V3_STBY
  J10  P3V3_STBY      VCCIO1<2>  @BASEBOARD_FAB2_LIB.BASEBOARD_FAB2(SCH_1):P3V3_STBY
  H10  P3V3_STBY      VCCIO1<1>  @BASEBOARD_FAB2_LIB.BASEBOARD_FAB2(SCH_1):P3V3_STBY
  E13  P3V3_STBY      VCCIO1<0>  @BASEBOARD_FAB2_LIB.BASEBOARD_FAB2(SCH_1):P3V3_STBY
   D5  P3V3_STBY      VCCIO0<3>  @BASEBOARD_FAB2_LIB.BASEBOARD_FAB2(SCH_1):P3V3_STBY
   G9  P3V3_STBY      VCCIO0<2>  @BASEBOARD_FAB2_LIB.BASEBOARD_FAB2(SCH_1):P3V3_STBY
  D12  P3V3_STBY      VCCIO0<1>  @BASEBOARD_FAB2_LIB.BASEBOARD_FAB2(SCH_1):P3V3_STBY
   G8  P3V3_STBY      VCCIO0<0>  @BASEBOARD_FAB2_LIB.BASEBOARD_FAB2(SCH_1):P3V3_STBY
  K10  P3V3_STBY      VCC<7>  @BASEBOARD_FAB2_LIB.BASEBOARD_FAB2(SCH_1):P3V3_STBY
   K7  P3V3_STBY      VCC<6>  @BASEBOARD_FAB2_LIB.BASEBOARD_FAB2(SCH_1):P3V3_STBY
  G10  P3V3_STBY      VCC<5>  @BASEBOARD_FAB2_LIB.BASEBOARD_FAB2(SCH_1):P3V3_STBY
   G7  P3V3_STBY      VCC<4>  @BASEBOARD_FAB2_LIB.BASEBOARD_FAB2(SCH_1):P3V3_STBY
  T16  P3V3_STBY      VCC<3>  @BASEBOARD_FAB2_LIB.BASEBOARD_FAB2(SCH_1):P3V3_STBY
   T1  P3V3_STBY      VCC<2>  @BASEBOARD_FAB2_LIB.BASEBOARD_FAB2(SCH_1):P3V3_STBY
  A16  P3V3_STBY      VCC<1>  @BASEBOARD_FAB2_LIB.BASEBOARD_FAB2(SCH_1):P3V3_STBY
   A1  P3V3_STBY      VCC<0>  @BASEBOARD_FAB2_LIB.BASEBOARD_FAB2(SCH_1):P3V3_STBY
   A2  NC_CPLD1       NC<0>  @BASEBOARD_FAB2_LIB.BASEBOARD_FAB2(SCH_1):NC_CPLD1
  R15  GND            GND<23>  @BASEBOARD_FAB2_LIB.BASEBOARD_FAB2(SCH_1):GND
   R2  GND            GND<22>  @BASEBOARD_FAB2_LIB.BASEBOARD_FAB2(SCH_1):GND
  P14  GND            GND<21>  @BASEBOARD_FAB2_LIB.BASEBOARD_FAB2(SCH_1):GND
   P3  GND            GND<20>  @BASEBOARD_FAB2_LIB.BASEBOARD_FAB2(SCH_1):GND
  N13  GND            GND<19>  @BASEBOARD_FAB2_LIB.BASEBOARD_FAB2(SCH_1):GND
   N4  GND            GND<18>  @BASEBOARD_FAB2_LIB.BASEBOARD_FAB2(SCH_1):GND
  M12  GND            GND<17>  @BASEBOARD_FAB2_LIB.BASEBOARD_FAB2(SCH_1):GND
   M5  GND            GND<16>  @BASEBOARD_FAB2_LIB.BASEBOARD_FAB2(SCH_1):GND
  L11  GND            GND<15>  @BASEBOARD_FAB2_LIB.BASEBOARD_FAB2(SCH_1):GND
   L6  GND            GND<14>  @BASEBOARD_FAB2_LIB.BASEBOARD_FAB2(SCH_1):GND
   J9  GND            GND<13>  @BASEBOARD_FAB2_LIB.BASEBOARD_FAB2(SCH_1):GND
   J8  GND            GND<12>  @BASEBOARD_FAB2_LIB.BASEBOARD_FAB2(SCH_1):GND
   H9  GND            GND<11>  @BASEBOARD_FAB2_LIB.BASEBOARD_FAB2(SCH_1):GND
   H8  GND            GND<10>  @BASEBOARD_FAB2_LIB.BASEBOARD_FAB2(SCH_1):GND
  F11  GND            GND<9>  @BASEBOARD_FAB2_LIB.BASEBOARD_FAB2(SCH_1):GND
   F6  GND            GND<8>  @BASEBOARD_FAB2_LIB.BASEBOARD_FAB2(SCH_1):GND
  E12  GND            GND<7>  @BASEBOARD_FAB2_LIB.BASEBOARD_FAB2(SCH_1):GND
   E5  GND            GND<6>  @BASEBOARD_FAB2_LIB.BASEBOARD_FAB2(SCH_1):GND
  D13  GND            GND<5>  @BASEBOARD_FAB2_LIB.BASEBOARD_FAB2(SCH_1):GND
   D4  GND            GND<4>  @BASEBOARD_FAB2_LIB.BASEBOARD_FAB2(SCH_1):GND
  C14  GND            GND<3>  @BASEBOARD_FAB2_LIB.BASEBOARD_FAB2(SCH_1):GND
   C3  GND            GND<2>  @BASEBOARD_FAB2_LIB.BASEBOARD_FAB2(SCH_1):GND
  B15  GND            GND<1>  @BASEBOARD_FAB2_LIB.BASEBOARD_FAB2(SCH_1):GND
   B2  GND            GND<0>  @BASEBOARD_FAB2_LIB.BASEBOARD_FAB2(SCH_1):GND

LCMXO2_A_256BGA  I59  U8D7   [LCMXO2_A_256BGA-IC,H63395-001]
  C13  TP_CPLD1_PT24D_DONE  PT24D_DONE  @BASEBOARD_FAB2_LIB.BASEBOARD_FAB2(SCH_1):TP_CPLD1_PT24D_DONE
  A13  TP_CPLD1_PT24C_INITN  PT24C_INITN  @BASEBOARD_FAB2_LIB.BASEBOARD_FAB2(SCH_1):TP_CPLD1_PT24C_INITN
  A15  TP_CPLD1_PT24B  PT24B  @BASEBOARD_FAB2_LIB.BASEBOARD_FAB2(SCH_1):TP_CPLD1_PT24B
  A14  TP_CPLD1_PT22D  PT22D  @BASEBOARD_FAB2_LIB.BASEBOARD_FAB2(SCH_1):TP_CPLD1_PT22D
  B13  TP_CPLD1_PT22C  PT22C  @BASEBOARD_FAB2_LIB.BASEBOARD_FAB2(SCH_1):TP_CPLD1_PT22C
  B10  TP_CPLD1_PT20D_PROGRAMN  PT20D_PROGRAMN  @BASEBOARD_FAB2_LIB.BASEBOARD_FAB2(SCH_1):TP_CPLD1_PT20D_PROGRAMN
  E10  TP_CPLD1_PT20B  PT20B  @BASEBOARD_FAB2_LIB.BASEBOARD_FAB2(SCH_1):TP_CPLD1_PT20B
  D10  TP_CPLD1_PT20A  PT20A  @BASEBOARD_FAB2_LIB.BASEBOARD_FAB2(SCH_1):TP_CPLD1_PT20A
  E11  TP_CPLD1_PT19D  PT19D  @BASEBOARD_FAB2_LIB.BASEBOARD_FAB2(SCH_1):TP_CPLD1_PT19D
   D8  TP_CPLD1_PT17C  PT17C  @BASEBOARD_FAB2_LIB.BASEBOARD_FAB2(SCH_1):TP_CPLD1_PT17C
   A8  TP_CPLD1_PT17B_PCLKC0_1  PT17B_PCLKC0_1  @BASEBOARD_FAB2_LIB.BASEBOARD_FAB2(SCH_1):TP_CPLD1_PT17B_PCLKC0_1
   E8  TP_CPLD1_PT16B  PT16B  @BASEBOARD_FAB2_LIB.BASEBOARD_FAB2(SCH_1):TP_CPLD1_PT16B
   B7  TP_CPLD1_PT13A  PT13A  @BASEBOARD_FAB2_LIB.BASEBOARD_FAB2(SCH_1):TP_CPLD1_PT13A
   B6  TP_CPLD1_PT11B  PT11B  @BASEBOARD_FAB2_LIB.BASEBOARD_FAB2(SCH_1):TP_CPLD1_PT11B
   A5  TP_CPLD1_PT11A  PT11A  @BASEBOARD_FAB2_LIB.BASEBOARD_FAB2(SCH_1):TP_CPLD1_PT11A
  J13  TP_CPLD1_PR9D   PR9D  @BASEBOARD_FAB2_LIB.BASEBOARD_FAB2(SCH_1):TP_CPLD1_PR9D
  H11  TP_CPLD1_PR9C   PR9C  @BASEBOARD_FAB2_LIB.BASEBOARD_FAB2(SCH_1):TP_CPLD1_PR9C
  J15  TP_CPLD1_PR9A   PR9A  @BASEBOARD_FAB2_LIB.BASEBOARD_FAB2(SCH_1):TP_CPLD1_PR9A
  J14  TP_CPLD1_PR7D   PR7D  @BASEBOARD_FAB2_LIB.BASEBOARD_FAB2(SCH_1):TP_CPLD1_PR7D
  J16  TP_CPLD1_PR7C   PR7C  @BASEBOARD_FAB2_LIB.BASEBOARD_FAB2(SCH_1):TP_CPLD1_PR7C
  H16  TP_CPLD1_PR7B_PCLKC1_0  PR7B_PCLKC1_0  @BASEBOARD_FAB2_LIB.BASEBOARD_FAB2(SCH_1):TP_CPLD1_PR7B_PCLKC1_0
  H14  TP_CPLD1_PR7A_PCLKT1_0  PR7A_PCLKT1_0  @BASEBOARD_FAB2_LIB.BASEBOARD_FAB2(SCH_1):TP_CPLD1_PR7A_PCLKT1_0
  L13  TP_CPLD1_PR12D  PR12D  @BASEBOARD_FAB2_LIB.BASEBOARD_FAB2(SCH_1):TP_CPLD1_PR12D
  L14  TP_CPLD1_PR11B  PR11B  @BASEBOARD_FAB2_LIB.BASEBOARD_FAB2(SCH_1):TP_CPLD1_PR11B
  J11  TP_CPLD1_PR10C  PR10C  @BASEBOARD_FAB2_LIB.BASEBOARD_FAB2(SCH_1):TP_CPLD1_PR10C
   C9  SMB_SENSOR_STBY_LVC3_SDA  PT18D_SDA_PCLKC0_0  @BASEBOARD_FAB2_LIB.BASEBOARD_FAB2(SCH_1):SMB_SENSOR_STBY_LVC3_SDA
   A9  SMB_SENSOR_STBY_LVC3_SCL  PT18C_SCL_PCLKT0_0  @BASEBOARD_FAB2_LIB.BASEBOARD_FAB2(SCH_1):SMB_SENSOR_STBY_LVC3_SCL
   F8  SGPIO_BMC_DIN_R  PT18A  @BASEBOARD_FAB2_LIB.BASEBOARD_FAB2(SCH_1):SGPIO_BMC_DIN_R
  E15  RST_PLTRST_N    PR1B  @BASEBOARD_FAB2_LIB.BASEBOARD_FAB2(SCH_1):RST_PLTRST_N
  K11  RST_PLTRST_BUF_N  PR12C  @BASEBOARD_FAB2_LIB.BASEBOARD_FAB2(SCH_1):RST_PLTRST_BUF_N
   D9  RST_PCIE_MIDPLANE_N  PT18B  @BASEBOARD_FAB2_LIB.BASEBOARD_FAB2(SCH_1):RST_PCIE_MIDPLANE_N
   D6  RST_PCIE_CPU_DEV0_N  PT12A  @BASEBOARD_FAB2_LIB.BASEBOARD_FAB2(SCH_1):RST_PCIE_CPU_DEV0_N
  F14  RST_BMC_SYSRST_BTN_OUT_B_N   PR4A  @BASEBOARD_FAB2_LIB.BASEBOARD_FAB2(SCH_1):RST_BMC_SYSRST_BTN_OUT_B_N
  D14  PWRGD_SYS_PWROK   PR1A  @BASEBOARD_FAB2_LIB.BASEBOARD_FAB2(SCH_1):PWRGD_SYS_PWROK
   B4  PWRGD_PVTT_CPU0  PT11D  @BASEBOARD_FAB2_LIB.BASEBOARD_FAB2(SCH_1):PWRGD_PVTT_CPU0
  L16  PWRGD_PVCCIO_CPU1  PR11A  @BASEBOARD_FAB2_LIB.BASEBOARD_FAB2(SCH_1):PWRGD_PVCCIO_CPU1
  C16  PWRGD_PCH_PWROK   PR2C  @BASEBOARD_FAB2_LIB.BASEBOARD_FAB2(SCH_1):PWRGD_PCH_PWROK
  L12  PWRGD_P3V3_STBY  PR10D  @BASEBOARD_FAB2_LIB.BASEBOARD_FAB2(SCH_1):PWRGD_P3V3_STBY
  D16  PWRGD_P1V8MCP_CPU1   PR2A  @BASEBOARD_FAB2_LIB.BASEBOARD_FAB2(SCH_1):PWRGD_P1V8MCP_CPU1
  D15  PWRGD_P1V8MCP_CPU0   PR2D  @BASEBOARD_FAB2_LIB.BASEBOARD_FAB2(SCH_1):PWRGD_P1V8MCP_CPU0
   E7  PWRGD_P1V26_BMC_STBY  PT12B  @BASEBOARD_FAB2_LIB.BASEBOARD_FAB2(SCH_1):PWRGD_P1V26_BMC_STBY
   B5  PWRGD_P12V_MAIN   PT9B  @BASEBOARD_FAB2_LIB.BASEBOARD_FAB2(SCH_1):PWRGD_P12V_MAIN
  B11  PWRGD_DSW_PWROK  PT22A  @BASEBOARD_FAB2_LIB.BASEBOARD_FAB2(SCH_1):PWRGD_DSW_PWROK
  F13  PWRGD_CPUPWRGD   PR3C  @BASEBOARD_FAB2_LIB.BASEBOARD_FAB2(SCH_1):PWRGD_CPUPWRGD
  A12  PU_THERMTRIP_FORCE_N  PT22B  @BASEBOARD_FAB2_LIB.BASEBOARD_FAB2(SCH_1):PU_THERMTRIP_FORCE_N
   B9  PU_RST_PERST_BIT1  PT19A  @BASEBOARD_FAB2_LIB.BASEBOARD_FAB2(SCH_1):PU_RST_PERST_BIT1
  K16  PU_FAB2_MARKER_CPLD   PR9B  @BASEBOARD_FAB2_LIB.BASEBOARD_FAB2(SCH_1):PU_FAB2_MARKER_CPLD
   B8  JTAG_PLD_TMS   PT16D_TMS  @BASEBOARD_FAB2_LIB.BASEBOARD_FAB2(SCH_1):JTAG_PLD_TMS
   C6  JTAG_PLD_TDO   PT12C_TDO  @BASEBOARD_FAB2_LIB.BASEBOARD_FAB2(SCH_1):JTAG_PLD_TDO
   A6  JTAG_PLD_TDI   PT12D_TDI  @BASEBOARD_FAB2_LIB.BASEBOARD_FAB2(SCH_1):JTAG_PLD_TDI
   A7  JTAG_PLD_TCK   PT16C_TCK  @BASEBOARD_FAB2_LIB.BASEBOARD_FAB2(SCH_1):JTAG_PLD_TCK
  G11  FM_WBG_PRSNT_N   PR5C  @BASEBOARD_FAB2_LIB.BASEBOARD_FAB2(SCH_1):FM_WBG_PRSNT_N
  G15  FM_UV_ADR_TRIGGER_N   PR5A  @BASEBOARD_FAB2_LIB.BASEBOARD_FAB2(SCH_1):FM_UV_ADR_TRIGGER_N
  H12  FM_UV_ADR_TRIGGER_EN   PR5D  @BASEBOARD_FAB2_LIB.BASEBOARD_FAB2(SCH_1):FM_UV_ADR_TRIGGER_EN
  L15  FM_THERMTRIP_DLY  PR12A  @BASEBOARD_FAB2_LIB.BASEBOARD_FAB2(SCH_1):FM_THERMTRIP_DLY
   E9  FM_SLP_SUS_N   PT17D  @BASEBOARD_FAB2_LIB.BASEBOARD_FAB2(SCH_1):FM_SLP_SUS_N
  C12  FM_SLPS4_N     PT23A  @BASEBOARD_FAB2_LIB.BASEBOARD_FAB2(SCH_1):FM_SLPS4_N
  B14  FM_SINT_PRSNT_N  PT24A  @BASEBOARD_FAB2_LIB.BASEBOARD_FAB2(SCH_1):FM_SINT_PRSNT_N
  P16  FM_PVPP_CPU1_EN  PR13D  @BASEBOARD_FAB2_LIB.BASEBOARD_FAB2(SCH_1):FM_PVPP_CPU1_EN
  P15  FM_PVPP_CPU0_EN  PR14C  @BASEBOARD_FAB2_LIB.BASEBOARD_FAB2(SCH_1):FM_PVPP_CPU0_EN
  H15  FM_PVDDQ_KLM_EN   PR6B  @BASEBOARD_FAB2_LIB.BASEBOARD_FAB2(SCH_1):FM_PVDDQ_KLM_EN
  H13  FM_PVDDQ_GHJ_EN   PR6C  @BASEBOARD_FAB2_LIB.BASEBOARD_FAB2(SCH_1):FM_PVDDQ_GHJ_EN
  K15  FM_PVDDQ_DEF_EN  PR10B  @BASEBOARD_FAB2_LIB.BASEBOARD_FAB2(SCH_1):FM_PVDDQ_DEF_EN
  K14  FM_PVDDQ_ABC_EN  PR10A  @BASEBOARD_FAB2_LIB.BASEBOARD_FAB2(SCH_1):FM_PVDDQ_ABC_EN
  N16  FM_PVCCIN_PVCCSA_CPU1_EN_LVC1  PR14A  @BASEBOARD_FAB2_LIB.BASEBOARD_FAB2(SCH_1):FM_PVCCIN_PVCCSA_CPU1_EN_LVC1
  A10  FM_PVCCIN_PVCCSA_CPU0_EN_LVC1  PT19B  @BASEBOARD_FAB2_LIB.BASEBOARD_FAB2(SCH_1):FM_PVCCIN_PVCCSA_CPU0_EN_LVC1
   F9  FM_PS_EN       PT19C  @BASEBOARD_FAB2_LIB.BASEBOARD_FAB2(SCH_1):FM_PS_EN
   F7  FM_PLD_DEBUG_MODE_N  PT16A  @BASEBOARD_FAB2_LIB.BASEBOARD_FAB2(SCH_1):FM_PLD_DEBUG_MODE_N
  B12  FM_PCH_PWRBTN_N  PT23B  @BASEBOARD_FAB2_LIB.BASEBOARD_FAB2(SCH_1):FM_PCH_PWRBTN_N
   A3  FM_PCH_PRSNT_N  PT11C  @BASEBOARD_FAB2_LIB.BASEBOARD_FAB2(SCH_1):FM_PCH_PRSNT_N
   A4  FM_P3V3_CPLD_EN  PT10A  @BASEBOARD_FAB2_LIB.BASEBOARD_FAB2(SCH_1):FM_P3V3_CPLD_EN
  F12  FM_P1V8MCP_CPU1_EN   PR4C  @BASEBOARD_FAB2_LIB.BASEBOARD_FAB2(SCH_1):FM_P1V8MCP_CPU1_EN
  E16  FM_P1V8MCP_CPU0_EN   PR3A  @BASEBOARD_FAB2_LIB.BASEBOARD_FAB2(SCH_1):FM_P1V8MCP_CPU0_EN
  R16  FM_P12V_MAIN_SW_EN  PR14D  @BASEBOARD_FAB2_LIB.BASEBOARD_FAB2(SCH_1):FM_P12V_MAIN_SW_EN
  K12  FM_MEM_THERM_EVENT_PCH_N  PR11D  @BASEBOARD_FAB2_LIB.BASEBOARD_FAB2(SCH_1):FM_MEM_THERM_EVENT_PCH_N
  K13  FM_MEM_THERM_EVENT_LVT3_N  PR11C  @BASEBOARD_FAB2_LIB.BASEBOARD_FAB2(SCH_1):FM_MEM_THERM_EVENT_LVT3_N
  C10  FM_JTAG_PLD_EN_DEBUG  PT20C_JTAGENB  @BASEBOARD_FAB2_LIB.BASEBOARD_FAB2(SCH_1):FM_JTAG_PLD_EN_DEBUG
   D7  FM_FORCE_ADR_N  PT13D  @BASEBOARD_FAB2_LIB.BASEBOARD_FAB2(SCH_1):FM_FORCE_ADR_N
  G16  FM_FAST_PROCHOT_THROTTLE_IN_N   PR6A  @BASEBOARD_FAB2_LIB.BASEBOARD_FAB2(SCH_1):FM_FAST_PROCHOT_THROTTLE_IN_N
  J12  FM_FAST_PROCHOT_THROTTLE_DLY_N   PR6D  @BASEBOARD_FAB2_LIB.BASEBOARD_FAB2(SCH_1):FM_FAST_PROCHOT_THROTTLE_DLY_N
  C15  FM_DB1200_PWRGD   PR1C  @BASEBOARD_FAB2_LIB.BASEBOARD_FAB2(SCH_1):FM_DB1200_PWRGD
   B3  FM_CTNR_PS_ON   PT9C  @BASEBOARD_FAB2_LIB.BASEBOARD_FAB2(SCH_1):FM_CTNR_PS_ON
  N14  FM_CPU1_VRM_OSC_EN  PR14B  @BASEBOARD_FAB2_LIB.BASEBOARD_FAB2(SCH_1):FM_CPU1_VRM_OSC_EN
  G14  FM_CPU1_THERMTRIP_LVT3_N   PR5B  @BASEBOARD_FAB2_LIB.BASEBOARD_FAB2(SCH_1):FM_CPU1_THERMTRIP_LVT3_N
   C5  FM_CPU1_THERMTRIP_LATCH_LVT3_N  PT10B  @BASEBOARD_FAB2_LIB.BASEBOARD_FAB2(SCH_1):FM_CPU1_THERMTRIP_LATCH_LVT3_N
  M14  FM_CPU1_PROC_ID1  PR13A  @BASEBOARD_FAB2_LIB.BASEBOARD_FAB2(SCH_1):FM_CPU1_PROC_ID1
  M15  FM_CPU1_PROC_ID0  PR13B  @BASEBOARD_FAB2_LIB.BASEBOARD_FAB2(SCH_1):FM_CPU1_PROC_ID0
  F16  FM_CPU1_MCP_CLK_EN_N   PR4B  @BASEBOARD_FAB2_LIB.BASEBOARD_FAB2(SCH_1):FM_CPU1_MCP_CLK_EN_N
   E6  FM_CPU1_FIVR_FAULT_LVT3_N  PT13C  @BASEBOARD_FAB2_LIB.BASEBOARD_FAB2(SCH_1):FM_CPU1_FIVR_FAULT_LVT3_N
  G13  FM_CPU1_FIVR_FAULT_LVT3   PR4D  @BASEBOARD_FAB2_LIB.BASEBOARD_FAB2(SCH_1):FM_CPU1_FIVR_FAULT_LVT3
  F10  FM_CPU1_CD_PRES  PT21C  @BASEBOARD_FAB2_LIB.BASEBOARD_FAB2(SCH_1):FM_CPU1_CD_PRES
  N15  FM_CPU0_THERMTRIP_LVT3_N  PR13C  @BASEBOARD_FAB2_LIB.BASEBOARD_FAB2(SCH_1):FM_CPU0_THERMTRIP_LVT3_N
  G12  FM_CPU0_THERMTRIP_LATCH_LVT3_N   PR3D  @BASEBOARD_FAB2_LIB.BASEBOARD_FAB2(SCH_1):FM_CPU0_THERMTRIP_LATCH_LVT3_N
  A11  FM_CPU0_OR_CPU1_MCP_PRES  PT21A  @BASEBOARD_FAB2_LIB.BASEBOARD_FAB2(SCH_1):FM_CPU0_OR_CPU1_MCP_PRES
  F15  FM_CPU0_MCP_CLK_EN_N   PR3B  @BASEBOARD_FAB2_LIB.BASEBOARD_FAB2(SCH_1):FM_CPU0_MCP_CLK_EN_N
  M16  FM_CPU0_FIVR_FAULT_LVT3  PR12B  @BASEBOARD_FAB2_LIB.BASEBOARD_FAB2(SCH_1):FM_CPU0_FIVR_FAULT_LVT3
  C11  FM_CPU0_CD_PRES  PT21B  @BASEBOARD_FAB2_LIB.BASEBOARD_FAB2(SCH_1):FM_CPU0_CD_PRES
  D11  FM_CPU0_AND_CPU1_MCP_PRES  PT21D  @BASEBOARD_FAB2_LIB.BASEBOARD_FAB2(SCH_1):FM_CPU0_AND_CPU1_MCP_PRES
  E14  FM_CPLD_ADR_TRIGGER_N   PR2B  @BASEBOARD_FAB2_LIB.BASEBOARD_FAB2(SCH_1):FM_CPLD_ADR_TRIGGER_N
   C7  FM_BMC_ONCTL_N  PT13B  @BASEBOARD_FAB2_LIB.BASEBOARD_FAB2(SCH_1):FM_BMC_ONCTL_N
   C4  FM_ADR_SMI_GPIO_R_N   PT9A  @BASEBOARD_FAB2_LIB.BASEBOARD_FAB2(SCH_1):FM_ADR_SMI_GPIO_R_N
  B16  FM_ADR_COMPLETE_DLY   PR1D  @BASEBOARD_FAB2_LIB.BASEBOARD_FAB2(SCH_1):FM_ADR_COMPLETE_DLY
   C8  FM_ADR_COMPLETE  PT17A_PCLKT0_1  @BASEBOARD_FAB2_LIB.BASEBOARD_FAB2(SCH_1):FM_ADR_COMPLETE

LCMXO2_A_256BGA  I179  U8D7   [LCMXO2_A_256BGA-IC,H63395-001]
  N11  XDP_SYSPWROK   PB21D  @BASEBOARD_FAB2_LIB.BASEBOARD_FAB2(SCH_1):XDP_SYSPWROK
  M11  XDP_PWRGD_RST_N  PB19D  @BASEBOARD_FAB2_LIB.BASEBOARD_FAB2(SCH_1):XDP_PWRGD_RST_N
   K6  UART_BMC_TXD5  PL10D  @BASEBOARD_FAB2_LIB.BASEBOARD_FAB2(SCH_1):UART_BMC_TXD5
   J5  UART_BMC_RXD5  PL10C  @BASEBOARD_FAB2_LIB.BASEBOARD_FAB2(SCH_1):UART_BMC_RXD5
   J3  TP_CPLD1_PL7D_PCLKT4_0  PL7D_PCLKC4_0  @BASEBOARD_FAB2_LIB.BASEBOARD_FAB2(SCH_1):TP_CPLD1_PL7D_PCLKT4_0
   E3  TP_CPLD1_PL2B_L_GPLLC_IN  PL2B_L_GPLLC_IN  @BASEBOARD_FAB2_LIB.BASEBOARD_FAB2(SCH_1):TP_CPLD1_PL2B_L_GPLLC_IN
   D1  TP_CPLD1_PL1B_L_GPLLC_FB  PL1B_L_GPLLC_FB  @BASEBOARD_FAB2_LIB.BASEBOARD_FAB2(SCH_1):TP_CPLD1_PL1B_L_GPLLC_FB
   D3  TP_CPLD1_PL1A_L_GPLLT_FB  PL1A_L_GPLLT_FB  @BASEBOARD_FAB2_LIB.BASEBOARD_FAB2(SCH_1):TP_CPLD1_PL1A_L_GPLLT_FB
   L3  TP_CPLD1_PL11A  PL11B  @BASEBOARD_FAB2_LIB.BASEBOARD_FAB2(SCH_1):TP_CPLD1_PL11A
   L7  TP_CPLD1_PB8D   PB8D  @BASEBOARD_FAB2_LIB.BASEBOARD_FAB2(SCH_1):TP_CPLD1_PB8D
   T6  TP_CPLD1_PB8B_SO_SPISO  PB8B_SO_SPISO  @BASEBOARD_FAB2_LIB.BASEBOARD_FAB2(SCH_1):TP_CPLD1_PB8B_SO_SPISO
   P6  TP_CPLD1_PB8A_MCLK_CCLK  PB8A_MCLK_CCLK  @BASEBOARD_FAB2_LIB.BASEBOARD_FAB2(SCH_1):TP_CPLD1_PB8A_MCLK_CCLK
   R5  TP_CPLD1_PB5A_CSSPIN  PB5A_CSSPIN  @BASEBOARD_FAB2_LIB.BASEBOARD_FAB2(SCH_1):TP_CPLD1_PB5A_CSSPIN
  P13  TP_CPLD1_PB25B_SI_SISPI  PB25B_SI_SISPI  @BASEBOARD_FAB2_LIB.BASEBOARD_FAB2(SCH_1):TP_CPLD1_PB25B_SI_SISPI
   P9  TP_CPLD1_PB16B_PCLKC2_1  PB16B_PCLKC2_1  @BASEBOARD_FAB2_LIB.BASEBOARD_FAB2(SCH_1):TP_CPLD1_PB16B_PCLKC2_1
   T9  TP_CPLD1_PB16A_PCLKT2_1  PB16A_PCLKT2_1  @BASEBOARD_FAB2_LIB.BASEBOARD_FAB2(SCH_1):TP_CPLD1_PB16A_PCLKT2_1
   R8  TP_CPLD1_PB11B_PCLKC2_0  PB11B_PCLKC2_0  @BASEBOARD_FAB2_LIB.BASEBOARD_FAB2(SCH_1):TP_CPLD1_PB11B_PCLKC2_0
   K2  SP1_BMC_HOST_UART_TX  PL10B  @BASEBOARD_FAB2_LIB.BASEBOARD_FAB2(SCH_1):SP1_BMC_HOST_UART_TX
   K3  SP1_BMC_HOST_UART_RX  PL10A  @BASEBOARD_FAB2_LIB.BASEBOARD_FAB2(SCH_1):SP1_BMC_HOST_UART_RX
   J4  SMB_SLOTX24_PCH_STBY_LVC3_SDA   PL9D  @BASEBOARD_FAB2_LIB.BASEBOARD_FAB2(SCH_1):SMB_SLOTX24_PCH_STBY_LVC3_SDA
   H5  SMB_SLOTX24_PCH_STBY_LVC3_SCL   PL9C  @BASEBOARD_FAB2_LIB.BASEBOARD_FAB2(SCH_1):SMB_SLOTX24_PCH_STBY_LVC3_SCL
   K4  SGPIO_BMC_LD_N  PL11C  @BASEBOARD_FAB2_LIB.BASEBOARD_FAB2(SCH_1):SGPIO_BMC_LD_N
   J2  SGPIO_BMC_DOUT   PL9A  @BASEBOARD_FAB2_LIB.BASEBOARD_FAB2(SCH_1):SGPIO_BMC_DOUT
   J1  SGPIO_BMC_CLK  PL7C_PCLKT4_0  @BASEBOARD_FAB2_LIB.BASEBOARD_FAB2(SCH_1):SGPIO_BMC_CLK
   G4  RST_RSMRST_R_N   PL4D  @BASEBOARD_FAB2_LIB.BASEBOARD_FAB2(SCH_1):RST_RSMRST_R_N
   M1  RST_RSMRST_DLY  PL12B_PCLKC3_0  @BASEBOARD_FAB2_LIB.BASEBOARD_FAB2(SCH_1):RST_RSMRST_DLY
   M3  RST_PCIE_RISER1_PERST_N  PL13A  @BASEBOARD_FAB2_LIB.BASEBOARD_FAB2(SCH_1):RST_PCIE_RISER1_PERST_N
   B1  RST_PCIE_PCH_PERST_N   PL1C  @BASEBOARD_FAB2_LIB.BASEBOARD_FAB2(SCH_1):RST_PCIE_PCH_PERST_N
   R6  RST_PCIE_M2_DEV_N   PB6B  @BASEBOARD_FAB2_LIB.BASEBOARD_FAB2(SCH_1):RST_PCIE_M2_DEV_N
   H1  RST_PCIE_CPU_DEV3_N   PL7B  @BASEBOARD_FAB2_LIB.BASEBOARD_FAB2(SCH_1):RST_PCIE_CPU_DEV3_N
   H3  RST_PCIE_CPU_DEV2_N   PL7A  @BASEBOARD_FAB2_LIB.BASEBOARD_FAB2(SCH_1):RST_PCIE_CPU_DEV2_N
   C1  RST_PCIE_CPU_DEV1_N   PL2C  @BASEBOARD_FAB2_LIB.BASEBOARD_FAB2(SCH_1):RST_PCIE_CPU_DEV1_N
  N10  RST_CPU1_LVC3_R1_N  PB19C  @BASEBOARD_FAB2_LIB.BASEBOARD_FAB2(SCH_1):RST_CPU1_LVC3_R1_N
  R10  RST_CPU0_LVC3_R1_N  PB19B  @BASEBOARD_FAB2_LIB.BASEBOARD_FAB2(SCH_1):RST_CPU0_LVC3_R1_N
  P10  RST_CD_CPU1_POR_N  PB19A  @BASEBOARD_FAB2_LIB.BASEBOARD_FAB2(SCH_1):RST_CD_CPU1_POR_N
   N3  RST_CD_CPU0_POR_N  PL14B  @BASEBOARD_FAB2_LIB.BASEBOARD_FAB2(SCH_1):RST_CD_CPU0_POR_N
   R7  PWRGD_PVTT_CPU1   PB9A  @BASEBOARD_FAB2_LIB.BASEBOARD_FAB2(SCH_1):PWRGD_PVTT_CPU1
   T4  PWRGD_PVSA_CPU1   PB3B  @BASEBOARD_FAB2_LIB.BASEBOARD_FAB2(SCH_1):PWRGD_PVSA_CPU1
   L1  PWRGD_PVSA_CPU0  PL11A  @BASEBOARD_FAB2_LIB.BASEBOARD_FAB2(SCH_1):PWRGD_PVSA_CPU0
   N2  PWRGD_PVPP_KLM  PL13C  @BASEBOARD_FAB2_LIB.BASEBOARD_FAB2(SCH_1):PWRGD_PVPP_KLM
   M2  PWRGD_PVPP_GHJ  PL14A  @BASEBOARD_FAB2_LIB.BASEBOARD_FAB2(SCH_1):PWRGD_PVPP_GHJ
   M6  PWRGD_PVPP_DEF  PB11C  @BASEBOARD_FAB2_LIB.BASEBOARD_FAB2(SCH_1):PWRGD_PVPP_DEF
   N7  PWRGD_PVPP_ABC   PB9D  @BASEBOARD_FAB2_LIB.BASEBOARD_FAB2(SCH_1):PWRGD_PVPP_ABC
   P8  PWRGD_PVNN_P1V05_PCH  PB12A  @BASEBOARD_FAB2_LIB.BASEBOARD_FAB2(SCH_1):PWRGD_PVNN_P1V05_PCH
   L4  PWRGD_PVCCMCP_CPU1  PL12D  @BASEBOARD_FAB2_LIB.BASEBOARD_FAB2(SCH_1):PWRGD_PVCCMCP_CPU1
   P5  PWRGD_PVCCMCP_CPU0   PB5B  @BASEBOARD_FAB2_LIB.BASEBOARD_FAB2(SCH_1):PWRGD_PVCCMCP_CPU0
   L8  PWRGD_PVCCIO_CPU0  PB11D  @BASEBOARD_FAB2_LIB.BASEBOARD_FAB2(SCH_1):PWRGD_PVCCIO_CPU0
   T5  PWRGD_PVCCIOMCP_CPU1   PB6A  @BASEBOARD_FAB2_LIB.BASEBOARD_FAB2(SCH_1):PWRGD_PVCCIOMCP_CPU1
   N6  PWRGD_PVCCIOMCP_CPU0   PB8C  @BASEBOARD_FAB2_LIB.BASEBOARD_FAB2(SCH_1):PWRGD_PVCCIOMCP_CPU0
   N1  PWRGD_PVCCIN_CPU1  PL13B  @BASEBOARD_FAB2_LIB.BASEBOARD_FAB2(SCH_1):PWRGD_PVCCIN_CPU1
   K5  PWRGD_PVCCIN_CPU0  PL12C  @BASEBOARD_FAB2_LIB.BASEBOARD_FAB2(SCH_1):PWRGD_PVCCIN_CPU0
   J6  PWRGD_P5V       PL6D  @BASEBOARD_FAB2_LIB.BASEBOARD_FAB2(SCH_1):PWRGD_P5V
   H6  PWRGD_P3V3      PL5D  @BASEBOARD_FAB2_LIB.BASEBOARD_FAB2(SCH_1):PWRGD_P3V3
  T15  PWRGD_DRAMPWRGD  PB25C  @BASEBOARD_FAB2_LIB.BASEBOARD_FAB2(SCH_1):PWRGD_DRAMPWRGD
  M10  PWRGD_CPU1_LVC3  PB21C  @BASEBOARD_FAB2_LIB.BASEBOARD_FAB2(SCH_1):PWRGD_CPU1_LVC3
   L5  PWRGD_CPU0_LVC3  PL11D  @BASEBOARD_FAB2_LIB.BASEBOARD_FAB2(SCH_1):PWRGD_CPU0_LVC3
   F4  PU_RST_PERST_BIT0   PL3C  @BASEBOARD_FAB2_LIB.BASEBOARD_FAB2(SCH_1):PU_RST_PERST_BIT0
   P2  FM_UART_ALERT_N  PL14D  @BASEBOARD_FAB2_LIB.BASEBOARD_FAB2(SCH_1):FM_UART_ALERT_N
  P11  FM_UARTSW_MSB_N  PB21B  @BASEBOARD_FAB2_LIB.BASEBOARD_FAB2(SCH_1):FM_UARTSW_MSB_N
   R9  FM_UARTSW_LSB_N  PB18A  @BASEBOARD_FAB2_LIB.BASEBOARD_FAB2(SCH_1):FM_UARTSW_LSB_N
  L10  FM_SOL_UART_CH_SEL  PB18D  @BASEBOARD_FAB2_LIB.BASEBOARD_FAB2(SCH_1):FM_SOL_UART_CH_SEL
   G1  FM_SLPS3_N      PL6A  @BASEBOARD_FAB2_LIB.BASEBOARD_FAB2(SCH_1):FM_SLPS3_N
   G6  FM_PWR_BTN_N    PL3D  @BASEBOARD_FAB2_LIB.BASEBOARD_FAB2(SCH_1):FM_PWR_BTN_N
   M8  FM_PVCCMCP_CPU1_EN  PB16C  @BASEBOARD_FAB2_LIB.BASEBOARD_FAB2(SCH_1):FM_PVCCMCP_CPU1_EN
   H2  FM_PVCCMCP_CPU0_EN   PL6B  @BASEBOARD_FAB2_LIB.BASEBOARD_FAB2(SCH_1):FM_PVCCMCP_CPU0_EN
   T7  FM_PVCCIO_CPU1_EN  PB11A_PCLKT2_0  @BASEBOARD_FAB2_LIB.BASEBOARD_FAB2(SCH_1):FM_PVCCIO_CPU1_EN
   M7  FM_PVCCIO_CPU0_EN   PB9C  @BASEBOARD_FAB2_LIB.BASEBOARD_FAB2(SCH_1):FM_PVCCIO_CPU0_EN
   P7  FM_PVCCIOMCP_CPU1_EN   PB9B  @BASEBOARD_FAB2_LIB.BASEBOARD_FAB2(SCH_1):FM_PVCCIOMCP_CPU1_EN
   K1  FM_PVCCIOMCP_CPU0_EN   PL9B  @BASEBOARD_FAB2_LIB.BASEBOARD_FAB2(SCH_1):FM_PVCCIOMCP_CPU0_EN
   C2  FM_PCH_PLD_DATA   PL1D  @BASEBOARD_FAB2_LIB.BASEBOARD_FAB2(SCH_1):FM_PCH_PLD_DATA
   H4  FM_MP_PS_FAIL_N   PL6C  @BASEBOARD_FAB2_LIB.BASEBOARD_FAB2(SCH_1):FM_MP_PS_FAIL_N
   D2  FM_MEM_EVENT_FUNC   PL2D  @BASEBOARD_FAB2_LIB.BASEBOARD_FAB2(SCH_1):FM_MEM_EVENT_FUNC
   L9  FM_IE_DISABLE_N  PB12D  @BASEBOARD_FAB2_LIB.BASEBOARD_FAB2(SCH_1):FM_IE_DISABLE_N
   P1  FM_GLOBAL_RST_WARN_N  PL13D  @BASEBOARD_FAB2_LIB.BASEBOARD_FAB2(SCH_1):FM_GLOBAL_RST_WARN_N
   T3  FM_DIS_ADR_DLY   PB6C  @BASEBOARD_FAB2_LIB.BASEBOARD_FAB2(SCH_1):FM_DIS_ADR_DLY
   G5  FM_DEBUG_RST_BTN_N   PL4C  @BASEBOARD_FAB2_LIB.BASEBOARD_FAB2(SCH_1):FM_DEBUG_RST_BTN_N
  R11  FM_DB1200ZL_BCLKS_EN_N  PB22A  @BASEBOARD_FAB2_LIB.BASEBOARD_FAB2(SCH_1):FM_DB1200ZL_BCLKS_EN_N
  T13  FM_CPU_MSMI_LVT3_N  PB24B  @BASEBOARD_FAB2_LIB.BASEBOARD_FAB2(SCH_1):FM_CPU_MSMI_LVT3_N
  R14  FM_CPU_CATERR_LVT3_N  PB25D  @BASEBOARD_FAB2_LIB.BASEBOARD_FAB2(SCH_1):FM_CPU_CATERR_LVT3_N
   E2  FM_CPU_CATERR_DLY_LVT3_N  PL2A_L_GPLLT_IN  @BASEBOARD_FAB2_LIB.BASEBOARD_FAB2(SCH_1):FM_CPU_CATERR_DLY_LVT3_N
  T12  FM_CPU1_SKTOCC_LVT3_N  PB22B  @BASEBOARD_FAB2_LIB.BASEBOARD_FAB2(SCH_1):FM_CPU1_SKTOCC_LVT3_N
   P4  FM_CPU1_RC_EN   PB3A  @BASEBOARD_FAB2_LIB.BASEBOARD_FAB2(SCH_1):FM_CPU1_RC_EN
  T11  FM_CPU1_PKGID2  PB21A  @BASEBOARD_FAB2_LIB.BASEBOARD_FAB2(SCH_1):FM_CPU1_PKGID2
  P12  FM_CPU1_PKGID1  PB24A  @BASEBOARD_FAB2_LIB.BASEBOARD_FAB2(SCH_1):FM_CPU1_PKGID1
  R12  FM_CPU1_PKGID0  PB25A_SN  @BASEBOARD_FAB2_LIB.BASEBOARD_FAB2(SCH_1):FM_CPU1_PKGID0
  R13  FM_CPU0_VRM_OSC_EN  PB22C  @BASEBOARD_FAB2_LIB.BASEBOARD_FAB2(SCH_1):FM_CPU0_VRM_OSC_EN
  T14  FM_CPU0_SKTOCC_LVT3_N  PB22D  @BASEBOARD_FAB2_LIB.BASEBOARD_FAB2(SCH_1):FM_CPU0_SKTOCC_LVT3_N
   R3  FM_CPU0_RC_EN   PB3D  @BASEBOARD_FAB2_LIB.BASEBOARD_FAB2(SCH_1):FM_CPU0_RC_EN
   F3  FM_CPU0_PROC_ID1   PL4A  @BASEBOARD_FAB2_LIB.BASEBOARD_FAB2(SCH_1):FM_CPU0_PROC_ID1
   F1  FM_CPU0_PROC_ID0   PL4B  @BASEBOARD_FAB2_LIB.BASEBOARD_FAB2(SCH_1):FM_CPU0_PROC_ID0
   G2  FM_CPU0_PKGID2   PL5A  @BASEBOARD_FAB2_LIB.BASEBOARD_FAB2(SCH_1):FM_CPU0_PKGID2
   G3  FM_CPU0_PKGID1   PL5B  @BASEBOARD_FAB2_LIB.BASEBOARD_FAB2(SCH_1):FM_CPU0_PKGID1
   F2  FM_CPU0_PKGID0  PL3B_PCLKC5_0  @BASEBOARD_FAB2_LIB.BASEBOARD_FAB2(SCH_1):FM_CPU0_PKGID0
   F5  FM_CPU0_FIVR_FAULT_LVT3_N   PL5C  @BASEBOARD_FAB2_LIB.BASEBOARD_FAB2(SCH_1):FM_CPU0_FIVR_FAULT_LVT3_N
   M9  FM_CPLD_UART_CH_LOCK_N  PB18C  @BASEBOARD_FAB2_LIB.BASEBOARD_FAB2(SCH_1):FM_CPLD_UART_CH_LOCK_N
   T8  FM_CPLD_DBG_PWR_EN_N  PB12B  @BASEBOARD_FAB2_LIB.BASEBOARD_FAB2(SCH_1):FM_CPLD_DBG_PWR_EN_N
   N9  FM_CPLD_BMC_PWRDN_N  PB16D  @BASEBOARD_FAB2_LIB.BASEBOARD_FAB2(SCH_1):FM_CPLD_BMC_PWRDN_N
   R4  FM_BMC_CPLD_MP_RST_N   PB6D  @BASEBOARD_FAB2_LIB.BASEBOARD_FAB2(SCH_1):FM_BMC_CPLD_MP_RST_N
   R1  FM_BMC_CPLD_GPO  PL14C  @BASEBOARD_FAB2_LIB.BASEBOARD_FAB2(SCH_1):FM_BMC_CPLD_GPO
   T2  FM_ADR_MODE_SEL   PB3C  @BASEBOARD_FAB2_LIB.BASEBOARD_FAB2(SCH_1):FM_ADR_MODE_SEL
   N8  FM_156M_CPU1_BRD_OSC_EN  PB12C  @BASEBOARD_FAB2_LIB.BASEBOARD_FAB2(SCH_1):FM_156M_CPU1_BRD_OSC_EN
  T10  FM_156M_CPU0_BRD_OSC_EN  PB18B  @BASEBOARD_FAB2_LIB.BASEBOARD_FAB2(SCH_1):FM_156M_CPU0_BRD_OSC_EN
   E1  CLK_32K_SUSCLK_PLD  PL3A_PCLKT5_0  @BASEBOARD_FAB2_LIB.BASEBOARD_FAB2(SCH_1):CLK_32K_SUSCLK_PLD
   L2  CLK_25M_CPLD   PL12A_PCLKT3_0  @BASEBOARD_FAB2_LIB.BASEBOARD_FAB2(SCH_1):CLK_25M_CPLD

TPS3700_SM  I104  U8D8   [TPS3700_SM-IC,H69492-001]
    1  PWRGD_P5V_N     OUTB  @BASEBOARD_FAB2_LIB.BASEBOARD_FAB2(SCH_1):PWRGD_P5V_N
    6  PWRGD_P12V_MAIN_R   OUTA  @BASEBOARD_FAB2_LIB.BASEBOARD_FAB2(SCH_1):PWRGD_P12V_MAIN_R
    2  P3V3_STBY        VDD  @BASEBOARD_FAB2_LIB.BASEBOARD_FAB2(SCH_1):P3V3_STBY
    5  GND              GND  @BASEBOARD_FAB2_LIB.BASEBOARD_FAB2(SCH_1):GND
    3  A_PG_P5V        INBN  @BASEBOARD_FAB2_LIB.BASEBOARD_FAB2(SCH_1):A_PG_P5V
    4  A_PG_P12V_MAIN   INAP  @BASEBOARD_FAB2_LIB.BASEBOARD_FAB2(SCH_1):A_PG_P12V_MAIN

TTL08_QFN15  I10  U8E1   [TTL08_QFN15-74LVC08A,IC,D90404B]
    1  IRQ_FORCE_NM_THROTTLE_N   A<0>  @BASEBOARD_FAB2_LIB.BASEBOARD_FAB2(SCH_1):IRQ_FORCE_NM_THROTTLE_N
    2  FM_OC_DETECT_N   B<0>  @BASEBOARD_FAB2_LIB.BASEBOARD_FAB2(SCH_1):FM_OC_DETECT_N
    3  FM_FAST_PROCHOT_AND_OUT_0_N   Y<0>  @BASEBOARD_FAB2_LIB.BASEBOARD_FAB2(SCH_1):FM_FAST_PROCHOT_AND_OUT_0_N

TTL08_QFN15  I11  U8E1   [TTL08_QFN15-74LVC08A,IC,D90404B]
    4  IRQ_UV_DETECT_N   A<0>  @BASEBOARD_FAB2_LIB.BASEBOARD_FAB2(SCH_1):IRQ_UV_DETECT_N
    5  FM_HSC_TIMER_EXP_N   B<0>  @BASEBOARD_FAB2_LIB.BASEBOARD_FAB2(SCH_1):FM_HSC_TIMER_EXP_N
    6  FM_FAST_PROCHOT_AND_OUT_1_N   Y<0>  @BASEBOARD_FAB2_LIB.BASEBOARD_FAB2(SCH_1):FM_FAST_PROCHOT_AND_OUT_1_N

TTL08_QFN15  I243  U8E1   [TTL08_QFN15-74LVC08A,IC,D90404B]
   10  PWRGD_P12V_HSC_DLY   B<0>  @BASEBOARD_FAB2_LIB.BASEBOARD_FAB2(SCH_1):PWRGD_P12V_HSC_DLY
    9  FM_PS_EN        A<0>  @BASEBOARD_FAB2_LIB.BASEBOARD_FAB2(SCH_1):FM_PS_EN
    8  FM_CTNR_PS_ON_R   Y<0>  @BASEBOARD_FAB2_LIB.BASEBOARD_FAB2(SCH_1):FM_CTNR_PS_ON_R

TTL08_QFN15  I12  U8E1   [TTL08_QFN15-74LVC08A,IC,D90404B]
   11  FM_FAST_PROCHOT_THROTTLE_IN_N   Y<0>  @BASEBOARD_FAB2_LIB.BASEBOARD_FAB2(SCH_1):FM_FAST_PROCHOT_THROTTLE_IN_N
   13  FM_FAST_PROCHOT_AND_OUT_1_N   B<0>  @BASEBOARD_FAB2_LIB.BASEBOARD_FAB2(SCH_1):FM_FAST_PROCHOT_AND_OUT_1_N
   12  FM_FAST_PROCHOT_AND_OUT_0_N   A<0>  @BASEBOARD_FAB2_LIB.BASEBOARD_FAB2(SCH_1):FM_FAST_PROCHOT_AND_OUT_0_N

ADM809  I89  U8E2   [ADM809_SMLF-IC,D23047-001-GND=A]
    2  PWRGD_P12V_HSC_DLY_R  RESET_N  @BASEBOARD_FAB2_LIB.BASEBOARD_FAB2(SCH_1):PWRGD_P12V_HSC_DLY_R
    3  PWRGD_P12V_HSC    VCC  @BASEBOARD_FAB2_LIB.BASEBOARD_FAB2(SCH_1):PWRGD_P12V_HSC

TTL1G126_A_SOT  I130  U8E3   [TTL1G126_A_SOT-74HC1G126,IC,A7B]
    1  RST_PLTRST_TOP_SWAP     OE  @BASEBOARD_FAB2_LIB.BASEBOARD_FAB2(SCH_1):RST_PLTRST_TOP_SWAP
    4  FM_BIOS_TOP_SWAP_SPKR_R      Y  @BASEBOARD_FAB2_LIB.BASEBOARD_FAB2(SCH_1):FM_BIOS_TOP_SWAP_SPKR_R
    2  FM_BIOS_TOP_SWAP      A  @BASEBOARD_FAB2_LIB.BASEBOARD_FAB2(SCH_1):FM_BIOS_TOP_SWAP

TTL1G126_A_SOT  I1   U8E4   [TTL1G126_A_SOT-74HC1G126,IC,A7B]
    1  PU_TRI_STATE_EN     OE  @BASEBOARD_FAB2_LIB.BASEBOARD_FAB2(SCH_1):PU_TRI_STATE_EN
    4  IRQ_LVC3_WAKE_R_N      Y  @BASEBOARD_FAB2_LIB.BASEBOARD_FAB2(SCH_1):IRQ_LVC3_WAKE_R_N
    2  FM_ALL_WAKE_N      A  @BASEBOARD_FAB2_LIB.BASEBOARD_FAB2(SCH_1):FM_ALL_WAKE_N

PI3B3257A_TSSOPLF  I74  U8F1   [PI3B3257A_TSSOPLF-IC,E16801-001]
    7  SPI_SWITCH_MOSI     YB  @BASEBOARD_FAB2_LIB.BASEBOARD_FAB2(SCH_1):SPI_SWITCH_MOSI
   12  SPI_SWITCH_MISO     YD  @BASEBOARD_FAB2_LIB.BASEBOARD_FAB2(SCH_1):SPI_SWITCH_MISO
    9  SPI_SWITCH_CS0_N     YC  @BASEBOARD_FAB2_LIB.BASEBOARD_FAB2(SCH_1):SPI_SWITCH_CS0_N
    4  SPI_SWITCH_CLK     YA  @BASEBOARD_FAB2_LIB.BASEBOARD_FAB2(SCH_1):SPI_SWITCH_CLK
    5  SPI_PCH_MOSI     IB0  @BASEBOARD_FAB2_LIB.BASEBOARD_FAB2(SCH_1):SPI_PCH_MOSI
   14  SPI_PCH_MISO_R    ID0  @BASEBOARD_FAB2_LIB.BASEBOARD_FAB2(SCH_1):SPI_PCH_MISO_R
   11  SPI_PCH_CS0_N    IC0  @BASEBOARD_FAB2_LIB.BASEBOARD_FAB2(SCH_1):SPI_PCH_CS0_N
    2  SPI_PCH_CLK      IA0  @BASEBOARD_FAB2_LIB.BASEBOARD_FAB2(SCH_1):SPI_PCH_CLK
    6  SPI_BMC_DO       IB1  @BASEBOARD_FAB2_LIB.BASEBOARD_FAB2(SCH_1):SPI_BMC_DO
   13  SPI_BMC_DI       ID1  @BASEBOARD_FAB2_LIB.BASEBOARD_FAB2(SCH_1):SPI_BMC_DI
   10  SPI_BMC_CS0_N    IC1  @BASEBOARD_FAB2_LIB.BASEBOARD_FAB2(SCH_1):SPI_BMC_CS0_N
    3  SPI_BMC_CLK      IA1  @BASEBOARD_FAB2_LIB.BASEBOARD_FAB2(SCH_1):SPI_BMC_CLK
   16  P3V3_STBY        VCC  @BASEBOARD_FAB2_LIB.BASEBOARD_FAB2(SCH_1):P3V3_STBY
    8  GND              GND  @BASEBOARD_FAB2_LIB.BASEBOARD_FAB2(SCH_1):GND
   15  GND               EN  @BASEBOARD_FAB2_LIB.BASEBOARD_FAB2(SCH_1):GND
    1  FM_BIOS_SPI_BMC_CTRL      S  @BASEBOARD_FAB2_LIB.BASEBOARD_FAB2(SCH_1):FM_BIOS_SPI_BMC_CTRL

W25Q128_SKT16  I32  U8F2   [W25Q128_SKT16-IC,H12709-001]
   14  TP_SPI_2_6     NC<6>  @BASEBOARD_FAB2_LIB.BASEBOARD_FAB2(SCH_1):TP_SPI_2_6
   13  TP_SPI_2_5     NC<5>  @BASEBOARD_FAB2_LIB.BASEBOARD_FAB2(SCH_1):TP_SPI_2_5
   12  TP_SPI_2_4     NC<4>  @BASEBOARD_FAB2_LIB.BASEBOARD_FAB2(SCH_1):TP_SPI_2_4
   11  TP_SPI_2_3     NC<3>  @BASEBOARD_FAB2_LIB.BASEBOARD_FAB2(SCH_1):TP_SPI_2_3
    6  TP_SPI_2_2     NC<2>  @BASEBOARD_FAB2_LIB.BASEBOARD_FAB2(SCH_1):TP_SPI_2_2
    5  TP_SPI_2_1     NC<1>  @BASEBOARD_FAB2_LIB.BASEBOARD_FAB2(SCH_1):TP_SPI_2_1
    4  TP_SPI_2_0     NC<0>  @BASEBOARD_FAB2_LIB.BASEBOARD_FAB2(SCH_1):TP_SPI_2_0
   15  SPI_BMC_BT_DO  DI_IO<0>  @BASEBOARD_FAB2_LIB.BASEBOARD_FAB2(SCH_1):SPI_BMC_BT_DO
    8  SPI_BMC_BT_DI_R  DO_IO<1>  @BASEBOARD_FAB2_LIB.BASEBOARD_FAB2(SCH_1):SPI_BMC_BT_DI_R
    7  SPI_BMC_BT_CS_N   CS_N  @BASEBOARD_FAB2_LIB.BASEBOARD_FAB2(SCH_1):SPI_BMC_BT_CS_N
   16  SPI_BMC_BT_CLK    CLK  @BASEBOARD_FAB2_LIB.BASEBOARD_FAB2(SCH_1):SPI_BMC_BT_CLK
    3  PU_SPI_FLASH_RESET_2_N  RESET_N  @BASEBOARD_FAB2_LIB.BASEBOARD_FAB2(SCH_1):PU_SPI_FLASH_RESET_2_N
    9  PU_SPI_BMC_BT_WP_N  WP_N_IO<2>  @BASEBOARD_FAB2_LIB.BASEBOARD_FAB2(SCH_1):PU_SPI_BMC_BT_WP_N
    1  PU_SPI_BMC_BT_HOLD_N  HOLD_N_IO<3>  @BASEBOARD_FAB2_LIB.BASEBOARD_FAB2(SCH_1):PU_SPI_BMC_BT_HOLD_N
    2  P3V3_STBY        VCC  @BASEBOARD_FAB2_LIB.BASEBOARD_FAB2(SCH_1):P3V3_STBY
   10  GND              GND  @BASEBOARD_FAB2_LIB.BASEBOARD_FAB2(SCH_1):GND

TTL2G07_SOT23LF  I201  U8F3   [TTL2G07_SOT23LF-74LVC2G07,IC,DB]
    1  RST_BMC_SYSRST_BTN_OUT_N     1A  @BASEBOARD_FAB2_LIB.BASEBOARD_FAB2(SCH_1):RST_BMC_SYSRST_BTN_OUT_N
    6  RST_BMC_SYSRST_BTN_OUT_B_R_N     1Y  @BASEBOARD_FAB2_LIB.BASEBOARD_FAB2(SCH_1):RST_BMC_SYSRST_BTN_OUT_B_R_N
    4  FM_PCH_PWRBTN_R_N     2Y  @BASEBOARD_FAB2_LIB.BASEBOARD_FAB2(SCH_1):FM_PCH_PWRBTN_R_N
    3  FM_BMC_PWRBTN_OUT_N     2A  @BASEBOARD_FAB2_LIB.BASEBOARD_FAB2(SCH_1):FM_BMC_PWRBTN_OUT_N

TTL2G07_SOT23LF  I269  U8G1   [TTL2G07_SOT23LF-74LVC2G07,IC,DB]
    1  RST_PCH_SYSRST_BTN_OUT_N     1A  @BASEBOARD_FAB2_LIB.BASEBOARD_FAB2(SCH_1):RST_PCH_SYSRST_BTN_OUT_N
    6  RST_BMC_SYSRST_BTN_OUT_B_R_N     1Y  @BASEBOARD_FAB2_LIB.BASEBOARD_FAB2(SCH_1):RST_BMC_SYSRST_BTN_OUT_B_R_N
    4  FM_PCH_PWRBTN_R_N     2Y  @BASEBOARD_FAB2_LIB.BASEBOARD_FAB2(SCH_1):FM_PCH_PWRBTN_R_N
    3  FM_PCH_PWRBTN_OUT_N     2A  @BASEBOARD_FAB2_LIB.BASEBOARD_FAB2(SCH_1):FM_PCH_PWRBTN_OUT_N

TTL1G07_A_SOP  I88  U8G2   [TTL1G07_A_SOP-74LVC1G07,IC,C88B]
    4  FAN_PWM_OUT_SYS0_BUF      Y  @BASEBOARD_FAB2_LIB.BASEBOARD_FAB2(SCH_1):FAN_PWM_OUT_SYS0_BUF
    2  FAN_PWM_OUT_SYS0      A  @BASEBOARD_FAB2_LIB.BASEBOARD_FAB2(SCH_1):FAN_PWM_OUT_SYS0

TTL1G07_A_SOP  I92  U8G3   [TTL1G07_A_SOP-74LVC1G07,IC,C88B]
    4  FAN_PWM_OUT_SYS1_BUF      Y  @BASEBOARD_FAB2_LIB.BASEBOARD_FAB2(SCH_1):FAN_PWM_OUT_SYS1_BUF
    2  FAN_PWM_OUT_SYS1      A  @BASEBOARD_FAB2_LIB.BASEBOARD_FAB2(SCH_1):FAN_PWM_OUT_SYS1

TTL1G07_A_SOP  I178  U9A1   [TTL1G07_A_SOP-74LVC1G07,IC,C88B]
    4  SPA_SIN_SW_R       Y  @BASEBOARD_FAB2_LIB.BASEBOARD_FAB2(SCH_1):SPA_SIN_SW_R
    2  SPA_5V_SIN_SW      A  @BASEBOARD_FAB2_LIB.BASEBOARD_FAB2(SCH_1):SPA_5V_SIN_SW

TTL2G14  I15  U9A3   [TTL2G14_SMLF-74LVC2G14,IC,D184B]
    4  RST_SYSTEM_BTN_BUF_N   Y<0>  @BASEBOARD_FAB2_LIB.BASEBOARD_FAB2(SCH_1):RST_SYSTEM_BTN_BUF_N
    3  FP_RST_BTN_BUF1_N   A<0>  @BASEBOARD_FAB2_LIB.BASEBOARD_FAB2(SCH_1):FP_RST_BTN_BUF1_N

TTL2G14  I18  U9A3   [TTL2G14_SMLF-74LVC2G14,IC,D184B]
    1  FP_RST_BTN_R_N   A<0>  @BASEBOARD_FAB2_LIB.BASEBOARD_FAB2(SCH_1):FP_RST_BTN_R_N
    6  FP_RST_BTN_BUF1_N   Y<0>  @BASEBOARD_FAB2_LIB.BASEBOARD_FAB2(SCH_1):FP_RST_BTN_BUF1_N

TTL2G14  I10  U9A4   [TTL2G14_SMLF-74LVC2G14,IC,D184B]
    3  FP_PWR_BTN_BUF1_N   A<0>  @BASEBOARD_FAB2_LIB.BASEBOARD_FAB2(SCH_1):FP_PWR_BTN_BUF1_N
    4  FM_PWR_BTN_R_N   Y<0>  @BASEBOARD_FAB2_LIB.BASEBOARD_FAB2(SCH_1):FM_PWR_BTN_R_N

TTL2G14  I9   U9A4   [TTL2G14_SMLF-74LVC2G14,IC,D184B]
    1  FP_PWR_BTN_R1_N   A<0>  @BASEBOARD_FAB2_LIB.BASEBOARD_FAB2(SCH_1):FP_PWR_BTN_R1_N
    6  FP_PWR_BTN_BUF1_N   Y<0>  @BASEBOARD_FAB2_LIB.BASEBOARD_FAB2(SCH_1):FP_PWR_BTN_BUF1_N

74CBTLV1G125  I185  U9A5   [74CBTLV1G125_SMLF-IC,C88177-00A]
    2  JTAG_MCP_TCK_R      A  @BASEBOARD_FAB2_LIB.BASEBOARD_FAB2(SCH_1):JTAG_MCP_TCK_R
    4  GND                B  @BASEBOARD_FAB2_LIB.BASEBOARD_FAB2(SCH_1):GND
    1  FM_CPU0_OR_CPU1_MCP_PRES   OE_N  @BASEBOARD_FAB2_LIB.BASEBOARD_FAB2(SCH_1):FM_CPU0_OR_CPU1_MCP_PRES

TMP421_TSSOP  I1   U9B4   [TMP421_TSSOP-IC,G62962-001]
    6  SMB_SENSOR_TMP421_1_SDA    SDA  @BASEBOARD_FAB2_LIB.BASEBOARD_FAB2(SCH_1):SMB_SENSOR_TMP421_1_SDA
    7  SMB_SENSOR_TMP421_1_SCL    SCL  @BASEBOARD_FAB2_LIB.BASEBOARD_FAB2(SCH_1):SMB_SENSOR_TMP421_1_SCL
    3  PU_TMP421_1_A1   A<1>  @BASEBOARD_FAB2_LIB.BASEBOARD_FAB2(SCH_1):PU_TMP421_1_A1
    4  PD_TMP421_1_A0   A<0>  @BASEBOARD_FAB2_LIB.BASEBOARD_FAB2(SCH_1):PD_TMP421_1_A0
    8  P3V3_STBY         VP  @BASEBOARD_FAB2_LIB.BASEBOARD_FAB2(SCH_1):P3V3_STBY
    1  ISENSE_TMP421_1_DXP    DXP  @BASEBOARD_FAB2_LIB.BASEBOARD_FAB2(SCH_1):ISENSE_TMP421_1_DXP
    2  ISENSE_TMP421_1_DXN    DXN  @BASEBOARD_FAB2_LIB.BASEBOARD_FAB2(SCH_1):ISENSE_TMP421_1_DXN
    5  GND              GND  @BASEBOARD_FAB2_LIB.BASEBOARD_FAB2(SCH_1):GND

M25PE16_SM  I1   U9E1   [M25PE16_SM-IC,H77797-001]
    6  SPI_NIC_SCLK       C  @BASEBOARD_FAB2_LIB.BASEBOARD_FAB2(SCH_1):SPI_NIC_SCLK
    5  SPI_NIC_MOSI     DQ0  @BASEBOARD_FAB2_LIB.BASEBOARD_FAB2(SCH_1):SPI_NIC_MOSI
    2  SPI_NIC_MISO_R    DQ1  @BASEBOARD_FAB2_LIB.BASEBOARD_FAB2(SCH_1):SPI_NIC_MISO_R
    1  SPI_NIC_CS_N     S_N  @BASEBOARD_FAB2_LIB.BASEBOARD_FAB2(SCH_1):SPI_NIC_CS_N
    3  PU_NV_WP_N       W_N  @BASEBOARD_FAB2_LIB.BASEBOARD_FAB2(SCH_1):PU_NV_WP_N
    7  PU_NV_HOLD_N   RESET_N  @BASEBOARD_FAB2_LIB.BASEBOARD_FAB2(SCH_1):PU_NV_HOLD_N
    8  P3V3_STBY        VCC  @BASEBOARD_FAB2_LIB.BASEBOARD_FAB2(SCH_1):P3V3_STBY
    4  GND              VSS  @BASEBOARD_FAB2_LIB.BASEBOARD_FAB2(SCH_1):GND

FSA3357_SM  I75  U9F1   [FSA3357_SM-IC,C63273-001]
    7  UART_MUX_IN_R      A  @BASEBOARD_FAB2_LIB.BASEBOARD_FAB2(SCH_1):UART_MUX_IN_R
    2  UART_BMC_RXD5     B1  @BASEBOARD_FAB2_LIB.BASEBOARD_FAB2(SCH_1):UART_BMC_RXD5
    1  SP2_BMC_CM_UART_RX_R     B0  @BASEBOARD_FAB2_LIB.BASEBOARD_FAB2(SCH_1):SP2_BMC_CM_UART_RX_R
    3  SP1_BMC_HOST_UART_RX     B2  @BASEBOARD_FAB2_LIB.BASEBOARD_FAB2(SCH_1):SP1_BMC_HOST_UART_RX
    8  P3V3_STBY        VCC  @BASEBOARD_FAB2_LIB.BASEBOARD_FAB2(SCH_1):P3V3_STBY
    4  GND              GND  @BASEBOARD_FAB2_LIB.BASEBOARD_FAB2(SCH_1):GND
    5  FM_UARTSW_MSB_N     S2  @BASEBOARD_FAB2_LIB.BASEBOARD_FAB2(SCH_1):FM_UARTSW_MSB_N
    6  FM_UARTSW_LSB_N     S1  @BASEBOARD_FAB2_LIB.BASEBOARD_FAB2(SCH_1):FM_UARTSW_LSB_N

FSA3357_SM  I74  U9F2   [FSA3357_SM-IC,C63273-001]
    7  UART_MUX_OUT_R      A  @BASEBOARD_FAB2_LIB.BASEBOARD_FAB2(SCH_1):UART_MUX_OUT_R
    2  UART_BMC_TXD5     B1  @BASEBOARD_FAB2_LIB.BASEBOARD_FAB2(SCH_1):UART_BMC_TXD5
    1  SP2_BMC_CM_UART_TX_R     B0  @BASEBOARD_FAB2_LIB.BASEBOARD_FAB2(SCH_1):SP2_BMC_CM_UART_TX_R
    3  SP1_BMC_HOST_UART_TX     B2  @BASEBOARD_FAB2_LIB.BASEBOARD_FAB2(SCH_1):SP1_BMC_HOST_UART_TX
    8  P3V3_STBY        VCC  @BASEBOARD_FAB2_LIB.BASEBOARD_FAB2(SCH_1):P3V3_STBY
    4  GND              GND  @BASEBOARD_FAB2_LIB.BASEBOARD_FAB2(SCH_1):GND
    5  FM_UARTSW_MSB_N     S2  @BASEBOARD_FAB2_LIB.BASEBOARD_FAB2(SCH_1):FM_UARTSW_MSB_N
    6  FM_UARTSW_LSB_N     S1  @BASEBOARD_FAB2_LIB.BASEBOARD_FAB2(SCH_1):FM_UARTSW_LSB_N

TTL1G07_A_SOP  I69  U9F3   [TTL1G07_A_SOP-74LVC1G07,IC,C88B]
    4  RST_BMC_DDR3_R_N      Y  @BASEBOARD_FAB2_LIB.BASEBOARD_FAB2(SCH_1):RST_BMC_DDR3_R_N
    2  RST_BMC_DDR3_BUF_IN_N      A  @BASEBOARD_FAB2_LIB.BASEBOARD_FAB2(SCH_1):RST_BMC_DDR3_BUF_IN_N

AST1250_BGA  I11  U9F4   [AST1250_BGA-IC,G85138-002]
  V19  PVCCIO_CPU0    PECIVDD  @BASEBOARD_FAB2_LIB.BASEBOARD_FAB2(SCH_1):PVCCIO_CPU0
  AB19  P3V3_STBY_BMC_HPLLAV33  MPLLAV33  @BASEBOARD_FAB2_LIB.BASEBOARD_FAB2(SCH_1):P3V3_STBY_BMC_HPLLAV33
  V17  P3V3_STBY_BMC_HPLLAV33  HPLLAV33  @BASEBOARD_FAB2_LIB.BASEBOARD_FAB2(SCH_1):P3V3_STBY_BMC_HPLLAV33
   P3  P3V3_STBY_BMC_ADCAV33  ADCAV33  @BASEBOARD_FAB2_LIB.BASEBOARD_FAB2(SCH_1):P3V3_STBY_BMC_ADCAV33
  W18  P3V3_STBY      USB2AV33  @BASEBOARD_FAB2_LIB.BASEBOARD_FAB2(SCH_1):P3V3_STBY
   F9  P3V3_STBY      R2VDD<1>  @BASEBOARD_FAB2_LIB.BASEBOARD_FAB2(SCH_1):P3V3_STBY
   F8  P3V3_STBY      R2VDD<0>  @BASEBOARD_FAB2_LIB.BASEBOARD_FAB2(SCH_1):P3V3_STBY
  F11  P3V3_STBY      R1VDD<1>  @BASEBOARD_FAB2_LIB.BASEBOARD_FAB2(SCH_1):P3V3_STBY
  F10  P3V3_STBY      R1VDD<0>  @BASEBOARD_FAB2_LIB.BASEBOARD_FAB2(SCH_1):P3V3_STBY
   U9  P3V3_STBY      PV33D<10>  @BASEBOARD_FAB2_LIB.BASEBOARD_FAB2(SCH_1):P3V3_STBY
   U8  P3V3_STBY      PV33D<9>  @BASEBOARD_FAB2_LIB.BASEBOARD_FAB2(SCH_1):P3V3_STBY
  N17  P3V3_STBY      PV33D<8>  @BASEBOARD_FAB2_LIB.BASEBOARD_FAB2(SCH_1):P3V3_STBY
   N6  P3V3_STBY      PV33D<7>  @BASEBOARD_FAB2_LIB.BASEBOARD_FAB2(SCH_1):P3V3_STBY
  M17  P3V3_STBY      PV33D<6>  @BASEBOARD_FAB2_LIB.BASEBOARD_FAB2(SCH_1):P3V3_STBY
   M6  P3V3_STBY      PV33D<5>  @BASEBOARD_FAB2_LIB.BASEBOARD_FAB2(SCH_1):P3V3_STBY
   J6  P3V3_STBY      PV33D<4>  @BASEBOARD_FAB2_LIB.BASEBOARD_FAB2(SCH_1):P3V3_STBY
  H17  P3V3_STBY      PV33D<3>  @BASEBOARD_FAB2_LIB.BASEBOARD_FAB2(SCH_1):P3V3_STBY
   H6  P3V3_STBY      PV33D<2>  @BASEBOARD_FAB2_LIB.BASEBOARD_FAB2(SCH_1):P3V3_STBY
  F13  P3V3_STBY      PV33D<1>  @BASEBOARD_FAB2_LIB.BASEBOARD_FAB2(SCH_1):P3V3_STBY
  F12  P3V3_STBY      PV33D<0>  @BASEBOARD_FAB2_LIB.BASEBOARD_FAB2(SCH_1):P3V3_STBY
  J17  P3V3_STBY      PEAV33  @BASEBOARD_FAB2_LIB.BASEBOARD_FAB2(SCH_1):P3V3_STBY
   T3  P3V3_STBY      DACDV33  @BASEBOARD_FAB2_LIB.BASEBOARD_FAB2(SCH_1):P3V3_STBY
   P1  P3V3_STBY      DACAV33  @BASEBOARD_FAB2_LIB.BASEBOARD_FAB2(SCH_1):P3V3_STBY
  F20  P1V8_BMC_STBY_PCIEA  GPIOY1_SIOS5_N  @BASEBOARD_FAB2_LIB.BASEBOARD_FAB2(SCH_1):P1V8_BMC_STBY_PCIEA
  C21  P1V8_BMC_STBY_PCIEA  GPIOY0_SIOS3_N  @BASEBOARD_FAB2_LIB.BASEBOARD_FAB2(SCH_1):P1V8_BMC_STBY_PCIEA
  G20  P1V8_BMC_STBY_PCIE  GPIOY2_SIOPWREQ_N  @BASEBOARD_FAB2_LIB.BASEBOARD_FAB2(SCH_1):P1V8_BMC_STBY_PCIE
  U15  P1V538_BMC_STBY  MVDD<3>  @BASEBOARD_FAB2_LIB.BASEBOARD_FAB2(SCH_1):P1V538_BMC_STBY
  U14  P1V538_BMC_STBY  MVDD<2>  @BASEBOARD_FAB2_LIB.BASEBOARD_FAB2(SCH_1):P1V538_BMC_STBY
  U11  P1V538_BMC_STBY  MVDD<1>  @BASEBOARD_FAB2_LIB.BASEBOARD_FAB2(SCH_1):P1V538_BMC_STBY
  U10  P1V538_BMC_STBY  MVDD<0>  @BASEBOARD_FAB2_LIB.BASEBOARD_FAB2(SCH_1):P1V538_BMC_STBY
  Y20  P1V26_BMC_STBY_V1PLLAV12  V2PLLAV12  @BASEBOARD_FAB2_LIB.BASEBOARD_FAB2(SCH_1):P1V26_BMC_STBY_V1PLLAV12
  W19  P1V26_BMC_STBY_V1PLLAV12  V1PLLAV12  @BASEBOARD_FAB2_LIB.BASEBOARD_FAB2(SCH_1):P1V26_BMC_STBY_V1PLLAV12
  K17  P1V26_BMC_STBY  PEAV12  @BASEBOARD_FAB2_LIB.BASEBOARD_FAB2(SCH_1):P1V26_BMC_STBY
  Y18  P1V26_BMC_STBY  MPLLDV12  @BASEBOARD_FAB2_LIB.BASEBOARD_FAB2(SCH_1):P1V26_BMC_STBY
  U13  P1V26_BMC_STBY  IV12D<10>  @BASEBOARD_FAB2_LIB.BASEBOARD_FAB2(SCH_1):P1V26_BMC_STBY
  U12  P1V26_BMC_STBY  IV12D<9>  @BASEBOARD_FAB2_LIB.BASEBOARD_FAB2(SCH_1):P1V26_BMC_STBY
  R17  P1V26_BMC_STBY  IV12D<8>  @BASEBOARD_FAB2_LIB.BASEBOARD_FAB2(SCH_1):P1V26_BMC_STBY
   R6  P1V26_BMC_STBY  IV12D<7>  @BASEBOARD_FAB2_LIB.BASEBOARD_FAB2(SCH_1):P1V26_BMC_STBY
  P17  P1V26_BMC_STBY  IV12D<6>  @BASEBOARD_FAB2_LIB.BASEBOARD_FAB2(SCH_1):P1V26_BMC_STBY
   P6  P1V26_BMC_STBY  IV12D<5>  @BASEBOARD_FAB2_LIB.BASEBOARD_FAB2(SCH_1):P1V26_BMC_STBY
  L17  P1V26_BMC_STBY  IV12D<4>  @BASEBOARD_FAB2_LIB.BASEBOARD_FAB2(SCH_1):P1V26_BMC_STBY
   L6  P1V26_BMC_STBY  IV12D<3>  @BASEBOARD_FAB2_LIB.BASEBOARD_FAB2(SCH_1):P1V26_BMC_STBY
   K6  P1V26_BMC_STBY  IV12D<2>  @BASEBOARD_FAB2_LIB.BASEBOARD_FAB2(SCH_1):P1V26_BMC_STBY
  F15  P1V26_BMC_STBY  IV12D<1>  @BASEBOARD_FAB2_LIB.BASEBOARD_FAB2(SCH_1):P1V26_BMC_STBY
  F14  P1V26_BMC_STBY  IV12D<0>  @BASEBOARD_FAB2_LIB.BASEBOARD_FAB2(SCH_1):P1V26_BMC_STBY
  Y19  GND            USB2AVSS  @BASEBOARD_FAB2_LIB.BASEBOARD_FAB2(SCH_1):GND
  V18  GND            PLLVSS<2>  @BASEBOARD_FAB2_LIB.BASEBOARD_FAB2(SCH_1):GND
  AA19  GND            PLLVSS<1>  @BASEBOARD_FAB2_LIB.BASEBOARD_FAB2(SCH_1):GND
  AA18  GND            PLLVSS<0>  @BASEBOARD_FAB2_LIB.BASEBOARD_FAB2(SCH_1):GND
  D22  GND            PEAGND<1>  @BASEBOARD_FAB2_LIB.BASEBOARD_FAB2(SCH_1):GND
  D21  GND            PEAGND<0>  @BASEBOARD_FAB2_LIB.BASEBOARD_FAB2(SCH_1):GND
  H22  GND            NC<1>  @BASEBOARD_FAB2_LIB.BASEBOARD_FAB2(SCH_1):GND
  H21  GND            NC<0>  @BASEBOARD_FAB2_LIB.BASEBOARD_FAB2(SCH_1):GND
   P9  GND            GND<35>  @BASEBOARD_FAB2_LIB.BASEBOARD_FAB2(SCH_1):GND
  P14  GND            GND<34>  @BASEBOARD_FAB2_LIB.BASEBOARD_FAB2(SCH_1):GND
  P13  GND            GND<33>  @BASEBOARD_FAB2_LIB.BASEBOARD_FAB2(SCH_1):GND
  P12  GND            GND<32>  @BASEBOARD_FAB2_LIB.BASEBOARD_FAB2(SCH_1):GND
  P11  GND            GND<31>  @BASEBOARD_FAB2_LIB.BASEBOARD_FAB2(SCH_1):GND
  P10  GND            GND<30>  @BASEBOARD_FAB2_LIB.BASEBOARD_FAB2(SCH_1):GND
   N9  GND            GND<29>  @BASEBOARD_FAB2_LIB.BASEBOARD_FAB2(SCH_1):GND
  N14  GND            GND<28>  @BASEBOARD_FAB2_LIB.BASEBOARD_FAB2(SCH_1):GND
  N13  GND            GND<27>  @BASEBOARD_FAB2_LIB.BASEBOARD_FAB2(SCH_1):GND
  N12  GND            GND<26>  @BASEBOARD_FAB2_LIB.BASEBOARD_FAB2(SCH_1):GND
  N11  GND            GND<25>  @BASEBOARD_FAB2_LIB.BASEBOARD_FAB2(SCH_1):GND
  N10  GND            GND<24>  @BASEBOARD_FAB2_LIB.BASEBOARD_FAB2(SCH_1):GND
   M9  GND            GND<23>  @BASEBOARD_FAB2_LIB.BASEBOARD_FAB2(SCH_1):GND
  M14  GND            GND<22>  @BASEBOARD_FAB2_LIB.BASEBOARD_FAB2(SCH_1):GND
  M13  GND            GND<21>  @BASEBOARD_FAB2_LIB.BASEBOARD_FAB2(SCH_1):GND
  M12  GND            GND<20>  @BASEBOARD_FAB2_LIB.BASEBOARD_FAB2(SCH_1):GND
  M11  GND            GND<19>  @BASEBOARD_FAB2_LIB.BASEBOARD_FAB2(SCH_1):GND
  M10  GND            GND<18>  @BASEBOARD_FAB2_LIB.BASEBOARD_FAB2(SCH_1):GND
   L9  GND            GND<17>  @BASEBOARD_FAB2_LIB.BASEBOARD_FAB2(SCH_1):GND
  L14  GND            GND<16>  @BASEBOARD_FAB2_LIB.BASEBOARD_FAB2(SCH_1):GND
  L13  GND            GND<15>  @BASEBOARD_FAB2_LIB.BASEBOARD_FAB2(SCH_1):GND
  L12  GND            GND<14>  @BASEBOARD_FAB2_LIB.BASEBOARD_FAB2(SCH_1):GND
  L11  GND            GND<13>  @BASEBOARD_FAB2_LIB.BASEBOARD_FAB2(SCH_1):GND
  L10  GND            GND<12>  @BASEBOARD_FAB2_LIB.BASEBOARD_FAB2(SCH_1):GND
   K9  GND            GND<11>  @BASEBOARD_FAB2_LIB.BASEBOARD_FAB2(SCH_1):GND
  K14  GND            GND<10>  @BASEBOARD_FAB2_LIB.BASEBOARD_FAB2(SCH_1):GND
  K13  GND            GND<9>  @BASEBOARD_FAB2_LIB.BASEBOARD_FAB2(SCH_1):GND
  K12  GND            GND<8>  @BASEBOARD_FAB2_LIB.BASEBOARD_FAB2(SCH_1):GND
  K11  GND            GND<7>  @BASEBOARD_FAB2_LIB.BASEBOARD_FAB2(SCH_1):GND
  K10  GND            GND<6>  @BASEBOARD_FAB2_LIB.BASEBOARD_FAB2(SCH_1):GND
   J9  GND            GND<5>  @BASEBOARD_FAB2_LIB.BASEBOARD_FAB2(SCH_1):GND
  J14  GND            GND<4>  @BASEBOARD_FAB2_LIB.BASEBOARD_FAB2(SCH_1):GND
  J13  GND            GND<3>  @BASEBOARD_FAB2_LIB.BASEBOARD_FAB2(SCH_1):GND
  J12  GND            GND<2>  @BASEBOARD_FAB2_LIB.BASEBOARD_FAB2(SCH_1):GND
  J11  GND            GND<1>  @BASEBOARD_FAB2_LIB.BASEBOARD_FAB2(SCH_1):GND
  J10  GND            GND<0>  @BASEBOARD_FAB2_LIB.BASEBOARD_FAB2(SCH_1):GND
   R5  GND            DACAVSS  @BASEBOARD_FAB2_LIB.BASEBOARD_FAB2(SCH_1):GND
   P4  GND            ADCAVSS  @BASEBOARD_FAB2_LIB.BASEBOARD_FAB2(SCH_1):GND

AST1250_BGA  I1   U9F4   [AST1250_BGA-IC,G85138-002]
  A13  TP_RGMII2TXD3_GPIOT5  RGMII1TXD3_GPIOT5  @BASEBOARD_FAB2_LIB.BASEBOARD_FAB2(SCH_1):TP_RGMII2TXD3_GPIOT5
  E12  TP_RGMII2TXD2_GPIOT4  RGMII1TXD2_GPIOT4  @BASEBOARD_FAB2_LIB.BASEBOARD_FAB2(SCH_1):TP_RGMII2TXD2_GPIOT4
  B12  TP_RGMII2TXCTL_GPIOT7  RGMII1TXCTL_GPIOT1  @BASEBOARD_FAB2_LIB.BASEBOARD_FAB2(SCH_1):TP_RGMII2TXCTL_GPIOT7
  D10  TP_RGMII1TXD3_GPIOT5  RGMII2TXD3_GPIOU3  @BASEBOARD_FAB2_LIB.BASEBOARD_FAB2(SCH_1):TP_RGMII1TXD3_GPIOT5
  C10  TP_RGMII1TXD2_GPIOT4  RGMII2TXD2_GPIOU2  @BASEBOARD_FAB2_LIB.BASEBOARD_FAB2(SCH_1):TP_RGMII1TXD2_GPIOT4
   E9  TP_RGMII1TXCTL_GPIOT1  RGMII2TXCTL_GPIOT7  @BASEBOARD_FAB2_LIB.BASEBOARD_FAB2(SCH_1):TP_RGMII1TXCTL_GPIOT1
   E8  RMII_SPRNGVLLE_BMC_PCH_RXD1  RGMII2RXD1_RMII2RXD1_GPIOV5  @BASEBOARD_FAB2_LIB.BASEBOARD_FAB2(SCH_1):RMII_SPRNGVLLE_BMC_PCH_RXD1
   A9  RMII_SPRNGVLLE_BMC_PCH_RXD0  RGMII2RXD0_RMII2RXD0_GPIOV4  @BASEBOARD_FAB2_LIB.BASEBOARD_FAB2(SCH_1):RMII_SPRNGVLLE_BMC_PCH_RXD0
   D9  RMII_BMC_SPRNGVLLE_TXEN_R  RGMII2TXCK_RMII2TXEN_GPIOT6  @BASEBOARD_FAB2_LIB.BASEBOARD_FAB2(SCH_1):RMII_BMC_SPRNGVLLE_TXEN_R
  B10  RMII_BMC_PCH_SPRNGVLLE_TXD1_R  RGMII2TXD1_RMII2TXD1_GPIOU1  @BASEBOARD_FAB2_LIB.BASEBOARD_FAB2(SCH_1):RMII_BMC_PCH_SPRNGVLLE_TXD1_R
  A10  RMII_BMC_PCH_SPRNGVLLE_TXD0_R  RGMII2TXD0_RMII2TXD0_GPIOU0  @BASEBOARD_FAB2_LIB.BASEBOARD_FAB2(SCH_1):RMII_BMC_PCH_SPRNGVLLE_TXD0_R
   C8  RMII_BMC_PCH_SPRNGVLLE_RXER  RGMII2RXD3_RMII2RXER_GPIOV7  @BASEBOARD_FAB2_LIB.BASEBOARD_FAB2(SCH_1):RMII_BMC_PCH_SPRNGVLLE_RXER
   D8  RMII_BMC_PCH_SPRNGVLLE_CRSDV  RGMII2RXD2_RMII2CRSDV_GPIOV6  @BASEBOARD_FAB2_LIB.BASEBOARD_FAB2(SCH_1):RMII_BMC_PCH_SPRNGVLLE_CRSDV
  A12  RMII_BMC_OCP_TXEN_R  RGMII1TXCK_RMII1TXEN_GPIOT0  @BASEBOARD_FAB2_LIB.BASEBOARD_FAB2(SCH_1):RMII_BMC_OCP_TXEN_R
  D12  RMII_BMC_OCP_TXD1_R  RGMII1TXD1_RMII1TXD1_GPIOT3  @BASEBOARD_FAB2_LIB.BASEBOARD_FAB2(SCH_1):RMII_BMC_OCP_TXD1_R
  C12  RMII_BMC_OCP_TXD0_R  RGMII1TXD0_RMII1TXD0_GPIOT2  @BASEBOARD_FAB2_LIB.BASEBOARD_FAB2(SCH_1):RMII_BMC_OCP_TXD0_R
  E10  RMII_BMC_OCP_RXER  RGMII1RXD3_RMII1RXER_GPIOV1  @BASEBOARD_FAB2_LIB.BASEBOARD_FAB2(SCH_1):RMII_BMC_OCP_RXER
  B11  RMII_BMC_OCP_RXD1  RGMII1RXD1_RMII1RXD1_GPIOU7  @BASEBOARD_FAB2_LIB.BASEBOARD_FAB2(SCH_1):RMII_BMC_OCP_RXD1
  C11  RMII_BMC_OCP_RXD0  RGMII1RXD0_RMII1RXD0_GPIOU6  @BASEBOARD_FAB2_LIB.BASEBOARD_FAB2(SCH_1):RMII_BMC_OCP_RXD0
  A11  RMII_BMC_OCP_CRSDV  RGMII1RXD2_RMII1CRSDV_GPIOV0  @BASEBOARD_FAB2_LIB.BASEBOARD_FAB2(SCH_1):RMII_BMC_OCP_CRSDV
   P2  PD_ADCREXT     ADCREXT  @BASEBOARD_FAB2_LIB.BASEBOARD_FAB2(SCH_1):PD_ADCREXT
   K1  P3V3_STBY_BMC_ADCVREFP  ADCVREFP  @BASEBOARD_FAB2_LIB.BASEBOARD_FAB2(SCH_1):P3V3_STBY_BMC_ADCVREFP
   K2  P3V3_STBY_BMC_ADCVREFN  ADCVREFN  @BASEBOARD_FAB2_LIB.BASEBOARD_FAB2(SCH_1):P3V3_STBY_BMC_ADCVREFN
   Y7  IRQ_PVCCIN_CPU1_VRHOT_LVC3_N  GPIOP5_TACH13  @BASEBOARD_FAB2_LIB.BASEBOARD_FAB2(SCH_1):IRQ_PVCCIN_CPU1_VRHOT_LVC3_N
  AB6  IRQ_PVCCIN_CPU0_VRHOT_LVC3_N  GPIOP4_TACH12  @BASEBOARD_FAB2_LIB.BASEBOARD_FAB2(SCH_1):IRQ_PVCCIN_CPU0_VRHOT_LVC3_N
   B8  GND            RGMIICK  @BASEBOARD_FAB2_LIB.BASEBOARD_FAB2(SCH_1):GND
   B9  GND            RGMII2RXCTL_GPIOV3  @BASEBOARD_FAB2_LIB.BASEBOARD_FAB2(SCH_1):GND
  D11  GND            RGMII1RXCTL_GPIOU5  @BASEBOARD_FAB2_LIB.BASEBOARD_FAB2(SCH_1):GND
   P5  GND            ADC15_GPIX7  @BASEBOARD_FAB2_LIB.BASEBOARD_FAB2(SCH_1):GND
   N1  GND            ADC14_GPIX6  @BASEBOARD_FAB2_LIB.BASEBOARD_FAB2(SCH_1):GND
   N2  GND            ADC13_GPIX5  @BASEBOARD_FAB2_LIB.BASEBOARD_FAB2(SCH_1):GND
   N3  GND            ADC12_GPIX4  @BASEBOARD_FAB2_LIB.BASEBOARD_FAB2(SCH_1):GND
   N4  GND            ADC11_GPIX3  @BASEBOARD_FAB2_LIB.BASEBOARD_FAB2(SCH_1):GND
   N5  GND            ADC10_GPIX2  @BASEBOARD_FAB2_LIB.BASEBOARD_FAB2(SCH_1):GND
   M1  GND            ADC9_GPIX1  @BASEBOARD_FAB2_LIB.BASEBOARD_FAB2(SCH_1):GND
   M2  GND            ADC8_GPIX0  @BASEBOARD_FAB2_LIB.BASEBOARD_FAB2(SCH_1):GND
   V7  FM_XRC_READY_N  GPIOO7_TACH7_VPIR5  @BASEBOARD_FAB2_LIB.BASEBOARD_FAB2(SCH_1):FM_XRC_READY_N
  AB4  FM_XRC_PRESENT_N  GPIOO6_TACH6_VPIR4  @BASEBOARD_FAB2_LIB.BASEBOARD_FAB2(SCH_1):FM_XRC_PRESENT_N
   D5  FM_UV_ADR_TRIGGER_EN  GPIOA7_TIMER8_MDIO2  @BASEBOARD_FAB2_LIB.BASEBOARD_FAB2(SCH_1):FM_UV_ADR_TRIGGER_EN
  AB2  FM_UARTSW_MSB_N  GPION7_PWM7_VPIG7  @BASEBOARD_FAB2_LIB.BASEBOARD_FAB2(SCH_1):FM_UARTSW_MSB_N
  AA3  FM_UARTSW_LSB_N  GPION6_PWM6_VPIG6  @BASEBOARD_FAB2_LIB.BASEBOARD_FAB2(SCH_1):FM_UARTSW_LSB_N
  AA5  FM_MP_PS_REDUNDANT_LOST_N  GPIOO5_TACH5_VPIR3  @BASEBOARD_FAB2_LIB.BASEBOARD_FAB2(SCH_1):FM_MP_PS_REDUNDANT_LOST_N
   W6  FM_MP_PS_FAIL_N  GPIOO4_TACH4_VPIR2  @BASEBOARD_FAB2_LIB.BASEBOARD_FAB2(SCH_1):FM_MP_PS_FAIL_N
   A3  FM_FORCE_ADR_N  GPIOA6_TIMER7_MDC2  @BASEBOARD_FAB2_LIB.BASEBOARD_FAB2(SCH_1):FM_FORCE_ADR_N
  AB1  FM_CPU_MSMI_LVT3_N  GPION3_PWM3_VPIG3  @BASEBOARD_FAB2_LIB.BASEBOARD_FAB2(SCH_1):FM_CPU_MSMI_LVT3_N
  AB7  FM_CPU1_PROCHOT_LVT3_BMC_N  GPIOP7_TACH15_FLACK  @BASEBOARD_FAB2_LIB.BASEBOARD_FAB2(SCH_1):FM_CPU1_PROCHOT_LVT3_BMC_N
  AA7  FM_CPU0_PROCHOT_LVT3_BMC_N  GPIOP6_TACH14_BMCINT  @BASEBOARD_FAB2_LIB.BASEBOARD_FAB2(SCH_1):FM_CPU0_PROCHOT_LVT3_BMC_N
  AA6  FM_BOARD_SKU_ID3  GPIOP3_TACH11_VPIR9  @BASEBOARD_FAB2_LIB.BASEBOARD_FAB2(SCH_1):FM_BOARD_SKU_ID3
   W7  FM_BOARD_SKU_ID2  GPIOP2_TACH10_VPIR8  @BASEBOARD_FAB2_LIB.BASEBOARD_FAB2(SCH_1):FM_BOARD_SKU_ID2
  AB5  FM_BOARD_SKU_ID1  GPIOP1_TACH9_VPIR7  @BASEBOARD_FAB2_LIB.BASEBOARD_FAB2(SCH_1):FM_BOARD_SKU_ID1
   Y6  FM_BOARD_SKU_ID0  GPIOP0_TACH8_VPIR6  @BASEBOARD_FAB2_LIB.BASEBOARD_FAB2(SCH_1):FM_BOARD_SKU_ID0
   Y4  FM_BIOS_SPI_BMC_CTRL  GPION5_PWM5_VPIG5  @BASEBOARD_FAB2_LIB.BASEBOARD_FAB2(SCH_1):FM_BIOS_SPI_BMC_CTRL
  AA2  FM_BIOS_PREFRB2_GOOD  GPION2_PWM2_VPIG2  @BASEBOARD_FAB2_LIB.BASEBOARD_FAB2(SCH_1):FM_BIOS_PREFRB2_GOOD
   W5  FM_BACKUP_BIOS_SEL_N  GPION4_PWM4_VPIG4  @BASEBOARD_FAB2_LIB.BASEBOARD_FAB2(SCH_1):FM_BACKUP_BIOS_SEL_N
  AB3  FAN_TACH3      GPIOO3_TACH3_VPIR1  @BASEBOARD_FAB2_LIB.BASEBOARD_FAB2(SCH_1):FAN_TACH3
  AA4  FAN_TACH2      GPIOO2_TACH2_VPIR0  @BASEBOARD_FAB2_LIB.BASEBOARD_FAB2(SCH_1):FAN_TACH2
   Y5  FAN_TACH1      GPIOO1_TACH1_VPIG9  @BASEBOARD_FAB2_LIB.BASEBOARD_FAB2(SCH_1):FAN_TACH1
   V6  FAN_TACH0      GPIOO0_TACH0_VPIG8  @BASEBOARD_FAB2_LIB.BASEBOARD_FAB2(SCH_1):FAN_TACH0
   Y3  FAN_PWM_OUT_SYS1  GPION1_PWM1_VPIG1  @BASEBOARD_FAB2_LIB.BASEBOARD_FAB2(SCH_1):FAN_PWM_OUT_SYS1
   W4  FAN_PWM_OUT_SYS0  GPION0_PWM0_VPIG0  @BASEBOARD_FAB2_LIB.BASEBOARD_FAB2(SCH_1):FAN_PWM_OUT_SYS0
   C9  CLK_50M_CKMNG_BMC_2  RGMII2RXCK_RMII2RCLK_GPIOV2  @BASEBOARD_FAB2_LIB.BASEBOARD_FAB2(SCH_1):CLK_50M_CKMNG_BMC_2
  E11  CLK_50M_CKMNG_BMC_1  RGMII1RXCK_RMII1RCLK_GPIOU4  @BASEBOARD_FAB2_LIB.BASEBOARD_FAB2(SCH_1):CLK_50M_CKMNG_BMC_1
   L1  A_PVNN_STBY_PCH_SENSOR  ADC4_GPIW4  @BASEBOARD_FAB2_LIB.BASEBOARD_FAB2(SCH_1):A_PVNN_STBY_PCH_SENSOR
   M4  A_P5V_STBY_SCALED  ADC6_GPIW6  @BASEBOARD_FAB2_LIB.BASEBOARD_FAB2(SCH_1):A_P5V_STBY_SCALED
   L4  A_P5V_SCALED   ADC1_GPIW1  @BASEBOARD_FAB2_LIB.BASEBOARD_FAB2(SCH_1):A_P5V_SCALED
   M3  A_P3V_BAT_SCALED  ADC7_GPIW7  @BASEBOARD_FAB2_LIB.BASEBOARD_FAB2(SCH_1):A_P3V_BAT_SCALED
   M5  A_P3V3_STBY_SCALED  ADC5_GPIW5  @BASEBOARD_FAB2_LIB.BASEBOARD_FAB2(SCH_1):A_P3V3_STBY_SCALED
   L5  A_P3V3_SCALED  ADC0_GPIW0  @BASEBOARD_FAB2_LIB.BASEBOARD_FAB2(SCH_1):A_P3V3_SCALED
   L2  A_P1V05_STBY_PCH_SENSOR  ADC3_GPIW3  @BASEBOARD_FAB2_LIB.BASEBOARD_FAB2(SCH_1):A_P1V05_STBY_PCH_SENSOR
   L3  A_P12V_STBY_SCALED  ADC2_GPIW2  @BASEBOARD_FAB2_LIB.BASEBOARD_FAB2(SCH_1):A_P12V_STBY_SCALED

AST1250_BGA  I1   U9F4   [AST1250_BGA-IC,G85138-002]
  U22  TP_SPI_BMC_BT_D2  ROMD3  @BASEBOARD_FAB2_LIB.BASEBOARD_FAB2(SCH_1):TP_SPI_BMC_BT_D2
  W22  TP_GPIOR5_ROMA25_VPOR7  GPIOR5_ROMA25_VPOR7  @BASEBOARD_FAB2_LIB.BASEBOARD_FAB2(SCH_1):TP_GPIOR5_ROMA25_VPOR7
  T21  SPI_BMC_BT_DO_R  ROMD1  @BASEBOARD_FAB2_LIB.BASEBOARD_FAB2(SCH_1):SPI_BMC_BT_DO_R
  T20  SPI_BMC_BT_DI  ROMD2  @BASEBOARD_FAB2_LIB.BASEBOARD_FAB2(SCH_1):SPI_BMC_BT_DI
  R19  SPI_BMC_BT_CS_R_N  ROMCS0_N  @BASEBOARD_FAB2_LIB.BASEBOARD_FAB2(SCH_1):SPI_BMC_BT_CS_R_N
  T22  SPI_BMC_BT_CLK_R  ROMD0  @BASEBOARD_FAB2_LIB.BASEBOARD_FAB2(SCH_1):SPI_BMC_BT_CLK_R
   E7  LED_POSTCODE_7  GPIOH7_ROMD15_RXD6  @BASEBOARD_FAB2_LIB.BASEBOARD_FAB2(SCH_1):LED_POSTCODE_7
   A6  LED_POSTCODE_6  GPIOH6_ROMD14_TXD6  @BASEBOARD_FAB2_LIB.BASEBOARD_FAB2(SCH_1):LED_POSTCODE_6
   B6  LED_POSTCODE_5  GPIOH5_ROMD13_NRTS6  @BASEBOARD_FAB2_LIB.BASEBOARD_FAB2(SCH_1):LED_POSTCODE_5
   D7  LED_POSTCODE_4  GPIOH4_ROMD12_NDTR6  @BASEBOARD_FAB2_LIB.BASEBOARD_FAB2(SCH_1):LED_POSTCODE_4
   A7  LED_POSTCODE_3  GPIOH3_ROMD11_NRI6  @BASEBOARD_FAB2_LIB.BASEBOARD_FAB2(SCH_1):LED_POSTCODE_3
   B7  LED_POSTCODE_2  GPIOH2_ROMD10_NDSR6  @BASEBOARD_FAB2_LIB.BASEBOARD_FAB2(SCH_1):LED_POSTCODE_2
   C7  LED_POSTCODE_1  GPIOH1_ROMD9_NDCD6  @BASEBOARD_FAB2_LIB.BASEBOARD_FAB2(SCH_1):LED_POSTCODE_1
   A8  LED_POSTCODE_0  GPIOH0_ROMD8_NCTS6  @BASEBOARD_FAB2_LIB.BASEBOARD_FAB2(SCH_1):LED_POSTCODE_0
  U18  IRQ_DIMM_SAVE_LVT3_N  GPIOG7_FLWP_N  @BASEBOARD_FAB2_LIB.BASEBOARD_FAB2(SCH_1):IRQ_DIMM_SAVE_LVT3_N
  V21  FM_THROTTLE_N  GPIOR4_ROMA24_VPOR6  @BASEBOARD_FAB2_LIB.BASEBOARD_FAB2(SCH_1):FM_THROTTLE_N
  R18  FM_SOL_UART_CH_SEL  ROMOE_N_GPIOS4  @BASEBOARD_FAB2_LIB.BASEBOARD_FAB2(SCH_1):FM_SOL_UART_CH_SEL
  M20  FM_ROMA<9>     ROMA9_GPIOZ7_VPOB7  @BASEBOARD_FAB2_LIB.BASEBOARD_FAB2(SCH_1):FM_ROMA<9>
  M19  FM_ROMA<8>     ROMA8_GPIOZ6_VPOB6  @BASEBOARD_FAB2_LIB.BASEBOARD_FAB2(SCH_1):FM_ROMA<8>
  P22  FM_ROMA<7>     ROMA7_GPIOZ5_VPOB5  @BASEBOARD_FAB2_LIB.BASEBOARD_FAB2(SCH_1):FM_ROMA<7>
  P21  FM_ROMA<6>     ROMA6_GPIOZ4_VPOB4  @BASEBOARD_FAB2_LIB.BASEBOARD_FAB2(SCH_1):FM_ROMA<6>
  P20  FM_ROMA<5>     ROMA5_GPIOZ3_VPOB3  @BASEBOARD_FAB2_LIB.BASEBOARD_FAB2(SCH_1):FM_ROMA<5>
  P19  FM_ROMA<4>     ROMA4_GPIOZ2_VPOB2  @BASEBOARD_FAB2_LIB.BASEBOARD_FAB2(SCH_1):FM_ROMA<4>
  P18  FM_ROMA<3>     ROMA3_GPIOZ1_VPOB1  @BASEBOARD_FAB2_LIB.BASEBOARD_FAB2(SCH_1):FM_ROMA<3>
  R22  FM_ROMA<2>     ROMA2_GPIOZ0_VPOB0  @BASEBOARD_FAB2_LIB.BASEBOARD_FAB2(SCH_1):FM_ROMA<2>
  K18  FM_ROMA<23>    ROMA23_GPIOS7_VPOR5  @BASEBOARD_FAB2_LIB.BASEBOARD_FAB2(SCH_1):FM_ROMA<23>
  L22  FM_ROMA<22>    ROMA22_GPIOS6_VPOR4  @BASEBOARD_FAB2_LIB.BASEBOARD_FAB2(SCH_1):FM_ROMA<22>
  N20  FM_ROMA<21>    ROMA21_GPIOAB3_VPOR3  @BASEBOARD_FAB2_LIB.BASEBOARD_FAB2(SCH_1):FM_ROMA<21>
  N22  FM_ROMA<20>    ROMA20_GPIOAB2_VPOR2  @BASEBOARD_FAB2_LIB.BASEBOARD_FAB2(SCH_1):FM_ROMA<20>
  R21  FM_ROMA<1>     ROMA<1>  @BASEBOARD_FAB2_LIB.BASEBOARD_FAB2(SCH_1):FM_ROMA<1>
  M18  FM_ROMA<19>    ROMA19_GPIOAB1_VPOR1  @BASEBOARD_FAB2_LIB.BASEBOARD_FAB2(SCH_1):FM_ROMA<19>
  N19  FM_ROMA<18>    ROMA18_GPIOAB0_VPOR0  @BASEBOARD_FAB2_LIB.BASEBOARD_FAB2(SCH_1):FM_ROMA<18>
  N18  FM_ROMA<17>    ROMA17_GPIOAA7_VPOG7  @BASEBOARD_FAB2_LIB.BASEBOARD_FAB2(SCH_1):FM_ROMA<17>
  T18  FM_ROMA<16>    ROMA16_GPIOAA6_VPOG6  @BASEBOARD_FAB2_LIB.BASEBOARD_FAB2(SCH_1):FM_ROMA<16>
  L21  FM_ROMA<15>    ROMA15_GPIOAA5_VPOG5  @BASEBOARD_FAB2_LIB.BASEBOARD_FAB2(SCH_1):FM_ROMA<15>
  L20  FM_ROMA<14>    ROMA14_GPIOAA4_VPOG4  @BASEBOARD_FAB2_LIB.BASEBOARD_FAB2(SCH_1):FM_ROMA<14>
  L19  FM_ROMA<13>    ROMA13_GPIOAA3_VPOG3  @BASEBOARD_FAB2_LIB.BASEBOARD_FAB2(SCH_1):FM_ROMA<13>
  L18  FM_ROMA<12>    ROMA12_GPIOAA2_VPOG2  @BASEBOARD_FAB2_LIB.BASEBOARD_FAB2(SCH_1):FM_ROMA<12>
  M22  FM_ROMA<11>    ROMA11_GPIOAA1_VPOG1  @BASEBOARD_FAB2_LIB.BASEBOARD_FAB2(SCH_1):FM_ROMA<11>
  M21  FM_ROMA<10>    ROMA10_GPIOAA0_VPOG0  @BASEBOARD_FAB2_LIB.BASEBOARD_FAB2(SCH_1):FM_ROMA<10>
  R20  FM_ROMA<0>     ROMA<0>  @BASEBOARD_FAB2_LIB.BASEBOARD_FAB2(SCH_1):FM_ROMA<0>
  Y22  FM_MB_SLOT_ID2  GPIOR2_ROMCS3_N  @BASEBOARD_FAB2_LIB.BASEBOARD_FAB2(SCH_1):FM_MB_SLOT_ID2
  W21  FM_MB_SLOT_ID1  GPIOR1_ROMCS2_N  @BASEBOARD_FAB2_LIB.BASEBOARD_FAB2(SCH_1):FM_MB_SLOT_ID1
  V20  FM_MB_SLOT_ID0  GPIOR0_ROMCS1_N  @BASEBOARD_FAB2_LIB.BASEBOARD_FAB2(SCH_1):FM_MB_SLOT_ID0
  U19  FM_FLASH_DESC_OVERRIDE_R  GPIOR3_ROMCS4_N  @BASEBOARD_FAB2_LIB.BASEBOARD_FAB2(SCH_1):FM_FLASH_DESC_OVERRIDE_R
  N21  FM_CPU_ERR2_LVT3_N  ROMWE_N_GPIOS5  @BASEBOARD_FAB2_LIB.BASEBOARD_FAB2(SCH_1):FM_CPU_ERR2_LVT3_N
   A5  FM_CPU1_SKTOCC_LVT3_N  GPIOR7_MDIO1  @BASEBOARD_FAB2_LIB.BASEBOARD_FAB2(SCH_1):FM_CPU1_SKTOCC_LVT3_N
   C6  FM_CPU0_SKTOCC_LVT3_N  GPIOR6_MDC1  @BASEBOARD_FAB2_LIB.BASEBOARD_FAB2(SCH_1):FM_CPU0_SKTOCC_LVT3_N
  V22  FM_BOARD_REV_ID2  ROMD6_GPIOS2_VPOVS  @BASEBOARD_FAB2_LIB.BASEBOARD_FAB2(SCH_1):FM_BOARD_REV_ID2
  T19  FM_BOARD_REV_ID1  ROMD5_GPIOS1_VPOHS  @BASEBOARD_FAB2_LIB.BASEBOARD_FAB2(SCH_1):FM_BOARD_REV_ID1
  U21  FM_BOARD_REV_ID0  ROMD4_GPIOS0_VPODE  @BASEBOARD_FAB2_LIB.BASEBOARD_FAB2(SCH_1):FM_BOARD_REV_ID0
  AA22  FM_BMC_NMI_N   GPIOG6_FLBUSY_N  @BASEBOARD_FAB2_LIB.BASEBOARD_FAB2(SCH_1):FM_BMC_NMI_N
  U20  FM_BIOS_MRC_DEBUG_MSG_DIS_N  ROMD7_GPIOS3_VPOCLK  @BASEBOARD_FAB2_LIB.BASEBOARD_FAB2(SCH_1):FM_BIOS_MRC_DEBUG_MSG_DIS_N

AST1250_BGA  I100  U9F4   [AST1250_BGA-IC,G85138-002]
   H5  UART_BMC_TXD5   TXD5  @BASEBOARD_FAB2_LIB.BASEBOARD_FAB2(SCH_1):UART_BMC_TXD5
   G1  UART_BMC_RXD5   RXD5  @BASEBOARD_FAB2_LIB.BASEBOARD_FAB2(SCH_1):UART_BMC_RXD5
   Y2  TP_GPIOM5_NRTS2_VPIB7  GPIOM5_NRTS2_VPIB7  @BASEBOARD_FAB2_LIB.BASEBOARD_FAB2(SCH_1):TP_GPIOM5_NRTS2_VPIB7
  B14  TP_GPIOE7_RXD3  GPIOE7_RXD3  @BASEBOARD_FAB2_LIB.BASEBOARD_FAB2(SCH_1):TP_GPIOE7_RXD3
  AA1  SP2_BMC_CM_UART_TX  GPIOM6_TXD2_VPIB8  @BASEBOARD_FAB2_LIB.BASEBOARD_FAB2(SCH_1):SP2_BMC_CM_UART_TX
   V5  SP2_BMC_CM_UART_RX  GPIOM7_RXD2_VPIB9  @BASEBOARD_FAB2_LIB.BASEBOARD_FAB2(SCH_1):SP2_BMC_CM_UART_RX
   W1  SP1_BMC_HOST_UART_TX  GPIOL6_TXD1_VPIB0  @BASEBOARD_FAB2_LIB.BASEBOARD_FAB2(SCH_1):SP1_BMC_HOST_UART_TX
   U5  SP1_BMC_HOST_UART_RX  GPIOL7_RXD1_VPIB1  @BASEBOARD_FAB2_LIB.BASEBOARD_FAB2(SCH_1):SP1_BMC_HOST_UART_RX
  C16  RST_SYSTEM_BTN_N  GPIOD4_SD2DAT2  @BASEBOARD_FAB2_LIB.BASEBOARD_FAB2(SCH_1):RST_SYSTEM_BTN_N
  K19  RST_PLTRST_BUF_N  PERST_N  @BASEBOARD_FAB2_LIB.BASEBOARD_FAB2(SCH_1):RST_PLTRST_BUF_N
  B16  RST_BMC_SYSRST_BTN_OUT_N  GPIOD5_SD2DAT3  @BASEBOARD_FAB2_LIB.BASEBOARD_FAB2(SCH_1):RST_BMC_SYSRST_BTN_OUT_N
  W20  RST_BMC_SRST_N  SRST_N  @BASEBOARD_FAB2_LIB.BASEBOARD_FAB2(SCH_1):RST_BMC_SRST_N
  B15  PWRGD_SYS_PWROK  GPIOE2_NDSR3  @BASEBOARD_FAB2_LIB.BASEBOARD_FAB2(SCH_1):PWRGD_SYS_PWROK
  C15  PWRGD_PCH_PWROK  GPIOE1_NDCD3  @BASEBOARD_FAB2_LIB.BASEBOARD_FAB2(SCH_1):PWRGD_PCH_PWROK
  AA21  PECI_BMC_R      PECI  @BASEBOARD_FAB2_LIB.BASEBOARD_FAB2(SCH_1):PECI_BMC_R
   E4  PD_SP_ENTEST   ENTEST  @BASEBOARD_FAB2_LIB.BASEBOARD_FAB2(SCH_1):PD_SP_ENTEST
  D20  PD_PEREXT      NC_PEREXT  @BASEBOARD_FAB2_LIB.BASEBOARD_FAB2(SCH_1):PD_PEREXT
  F21  P2E_SSB_BMC_TX_C_DP  NC_PERXP  @BASEBOARD_FAB2_LIB.BASEBOARD_FAB2(SCH_1):P2E_SSB_BMC_TX_C_DP
  F22  P2E_SSB_BMC_TX_C_DN  NC_PERXN  @BASEBOARD_FAB2_LIB.BASEBOARD_FAB2(SCH_1):P2E_SSB_BMC_TX_C_DN
  E22  P2E_SSB_BMC_RX_DP  NC_PETXP  @BASEBOARD_FAB2_LIB.BASEBOARD_FAB2(SCH_1):P2E_SSB_BMC_RX_DP
  E21  P2E_SSB_BMC_RX_DN  NC_PETXN  @BASEBOARD_FAB2_LIB.BASEBOARD_FAB2(SCH_1):P2E_SSB_BMC_RX_DN
   U1  IRQ_UV_DETECT_N  GPIOL0_NCTS1  @BASEBOARD_FAB2_LIB.BASEBOARD_FAB2(SCH_1):IRQ_UV_DETECT_N
  B18  IRQ_SML1_PMBUS_ALERT_N  GPIOF4_NDTR4  @BASEBOARD_FAB2_LIB.BASEBOARD_FAB2(SCH_1):IRQ_SML1_PMBUS_ALERT_N
  D15  IRQ_SML0_ALERT_N  GPIOE0_NCTS3  @BASEBOARD_FAB2_LIB.BASEBOARD_FAB2(SCH_1):IRQ_SML0_ALERT_N
   C3  IRQ_PVDDQ_KLM_VRHOT_LVT3_N  GPIOC5_SD1DAT3_SDA12  @BASEBOARD_FAB2_LIB.BASEBOARD_FAB2(SCH_1):IRQ_PVDDQ_KLM_VRHOT_LVT3_N
   D4  IRQ_PVDDQ_GHJ_VRHOT_LVT3_N  GPIOC4_SD1DAT2_SCL12  @BASEBOARD_FAB2_LIB.BASEBOARD_FAB2(SCH_1):IRQ_PVDDQ_GHJ_VRHOT_LVT3_N
   B3  IRQ_PVDDQ_DEF_VRHOT_LVT3_N  GPIOC1_SD1CMD_SDA10  @BASEBOARD_FAB2_LIB.BASEBOARD_FAB2(SCH_1):IRQ_PVDDQ_DEF_VRHOT_LVT3_N
   C4  IRQ_PVDDQ_ABC_VRHOT_LVT3_N  GPIOC0_SD1CLK_SCL10  @BASEBOARD_FAB2_LIB.BASEBOARD_FAB2(SCH_1):IRQ_PVDDQ_ABC_VRHOT_LVT3_N
  D17  IRQ_OOB_MGMT_RISER_ALERT_N  GPIOF3_NRI4_SIOPBO_N  @BASEBOARD_FAB2_LIB.BASEBOARD_FAB2(SCH_1):IRQ_OOB_MGMT_RISER_ALERT_N
   T5  IRQ_OC_DETECT_N  GPIOL1_NDCD1_VPIDE  @BASEBOARD_FAB2_LIB.BASEBOARD_FAB2(SCH_1):IRQ_OC_DETECT_N
  A19  IRQ_MEZZ_LAN_ALERT_N  GPIOF5_NRTS4_SIOSCI_N  @BASEBOARD_FAB2_LIB.BASEBOARD_FAB2(SCH_1):IRQ_MEZZ_LAN_ALERT_N
  E16  IRQ_LOM_ALERT_N  GPIOF6_TXD4  @BASEBOARD_FAB2_LIB.BASEBOARD_FAB2(SCH_1):IRQ_LOM_ALERT_N
  A20  IRQ_HSC_FAULT_N  GPIOF2_NDSR4_SIOPWRGD  @BASEBOARD_FAB2_LIB.BASEBOARD_FAB2(SCH_1):IRQ_HSC_FAULT_N
   Y1  IRQ_BOARD_BMC_ALERT_N  GPIOM2_NDSR2_VPIB4  @BASEBOARD_FAB2_LIB.BASEBOARD_FAB2(SCH_1):IRQ_BOARD_BMC_ALERT_N
  D14  IRQ_BMC_PCH_SMI_LPC_N  GPIOE5_NRTS3  @BASEBOARD_FAB2_LIB.BASEBOARD_FAB2(SCH_1):IRQ_BMC_PCH_SMI_LPC_N
  E14  IRQ_BMC_PCH_SCI_LPC_N  GPIOE4_NDTR3  @BASEBOARD_FAB2_LIB.BASEBOARD_FAB2(SCH_1):IRQ_BMC_PCH_SCI_LPC_N
  D16  IRQ_BMC_PCH_NMI_STBY_N  GPIOD1_SD2CMD  @BASEBOARD_FAB2_LIB.BASEBOARD_FAB2(SCH_1):IRQ_BMC_PCH_NMI_STBY_N
   A1  H_CPU1_MEMKLM_MEMHOT_LVT3_BMC_N  GPIOC7_SD1WP_N_SDA13  @BASEBOARD_FAB2_LIB.BASEBOARD_FAB2(SCH_1):H_CPU1_MEMKLM_MEMHOT_LVT3_BMC_N
   B2  H_CPU1_MEMGHJ_MEMHOT_LVT3_BMC_N  GPIOC6_SD1CD_N_SCL13  @BASEBOARD_FAB2_LIB.BASEBOARD_FAB2(SCH_1):H_CPU1_MEMGHJ_MEMHOT_LVT3_BMC_N
   E5  H_CPU0_MEMDEF_MEMHOT_LVT3_BMC_N  GPIOC3_SD1DAT1_SDA11  @BASEBOARD_FAB2_LIB.BASEBOARD_FAB2(SCH_1):H_CPU0_MEMDEF_MEMHOT_LVT3_BMC_N
   A2  H_CPU0_MEMABC_MEMHOT_LVT3_BMC_N  GPIOC2_SD1DAT0_SCL11  @BASEBOARD_FAB2_LIB.BASEBOARD_FAB2(SCH_1):H_CPU0_MEMABC_MEMHOT_LVT3_BMC_N
  C17  H_CPU0_FAST_WAKE_LVT3_N  GPIOF7_RXD4  @BASEBOARD_FAB2_LIB.BASEBOARD_FAB2(SCH_1):H_CPU0_FAST_WAKE_LVT3_N
   H3  FP_PWR_ID_LED_N  GPIOQ5_SDA14  @BASEBOARD_FAB2_LIB.BASEBOARD_FAB2(SCH_1):FP_PWR_ID_LED_N
  A18  FP_NMI_BTN_N   GPIOD0_SD2CLK  @BASEBOARD_FAB2_LIB.BASEBOARD_FAB2(SCH_1):FP_NMI_BTN_N
  B17  FM_PWR_BTN_N   GPIOD2_SD2DAT0  @BASEBOARD_FAB2_LIB.BASEBOARD_FAB2(SCH_1):FM_PWR_BTN_N
   V2  FM_PMBUS_ALERT_BUF_EN_N  GPIOL5_NRTS1_VPICLK  @BASEBOARD_FAB2_LIB.BASEBOARD_FAB2(SCH_1):FM_PMBUS_ALERT_BUF_EN_N
  J22  FM_PE_BMC_WAKE_N  NC_PEWAKE_N  @BASEBOARD_FAB2_LIB.BASEBOARD_FAB2(SCH_1):FM_PE_BMC_WAKE_N
  D18  FM_PCH_BMC_THERMTRIP_N  GPIOF0_NCTS4  @BASEBOARD_FAB2_LIB.BASEBOARD_FAB2(SCH_1):FM_PCH_BMC_THERMTRIP_N
   V4  FM_OC_DETECT_EN_N  GPIOM3_NRI2_VPIB5  @BASEBOARD_FAB2_LIB.BASEBOARD_FAB2(SCH_1):FM_OC_DETECT_EN_N
   U4  FM_MEM_THERM_EVENT_PCH_N  GPIOL4_NDTR1_VPIVS  @BASEBOARD_FAB2_LIB.BASEBOARD_FAB2(SCH_1):FM_MEM_THERM_EVENT_PCH_N
   U3  FM_HSC_TIMER_EXP_N  GPIOL2_NDSR1_VPIODD  @BASEBOARD_FAB2_LIB.BASEBOARD_FAB2(SCH_1):FM_HSC_TIMER_EXP_N
  E15  FM_CPU_ERR1_LVT3_BMC_N  GPIOD7_SD2WP_N  @BASEBOARD_FAB2_LIB.BASEBOARD_FAB2(SCH_1):FM_CPU_ERR1_LVT3_BMC_N
  A16  FM_CPU_ERR0_LVT3_BMC_N  GPIOD6_SD2CD_N  @BASEBOARD_FAB2_LIB.BASEBOARD_FAB2(SCH_1):FM_CPU_ERR0_LVT3_BMC_N
  B19  FM_CPU_CATERR_LVT3_N  GPIOF1_NDCD4_SIOPBI_N  @BASEBOARD_FAB2_LIB.BASEBOARD_FAB2(SCH_1):FM_CPU_CATERR_LVT3_N
   W2  FM_CPU1_RC_ERROR_N  GPIOM1_NDCD2_VPIB3  @BASEBOARD_FAB2_LIB.BASEBOARD_FAB2(SCH_1):FM_CPU1_RC_ERROR_N
   H1  FM_CPU1_FIVR_FAULT_LVT3_R_N  GPIOQ<7>  @BASEBOARD_FAB2_LIB.BASEBOARD_FAB2(SCH_1):FM_CPU1_FIVR_FAULT_LVT3_R_N
   V3  FM_CPU0_RC_ERROR_N  GPIOM0_NCTS2_VPIB2  @BASEBOARD_FAB2_LIB.BASEBOARD_FAB2(SCH_1):FM_CPU0_RC_ERROR_N
   H2  FM_CPU0_FIVR_FAULT_LVT3_R_N  GPIOQ<6>  @BASEBOARD_FAB2_LIB.BASEBOARD_FAB2(SCH_1):FM_CPU0_FIVR_FAULT_LVT3_R_N
   D6  FM_CPLD_BMC_PWRDN_N  GPIOA0_MAC1LINK  @BASEBOARD_FAB2_LIB.BASEBOARD_FAB2(SCH_1):FM_CPLD_BMC_PWRDN_N
   W3  FM_BOARD_SKU_ID4  GPIOM4_NDTR2_VPIB6  @BASEBOARD_FAB2_LIB.BASEBOARD_FAB2(SCH_1):FM_BOARD_SKU_ID4
   E6  FM_BMC_SYS_THROTTLE_R_N  GPIOA3_TIMER4  @BASEBOARD_FAB2_LIB.BASEBOARD_FAB2(SCH_1):FM_BMC_SYS_THROTTLE_R_N
   H4  FM_BMC_READY_N  GPIOQ4_SCL14  @BASEBOARD_FAB2_LIB.BASEBOARD_FAB2(SCH_1):FM_BMC_READY_N
  A17  FM_BMC_PWRBTN_OUT_N  GPIOD3_SD2DAT1  @BASEBOARD_FAB2_LIB.BASEBOARD_FAB2(SCH_1):FM_BMC_PWRBTN_OUT_N
  K20  FM_BMC_ONCTL_R_N  GPIOY3_SIOONCTRL_N  @BASEBOARD_FAB2_LIB.BASEBOARD_FAB2(SCH_1):FM_BMC_ONCTL_R_N
   B5  FM_BMC_FAULT_LED_N  GPIOA1_MAC2LINK  @BASEBOARD_FAB2_LIB.BASEBOARD_FAB2(SCH_1):FM_BMC_FAULT_LED_N
  C14  FM_BMC_CPLD_MP_RST_N  GPIOE6_TXD3  @BASEBOARD_FAB2_LIB.BASEBOARD_FAB2(SCH_1):FM_BMC_CPLD_MP_RST_N
  E18  FM_BMC_CPLD_GPO  GPIOB7_EXTRST_N_SPICS1_N  @BASEBOARD_FAB2_LIB.BASEBOARD_FAB2(SCH_1):FM_BMC_CPLD_GPO
   V1  FM_BIOS_TOP_SWAP  GPIOL3_NRI1_VPIHS  @BASEBOARD_FAB2_LIB.BASEBOARD_FAB2(SCH_1):FM_BIOS_TOP_SWAP
   A4  FM_BIOS_POST_CMPLT_N  GPIOA2_TIMER3  @BASEBOARD_FAB2_LIB.BASEBOARD_FAB2(SCH_1):FM_BIOS_POST_CMPLT_N
  A15  FM_BB_BMC_MP_GPIO  GPIOE3_NRI3  @BASEBOARD_FAB2_LIB.BASEBOARD_FAB2(SCH_1):FM_BB_BMC_MP_GPIO
  B13  FM_BATTERY_SENSE_EN_N  GPIOG4_WDTRST1_OSCCLK  @BASEBOARD_FAB2_LIB.BASEBOARD_FAB2(SCH_1):FM_BATTERY_SENSE_EN_N
  Y21  CLK_48M_USB_BMC  GPIOG5_WDTRST2_USBCKI  @BASEBOARD_FAB2_LIB.BASEBOARD_FAB2(SCH_1):CLK_48M_USB_BMC
  AB22  CLK_24M_25M_BMC_CLKIN  CLKIN  @BASEBOARD_FAB2_LIB.BASEBOARD_FAB2(SCH_1):CLK_24M_25M_BMC_CLKIN
  G22  CLK_100M_BMC_PE_R_DP  NC_PEREFCLKP  @BASEBOARD_FAB2_LIB.BASEBOARD_FAB2(SCH_1):CLK_100M_BMC_PE_R_DP
  G21  CLK_100M_BMC_PE_R_DN  NC_PEREFCLKN  @BASEBOARD_FAB2_LIB.BASEBOARD_FAB2(SCH_1):CLK_100M_BMC_PE_R_DN

AST1250_BGA  I347  U9F4   [AST1250_BGA-IC,G85138-002]
   K4  USB_PCH_BMC_P4_DP  DP_USB11_DP_USB11_HDP2  @BASEBOARD_FAB2_LIB.BASEBOARD_FAB2(SCH_1):USB_PCH_BMC_P4_DP
   K3  USB_PCH_BMC_P4_DN  DN_USB11_DN_USB11_HDN2  @BASEBOARD_FAB2_LIB.BASEBOARD_FAB2(SCH_1):USB_PCH_BMC_P4_DN
  AB21  USB2_PCH_BMC_P5_DP  DP_USB2_DP_USB2_HDP  @BASEBOARD_FAB2_LIB.BASEBOARD_FAB2(SCH_1):USB2_PCH_BMC_P5_DP
  AB20  USB2_PCH_BMC_P5_DN  DN_USB2_DN_USB2_HDN  @BASEBOARD_FAB2_LIB.BASEBOARD_FAB2(SCH_1):USB2_PCH_BMC_P5_DN
   U2  TP_VGAVS_GPIOJ5  VGAVS_GPIOJ5  @BASEBOARD_FAB2_LIB.BASEBOARD_FAB2(SCH_1):TP_VGAVS_GPIOJ5
   T4  TP_VGAHS_GPIOJ4  VGAHS_GPIOJ4  @BASEBOARD_FAB2_LIB.BASEBOARD_FAB2(SCH_1):TP_VGAHS_GPIOJ4
  D19  TP_SPI_PCH_BIOS_MOSI_R  GPIOI2_SYSDO  @BASEBOARD_FAB2_LIB.BASEBOARD_FAB2(SCH_1):TP_SPI_PCH_BIOS_MOSI_R
  C20  TP_SPI_PCH_BIOS_MISO_R  GPIOI3_SYSDI  @BASEBOARD_FAB2_LIB.BASEBOARD_FAB2(SCH_1):TP_SPI_PCH_BIOS_MISO_R
  C22  TP_SPI_PCH_BIOS_CS0_R_N  GPIOI0_SYSCS_N  @BASEBOARD_FAB2_LIB.BASEBOARD_FAB2(SCH_1):TP_SPI_PCH_BIOS_CS0_R_N
  G18  TP_SPI_PCH_BIOS_CLK_R  GPIOI1_SYSCK  @BASEBOARD_FAB2_LIB.BASEBOARD_FAB2(SCH_1):TP_SPI_PCH_BIOS_CLK_R
   G4  TP_JTAG_BMC_RTCK   RTCK  @BASEBOARD_FAB2_LIB.BASEBOARD_FAB2(SCH_1):TP_JTAG_BMC_RTCK
   T1  TP_DDCDAT_GPIOJ7  DDCDAT_GPIOJ7  @BASEBOARD_FAB2_LIB.BASEBOARD_FAB2(SCH_1):TP_DDCDAT_GPIOJ7
   T2  TP_DDCCLK_GPIOJ6  DDCCLK_GPIOJ6  @BASEBOARD_FAB2_LIB.BASEBOARD_FAB2(SCH_1):TP_DDCCLK_GPIOJ6
   R2  TP_DACR         DACR  @BASEBOARD_FAB2_LIB.BASEBOARD_FAB2(SCH_1):TP_DACR
   R3  TP_DACG         DACG  @BASEBOARD_FAB2_LIB.BASEBOARD_FAB2(SCH_1):TP_DACG
   R4  TP_DACB         DACB  @BASEBOARD_FAB2_LIB.BASEBOARD_FAB2(SCH_1):TP_DACB
  C18  SPI_BMC_DO     GPIOI6_SPIDO_VBDO  @BASEBOARD_FAB2_LIB.BASEBOARD_FAB2(SCH_1):SPI_BMC_DO
  E20  SPI_BMC_DI     GPIOI7_SPIDI_VBDI  @BASEBOARD_FAB2_LIB.BASEBOARD_FAB2(SCH_1):SPI_BMC_DI
  B22  SPI_BMC_CS0_N  GPIOI4_SPICS0_N_VBCS_N  @BASEBOARD_FAB2_LIB.BASEBOARD_FAB2(SCH_1):SPI_BMC_CS0_N
  G19  SPI_BMC_CLK    GPIOI5_SPICK_VBCK  @BASEBOARD_FAB2_LIB.BASEBOARD_FAB2(SCH_1):SPI_BMC_CLK
   F4  SMB_VR_STBY_LVC3_SDA_R  GPIOK3_SDA6  @BASEBOARD_FAB2_LIB.BASEBOARD_FAB2(SCH_1):SMB_VR_STBY_LVC3_SDA_R
   C1  SMB_VR_STBY_LVC3_SCL_R  GPIOK2_SCL6  @BASEBOARD_FAB2_LIB.BASEBOARD_FAB2(SCH_1):SMB_VR_STBY_LVC3_SCL_R
   D2  SMB_SMLINK0_STBY_LVC3_SDA_R  GPIOK1_SDA5  @BASEBOARD_FAB2_LIB.BASEBOARD_FAB2(SCH_1):SMB_SMLINK0_STBY_LVC3_SDA_R
   E3  SMB_SMLINK0_STBY_LVC3_SCL_R  GPIOK0_SCL5  @BASEBOARD_FAB2_LIB.BASEBOARD_FAB2(SCH_1):SMB_SMLINK0_STBY_LVC3_SCL_R
  J18  SMB_SLOTX24_STBY_LVC3_SDA_R  SDA<2>  @BASEBOARD_FAB2_LIB.BASEBOARD_FAB2(SCH_1):SMB_SLOTX24_STBY_LVC3_SDA_R
  J19  SMB_SLOTX24_STBY_LVC3_SCL_R  SCL<2>  @BASEBOARD_FAB2_LIB.BASEBOARD_FAB2(SCH_1):SMB_SLOTX24_STBY_LVC3_SCL_R
   D1  SMB_SENSOR_BMC_STBY_LVC3_SDA  GPIOK5_SDA7  @BASEBOARD_FAB2_LIB.BASEBOARD_FAB2(SCH_1):SMB_SENSOR_BMC_STBY_LVC3_SDA
   E2  SMB_SENSOR_BMC_STBY_LVC3_SCL  GPIOK4_SCL7  @BASEBOARD_FAB2_LIB.BASEBOARD_FAB2(SCH_1):SMB_SENSOR_BMC_STBY_LVC3_SCL
   C2  SMB_OCP_LAN_STBY_LVC3_SDA_R  GPIOQ1_SDA3  @BASEBOARD_FAB2_LIB.BASEBOARD_FAB2(SCH_1):SMB_OCP_LAN_STBY_LVC3_SDA_R
   D3  SMB_OCP_LAN_STBY_LVC3_SCL_R  GPIOQ0_SCL3  @BASEBOARD_FAB2_LIB.BASEBOARD_FAB2(SCH_1):SMB_OCP_LAN_STBY_LVC3_SCL_R
   B4  SMB_OCP_FRU_STBY_LVC3_SDA_R  GPIOA5_TIMER6_SDA9  @BASEBOARD_FAB2_LIB.BASEBOARD_FAB2(SCH_1):SMB_OCP_FRU_STBY_LVC3_SDA_R
   C5  SMB_OCP_FRU_STBY_LVC3_SCL_R  GPIOA4_TIMER5_SCL9  @BASEBOARD_FAB2_LIB.BASEBOARD_FAB2(SCH_1):SMB_OCP_FRU_STBY_LVC3_SCL_R
  K22  SMB_LAN_STBY_LVC3_SDA_R  SDA<1>  @BASEBOARD_FAB2_LIB.BASEBOARD_FAB2(SCH_1):SMB_LAN_STBY_LVC3_SDA_R
  K21  SMB_LAN_STBY_LVC3_SCL_R  SCL<1>  @BASEBOARD_FAB2_LIB.BASEBOARD_FAB2(SCH_1):SMB_LAN_STBY_LVC3_SCL_R
   F5  SMB_HOST_STBY_LVC3_SDA_R  GPIOQ3_SDA4  @BASEBOARD_FAB2_LIB.BASEBOARD_FAB2(SCH_1):SMB_HOST_STBY_LVC3_SDA_R
   B1  SMB_HOST_STBY_LVC3_SCL_R  GPIOQ2_SCL4  @BASEBOARD_FAB2_LIB.BASEBOARD_FAB2(SCH_1):SMB_HOST_STBY_LVC3_SCL_R
   F3  SMB_BMC_PMBUS_STBY_LVC3_SDA_R  GPIOK7_SDA8  @BASEBOARD_FAB2_LIB.BASEBOARD_FAB2(SCH_1):SMB_BMC_PMBUS_STBY_LVC3_SDA_R
   G5  SMB_BMC_PMBUS_STBY_LVC3_SCL_R  GPIOK6_SCL8  @BASEBOARD_FAB2_LIB.BASEBOARD_FAB2(SCH_1):SMB_BMC_PMBUS_STBY_LVC3_SCL_R
   J4  SGPIO_BMC_LD_R_N  GPIOJ1_SGPMLD  @BASEBOARD_FAB2_LIB.BASEBOARD_FAB2(SCH_1):SGPIO_BMC_LD_R_N
   K5  SGPIO_BMC_DOUT_R  GPIOJ2_SGPMO  @BASEBOARD_FAB2_LIB.BASEBOARD_FAB2(SCH_1):SGPIO_BMC_DOUT_R
   J3  SGPIO_BMC_DIN  GPIOJ3_SGPMI  @BASEBOARD_FAB2_LIB.BASEBOARD_FAB2(SCH_1):SGPIO_BMC_DIN
   J5  SGPIO_BMC_CLK_R  GPIOJ0_SGPMCK  @BASEBOARD_FAB2_LIB.BASEBOARD_FAB2(SCH_1):SGPIO_BMC_CLK_R
  E19  RST_BMC_LVC3_N  GPIOB4_LPCRST_N  @BASEBOARD_FAB2_LIB.BASEBOARD_FAB2(SCH_1):RST_BMC_LVC3_N
   J1  PD_USB_BMC_P1_DP  USB11_HDP  @BASEBOARD_FAB2_LIB.BASEBOARD_FAB2(SCH_1):PD_USB_BMC_P1_DP
   J2  PD_USB_BMC_P1_DN  USB11_HDN  @BASEBOARD_FAB2_LIB.BASEBOARD_FAB2(SCH_1):PD_USB_BMC_P1_DN
  A21  LPC_LFRAME_N_CS0_R_N  LFRAME_N  @BASEBOARD_FAB2_LIB.BASEBOARD_FAB2(SCH_1):LPC_LFRAME_N_CS0_R_N
  C19  LPC_LAD3_IO3_R  LAD<3>  @BASEBOARD_FAB2_LIB.BASEBOARD_FAB2(SCH_1):LPC_LAD3_IO3_R
  F19  LPC_LAD2_IO2_R  LAD<2>  @BASEBOARD_FAB2_LIB.BASEBOARD_FAB2(SCH_1):LPC_LAD2_IO2_R
  A22  LPC_LAD1_IO1_R  LAD<1>  @BASEBOARD_FAB2_LIB.BASEBOARD_FAB2(SCH_1):LPC_LAD1_IO1_R
  B21  LPC_LAD0_IO0_R  LAD<0>  @BASEBOARD_FAB2_LIB.BASEBOARD_FAB2(SCH_1):LPC_LAD0_IO0_R
   E1  JTAG_BMC_TRST_N  NTRST  @BASEBOARD_FAB2_LIB.BASEBOARD_FAB2(SCH_1):JTAG_BMC_TRST_N
   G2  JTAG_BMC_TMS     TMS  @BASEBOARD_FAB2_LIB.BASEBOARD_FAB2(SCH_1):JTAG_BMC_TMS
   G3  JTAG_BMC_TDO     TDO  @BASEBOARD_FAB2_LIB.BASEBOARD_FAB2(SCH_1):JTAG_BMC_TDO
   F1  JTAG_BMC_TDI     TDI  @BASEBOARD_FAB2_LIB.BASEBOARD_FAB2(SCH_1):JTAG_BMC_TDI
   F2  JTAG_BMC_TCK     TCK  @BASEBOARD_FAB2_LIB.BASEBOARD_FAB2(SCH_1):JTAG_BMC_TCK
  E13  IRQ_PCH_NIC_ALERT_N  GPIOG1_SGPSLD  @BASEBOARD_FAB2_LIB.BASEBOARD_FAB2(SCH_1):IRQ_PCH_NIC_ALERT_N
  E17  IRQ_LPC_SERIRQ_R  LSIRQ_N  @BASEBOARD_FAB2_LIB.BASEBOARD_FAB2(SCH_1):IRQ_LPC_SERIRQ_R
  C13  FM_SLPS4_N     GPIOG3_SGPSI1  @BASEBOARD_FAB2_LIB.BASEBOARD_FAB2(SCH_1):FM_SLPS4_N
  D13  FM_SLPS3_N     GPIOG2_SGPSI0  @BASEBOARD_FAB2_LIB.BASEBOARD_FAB2(SCH_1):FM_SLPS3_N
  H18  FM_POST_CARD_PRES_BMC_N  GPIOB2_SALT3  @BASEBOARD_FAB2_LIB.BASEBOARD_FAB2(SCH_1):FM_POST_CARD_PRES_BMC_N
  F18  FM_FAST_PROCHOT_EN_N  GPIOB3_SALT4  @BASEBOARD_FAB2_LIB.BASEBOARD_FAB2(SCH_1):FM_FAST_PROCHOT_EN_N
  A14  FM_CPU_BMC_INIT  GPIOG0_SGPSCK  @BASEBOARD_FAB2_LIB.BASEBOARD_FAB2(SCH_1):FM_CPU_BMC_INIT
  H20  FM_CPU1_THERMTRIP_LATCH_LVT3_N  GPIOB6_LPCPME_N  @BASEBOARD_FAB2_LIB.BASEBOARD_FAB2(SCH_1):FM_CPU1_THERMTRIP_LATCH_LVT3_N
  H19  FM_CPU0_THERMTRIP_LATCH_LVT3_N  GPIOB5_LPCPD_N_LPCSMI_N  @BASEBOARD_FAB2_LIB.BASEBOARD_FAB2(SCH_1):FM_CPU0_THERMTRIP_LATCH_LVT3_N
  J21  FM_BMC_HEARTBEAT_N  GPIOB0_SALT1  @BASEBOARD_FAB2_LIB.BASEBOARD_FAB2(SCH_1):FM_BMC_HEARTBEAT_N
  J20  FM_BIOS_SMI_ACTIVE_N  GPIOB1_SALT2  @BASEBOARD_FAB2_LIB.BASEBOARD_FAB2(SCH_1):FM_BIOS_SMI_ACTIVE_N
  B20  CLK_24M_BMC_LPC   LCLK  @BASEBOARD_FAB2_LIB.BASEBOARD_FAB2(SCH_1):CLK_24M_BMC_LPC
  AA20  A_USB2VRES     USB2VRES  @BASEBOARD_FAB2_LIB.BASEBOARD_FAB2(SCH_1):A_USB2VRES
   R1  A_DACRSET      DACRSET  @BASEBOARD_FAB2_LIB.BASEBOARD_FAB2(SCH_1):A_DACRSET

AST1250_BGA  I281  U9F4   [AST1250_BGA-IC,G85138-002]
  V16  TP_M_BMC_DDR3_MIOZ   MIOZ  @BASEBOARD_FAB2_LIB.BASEBOARD_FAB2(SCH_1):TP_M_BMC_DDR3_MIOZ
  Y13  M_BMC_DDR3_MWE_N  MWE_N  @BASEBOARD_FAB2_LIB.BASEBOARD_FAB2(SCH_1):M_BMC_DDR3_MWE_N
  V13  M_BMC_DDR3_MVREF  MVREF  @BASEBOARD_FAB2_LIB.BASEBOARD_FAB2(SCH_1):M_BMC_DDR3_MVREF
  W13  M_BMC_DDR3_MRAS_N  MRAS_N  @BASEBOARD_FAB2_LIB.BASEBOARD_FAB2(SCH_1):M_BMC_DDR3_MRAS_N
  V14  M_BMC_DDR3_MODT   MODT  @BASEBOARD_FAB2_LIB.BASEBOARD_FAB2(SCH_1):M_BMC_DDR3_MODT
  AA8  M_BMC_DDR3_MDQS_1_DP  MDQS1  @BASEBOARD_FAB2_LIB.BASEBOARD_FAB2(SCH_1):M_BMC_DDR3_MDQS_1_DP
  AB8  M_BMC_DDR3_MDQS_1_DN  MDQS1_N  @BASEBOARD_FAB2_LIB.BASEBOARD_FAB2(SCH_1):M_BMC_DDR3_MDQS_1_DN
  AB10  M_BMC_DDR3_MDQS_0_DP  MDQS0  @BASEBOARD_FAB2_LIB.BASEBOARD_FAB2(SCH_1):M_BMC_DDR3_MDQS_0_DP
  AA10  M_BMC_DDR3_MDQS_0_DN  MDQS0_N  @BASEBOARD_FAB2_LIB.BASEBOARD_FAB2(SCH_1):M_BMC_DDR3_MDQS_0_DN
   V8  M_BMC_DDR3_MDM_1  MDM<1>  @BASEBOARD_FAB2_LIB.BASEBOARD_FAB2(SCH_1):M_BMC_DDR3_MDM_1
  W10  M_BMC_DDR3_MDM_0  MDM<0>  @BASEBOARD_FAB2_LIB.BASEBOARD_FAB2(SCH_1):M_BMC_DDR3_MDM_0
  AA13  M_BMC_DDR3_MCS_N  MCS_N  @BASEBOARD_FAB2_LIB.BASEBOARD_FAB2(SCH_1):M_BMC_DDR3_MCS_N
  AB12  M_BMC_DDR3_MCK_P   MCKP  @BASEBOARD_FAB2_LIB.BASEBOARD_FAB2(SCH_1):M_BMC_DDR3_MCK_P
  AA12  M_BMC_DDR3_MCK_N   MCKN  @BASEBOARD_FAB2_LIB.BASEBOARD_FAB2(SCH_1):M_BMC_DDR3_MCK_N
  Y12  M_BMC_DDR3_MCKE   MCKE  @BASEBOARD_FAB2_LIB.BASEBOARD_FAB2(SCH_1):M_BMC_DDR3_MCKE
  AB13  M_BMC_DDR3_MCAS_N  MCAS_N  @BASEBOARD_FAB2_LIB.BASEBOARD_FAB2(SCH_1):M_BMC_DDR3_MCAS_N
  Y14  M_BMC_DDR3_MBA_2  MBA<2>  @BASEBOARD_FAB2_LIB.BASEBOARD_FAB2(SCH_1):M_BMC_DDR3_MBA_2
  AA14  M_BMC_DDR3_MBA_1  MBA<1>  @BASEBOARD_FAB2_LIB.BASEBOARD_FAB2(SCH_1):M_BMC_DDR3_MBA_1
  W14  M_BMC_DDR3_MBA_0  MBA<0>  @BASEBOARD_FAB2_LIB.BASEBOARD_FAB2(SCH_1):M_BMC_DDR3_MBA_0
  AA17  M_BMC_DDR3_MA<9>  MA<9>  @BASEBOARD_FAB2_LIB.BASEBOARD_FAB2(SCH_1):M_BMC_DDR3_MA<9>
  AB16  M_BMC_DDR3_MA<8>  MA<8>  @BASEBOARD_FAB2_LIB.BASEBOARD_FAB2(SCH_1):M_BMC_DDR3_MA<8>
  AB18  M_BMC_DDR3_MA<7>  MA<7>  @BASEBOARD_FAB2_LIB.BASEBOARD_FAB2(SCH_1):M_BMC_DDR3_MA<7>
  AA15  M_BMC_DDR3_MA<6>  MA<6>  @BASEBOARD_FAB2_LIB.BASEBOARD_FAB2(SCH_1):M_BMC_DDR3_MA<6>
  W16  M_BMC_DDR3_MA<5>  MA<5>  @BASEBOARD_FAB2_LIB.BASEBOARD_FAB2(SCH_1):M_BMC_DDR3_MA<5>
  AB15  M_BMC_DDR3_MA<4>  MA<4>  @BASEBOARD_FAB2_LIB.BASEBOARD_FAB2(SCH_1):M_BMC_DDR3_MA<4>
  Y16  M_BMC_DDR3_MA<3>  MA<3>  @BASEBOARD_FAB2_LIB.BASEBOARD_FAB2(SCH_1):M_BMC_DDR3_MA<3>
  V15  M_BMC_DDR3_MA<2>  MA<2>  @BASEBOARD_FAB2_LIB.BASEBOARD_FAB2(SCH_1):M_BMC_DDR3_MA<2>
  W15  M_BMC_DDR3_MA<1>  MA<1>  @BASEBOARD_FAB2_LIB.BASEBOARD_FAB2(SCH_1):M_BMC_DDR3_MA<1>
  AB17  M_BMC_DDR3_MA<14>  MA<14>  @BASEBOARD_FAB2_LIB.BASEBOARD_FAB2(SCH_1):M_BMC_DDR3_MA<14>
  Y17  M_BMC_DDR3_MA<13>  MA<13>  @BASEBOARD_FAB2_LIB.BASEBOARD_FAB2(SCH_1):M_BMC_DDR3_MA<13>
  W17  M_BMC_DDR3_MA<12>  MA<12>  @BASEBOARD_FAB2_LIB.BASEBOARD_FAB2(SCH_1):M_BMC_DDR3_MA<12>
  AA16  M_BMC_DDR3_MA<11>  MA<11>  @BASEBOARD_FAB2_LIB.BASEBOARD_FAB2(SCH_1):M_BMC_DDR3_MA<11>
  Y15  M_BMC_DDR3_MA<10>  MA<10>  @BASEBOARD_FAB2_LIB.BASEBOARD_FAB2(SCH_1):M_BMC_DDR3_MA<10>
  AB14  M_BMC_DDR3_MA<0>  MA<0>  @BASEBOARD_FAB2_LIB.BASEBOARD_FAB2(SCH_1):M_BMC_DDR3_MA<0>
  AB9  M_BMC_DDR3_DQ<9>  MDQ<9>  @BASEBOARD_FAB2_LIB.BASEBOARD_FAB2(SCH_1):M_BMC_DDR3_DQ<9>
  V10  M_BMC_DDR3_DQ<8>  MDQ<8>  @BASEBOARD_FAB2_LIB.BASEBOARD_FAB2(SCH_1):M_BMC_DDR3_DQ<8>
  Y10  M_BMC_DDR3_DQ<7>  MDQ<7>  @BASEBOARD_FAB2_LIB.BASEBOARD_FAB2(SCH_1):M_BMC_DDR3_DQ<7>
  V11  M_BMC_DDR3_DQ<6>  MDQ<6>  @BASEBOARD_FAB2_LIB.BASEBOARD_FAB2(SCH_1):M_BMC_DDR3_DQ<6>
  W11  M_BMC_DDR3_DQ<5>  MDQ<5>  @BASEBOARD_FAB2_LIB.BASEBOARD_FAB2(SCH_1):M_BMC_DDR3_DQ<5>
  Y11  M_BMC_DDR3_DQ<4>  MDQ<4>  @BASEBOARD_FAB2_LIB.BASEBOARD_FAB2(SCH_1):M_BMC_DDR3_DQ<4>
  AA11  M_BMC_DDR3_DQ<3>  MDQ<3>  @BASEBOARD_FAB2_LIB.BASEBOARD_FAB2(SCH_1):M_BMC_DDR3_DQ<3>
  AB11  M_BMC_DDR3_DQ<2>  MDQ<2>  @BASEBOARD_FAB2_LIB.BASEBOARD_FAB2(SCH_1):M_BMC_DDR3_DQ<2>
  V12  M_BMC_DDR3_DQ<1>  MDQ<1>  @BASEBOARD_FAB2_LIB.BASEBOARD_FAB2(SCH_1):M_BMC_DDR3_DQ<1>
   W8  M_BMC_DDR3_DQ<15>  MDQ<15>  @BASEBOARD_FAB2_LIB.BASEBOARD_FAB2(SCH_1):M_BMC_DDR3_DQ<15>
   Y8  M_BMC_DDR3_DQ<14>  MDQ<14>  @BASEBOARD_FAB2_LIB.BASEBOARD_FAB2(SCH_1):M_BMC_DDR3_DQ<14>
   V9  M_BMC_DDR3_DQ<13>  MDQ<13>  @BASEBOARD_FAB2_LIB.BASEBOARD_FAB2(SCH_1):M_BMC_DDR3_DQ<13>
   W9  M_BMC_DDR3_DQ<12>  MDQ<12>  @BASEBOARD_FAB2_LIB.BASEBOARD_FAB2(SCH_1):M_BMC_DDR3_DQ<12>
   Y9  M_BMC_DDR3_DQ<11>  MDQ<11>  @BASEBOARD_FAB2_LIB.BASEBOARD_FAB2(SCH_1):M_BMC_DDR3_DQ<11>
  AA9  M_BMC_DDR3_DQ<10>  MDQ<10>  @BASEBOARD_FAB2_LIB.BASEBOARD_FAB2(SCH_1):M_BMC_DDR3_DQ<10>
  W12  M_BMC_DDR3_DQ<0>  MDQ<0>  @BASEBOARD_FAB2_LIB.BASEBOARD_FAB2(SCH_1):M_BMC_DDR3_DQ<0>

K4B1G16_BGA1  I1   U9F5   [K4B1G16_BGA1-IC,G38649-001]
   M7  TP_K4B1G16_BMC_NC4  NC<4>  @BASEBOARD_FAB2_LIB.BASEBOARD_FAB2(SCH_1):TP_K4B1G16_BMC_NC4
   L9  TP_K4B1G16_BMC_NC3  NC<3>  @BASEBOARD_FAB2_LIB.BASEBOARD_FAB2(SCH_1):TP_K4B1G16_BMC_NC3
   L1  TP_K4B1G16_BMC_NC2  NC<2>  @BASEBOARD_FAB2_LIB.BASEBOARD_FAB2(SCH_1):TP_K4B1G16_BMC_NC2
   J9  TP_K4B1G16_BMC_NC1  NC<1>  @BASEBOARD_FAB2_LIB.BASEBOARD_FAB2(SCH_1):TP_K4B1G16_BMC_NC1
   J1  TP_K4B1G16_BMC_NC0  NC<0>  @BASEBOARD_FAB2_LIB.BASEBOARD_FAB2(SCH_1):TP_K4B1G16_BMC_NC0
   T2  RST_BMC_DDR3_N  RESET_N  @BASEBOARD_FAB2_LIB.BASEBOARD_FAB2(SCH_1):RST_BMC_DDR3_N
   H9  P1V538_BMC_STBY  VDDQ<8>  @BASEBOARD_FAB2_LIB.BASEBOARD_FAB2(SCH_1):P1V538_BMC_STBY
   H2  P1V538_BMC_STBY  VDDQ<7>  @BASEBOARD_FAB2_LIB.BASEBOARD_FAB2(SCH_1):P1V538_BMC_STBY
   F1  P1V538_BMC_STBY  VDDQ<6>  @BASEBOARD_FAB2_LIB.BASEBOARD_FAB2(SCH_1):P1V538_BMC_STBY
   E9  P1V538_BMC_STBY  VDDQ<5>  @BASEBOARD_FAB2_LIB.BASEBOARD_FAB2(SCH_1):P1V538_BMC_STBY
   D2  P1V538_BMC_STBY  VDDQ<4>  @BASEBOARD_FAB2_LIB.BASEBOARD_FAB2(SCH_1):P1V538_BMC_STBY
   C9  P1V538_BMC_STBY  VDDQ<3>  @BASEBOARD_FAB2_LIB.BASEBOARD_FAB2(SCH_1):P1V538_BMC_STBY
   C1  P1V538_BMC_STBY  VDDQ<2>  @BASEBOARD_FAB2_LIB.BASEBOARD_FAB2(SCH_1):P1V538_BMC_STBY
   A8  P1V538_BMC_STBY  VDDQ<1>  @BASEBOARD_FAB2_LIB.BASEBOARD_FAB2(SCH_1):P1V538_BMC_STBY
   A1  P1V538_BMC_STBY  VDDQ<0>  @BASEBOARD_FAB2_LIB.BASEBOARD_FAB2(SCH_1):P1V538_BMC_STBY
   R9  P1V538_BMC_STBY  VDD<8>  @BASEBOARD_FAB2_LIB.BASEBOARD_FAB2(SCH_1):P1V538_BMC_STBY
   R1  P1V538_BMC_STBY  VDD<7>  @BASEBOARD_FAB2_LIB.BASEBOARD_FAB2(SCH_1):P1V538_BMC_STBY
   N9  P1V538_BMC_STBY  VDD<6>  @BASEBOARD_FAB2_LIB.BASEBOARD_FAB2(SCH_1):P1V538_BMC_STBY
   N1  P1V538_BMC_STBY  VDD<5>  @BASEBOARD_FAB2_LIB.BASEBOARD_FAB2(SCH_1):P1V538_BMC_STBY
   K8  P1V538_BMC_STBY  VDD<4>  @BASEBOARD_FAB2_LIB.BASEBOARD_FAB2(SCH_1):P1V538_BMC_STBY
   K2  P1V538_BMC_STBY  VDD<3>  @BASEBOARD_FAB2_LIB.BASEBOARD_FAB2(SCH_1):P1V538_BMC_STBY
   G7  P1V538_BMC_STBY  VDD<2>  @BASEBOARD_FAB2_LIB.BASEBOARD_FAB2(SCH_1):P1V538_BMC_STBY
   D9  P1V538_BMC_STBY  VDD<1>  @BASEBOARD_FAB2_LIB.BASEBOARD_FAB2(SCH_1):P1V538_BMC_STBY
   B2  P1V538_BMC_STBY  VDD<0>  @BASEBOARD_FAB2_LIB.BASEBOARD_FAB2(SCH_1):P1V538_BMC_STBY
   L3  M_BMC_DDR3_MWE_N   WE_N  @BASEBOARD_FAB2_LIB.BASEBOARD_FAB2(SCH_1):M_BMC_DDR3_MWE_N
   H1  M_BMC_DDR3_MVREF  VREFDQ  @BASEBOARD_FAB2_LIB.BASEBOARD_FAB2(SCH_1):M_BMC_DDR3_MVREF
   M8  M_BMC_DDR3_MVREF  VREFCA  @BASEBOARD_FAB2_LIB.BASEBOARD_FAB2(SCH_1):M_BMC_DDR3_MVREF
   J3  M_BMC_DDR3_MRAS_N  RAS_N  @BASEBOARD_FAB2_LIB.BASEBOARD_FAB2(SCH_1):M_BMC_DDR3_MRAS_N
   K1  M_BMC_DDR3_MODT    ODT  @BASEBOARD_FAB2_LIB.BASEBOARD_FAB2(SCH_1):M_BMC_DDR3_MODT
   C7  M_BMC_DDR3_MDQS_1_DP   DQSU  @BASEBOARD_FAB2_LIB.BASEBOARD_FAB2(SCH_1):M_BMC_DDR3_MDQS_1_DP
   B7  M_BMC_DDR3_MDQS_1_DN  DQSU_N  @BASEBOARD_FAB2_LIB.BASEBOARD_FAB2(SCH_1):M_BMC_DDR3_MDQS_1_DN
   F3  M_BMC_DDR3_MDQS_0_DP   DQSL  @BASEBOARD_FAB2_LIB.BASEBOARD_FAB2(SCH_1):M_BMC_DDR3_MDQS_0_DP
   G3  M_BMC_DDR3_MDQS_0_DN  DQSL_N  @BASEBOARD_FAB2_LIB.BASEBOARD_FAB2(SCH_1):M_BMC_DDR3_MDQS_0_DN
   D3  M_BMC_DDR3_MDM_1    DMU  @BASEBOARD_FAB2_LIB.BASEBOARD_FAB2(SCH_1):M_BMC_DDR3_MDM_1
   E7  M_BMC_DDR3_MDM_0    DML  @BASEBOARD_FAB2_LIB.BASEBOARD_FAB2(SCH_1):M_BMC_DDR3_MDM_0
   L2  M_BMC_DDR3_MCS_N   CS_N  @BASEBOARD_FAB2_LIB.BASEBOARD_FAB2(SCH_1):M_BMC_DDR3_MCS_N
   J7  M_BMC_DDR3_MCK_P     CK  @BASEBOARD_FAB2_LIB.BASEBOARD_FAB2(SCH_1):M_BMC_DDR3_MCK_P
   K7  M_BMC_DDR3_MCK_N   CK_N  @BASEBOARD_FAB2_LIB.BASEBOARD_FAB2(SCH_1):M_BMC_DDR3_MCK_N
   K9  M_BMC_DDR3_MCKE    CKE  @BASEBOARD_FAB2_LIB.BASEBOARD_FAB2(SCH_1):M_BMC_DDR3_MCKE
   K3  M_BMC_DDR3_MCAS_N  CAS_N  @BASEBOARD_FAB2_LIB.BASEBOARD_FAB2(SCH_1):M_BMC_DDR3_MCAS_N
   M3  M_BMC_DDR3_MBA_2    BA2  @BASEBOARD_FAB2_LIB.BASEBOARD_FAB2(SCH_1):M_BMC_DDR3_MBA_2
   N8  M_BMC_DDR3_MBA_1    BA1  @BASEBOARD_FAB2_LIB.BASEBOARD_FAB2(SCH_1):M_BMC_DDR3_MBA_1
   M2  M_BMC_DDR3_MBA_0    BA0  @BASEBOARD_FAB2_LIB.BASEBOARD_FAB2(SCH_1):M_BMC_DDR3_MBA_0
   R3  M_BMC_DDR3_MA<9>     A9  @BASEBOARD_FAB2_LIB.BASEBOARD_FAB2(SCH_1):M_BMC_DDR3_MA<9>
   T8  M_BMC_DDR3_MA<8>     A8  @BASEBOARD_FAB2_LIB.BASEBOARD_FAB2(SCH_1):M_BMC_DDR3_MA<8>
   R2  M_BMC_DDR3_MA<7>     A7  @BASEBOARD_FAB2_LIB.BASEBOARD_FAB2(SCH_1):M_BMC_DDR3_MA<7>
   R8  M_BMC_DDR3_MA<6>     A6  @BASEBOARD_FAB2_LIB.BASEBOARD_FAB2(SCH_1):M_BMC_DDR3_MA<6>
   P2  M_BMC_DDR3_MA<5>     A5  @BASEBOARD_FAB2_LIB.BASEBOARD_FAB2(SCH_1):M_BMC_DDR3_MA<5>
   P8  M_BMC_DDR3_MA<4>     A4  @BASEBOARD_FAB2_LIB.BASEBOARD_FAB2(SCH_1):M_BMC_DDR3_MA<4>
   N2  M_BMC_DDR3_MA<3>     A3  @BASEBOARD_FAB2_LIB.BASEBOARD_FAB2(SCH_1):M_BMC_DDR3_MA<3>
   P3  M_BMC_DDR3_MA<2>     A2  @BASEBOARD_FAB2_LIB.BASEBOARD_FAB2(SCH_1):M_BMC_DDR3_MA<2>
   P7  M_BMC_DDR3_MA<1>     A1  @BASEBOARD_FAB2_LIB.BASEBOARD_FAB2(SCH_1):M_BMC_DDR3_MA<1>
   T7  M_BMC_DDR3_MA<14>  NC<6>  @BASEBOARD_FAB2_LIB.BASEBOARD_FAB2(SCH_1):M_BMC_DDR3_MA<14>
   T3  M_BMC_DDR3_MA<13>  NC<5>  @BASEBOARD_FAB2_LIB.BASEBOARD_FAB2(SCH_1):M_BMC_DDR3_MA<13>
   N7  M_BMC_DDR3_MA<12>  A12/BC_N  @BASEBOARD_FAB2_LIB.BASEBOARD_FAB2(SCH_1):M_BMC_DDR3_MA<12>
   R7  M_BMC_DDR3_MA<11>    A11  @BASEBOARD_FAB2_LIB.BASEBOARD_FAB2(SCH_1):M_BMC_DDR3_MA<11>
   L7  M_BMC_DDR3_MA<10>  A10_AP  @BASEBOARD_FAB2_LIB.BASEBOARD_FAB2(SCH_1):M_BMC_DDR3_MA<10>
   N3  M_BMC_DDR3_MA<0>     A0  @BASEBOARD_FAB2_LIB.BASEBOARD_FAB2(SCH_1):M_BMC_DDR3_MA<0>
   B8  M_BMC_DDR3_DQ<9>   DQU6  @BASEBOARD_FAB2_LIB.BASEBOARD_FAB2(SCH_1):M_BMC_DDR3_DQ<9>
   D7  M_BMC_DDR3_DQ<8>   DQU0  @BASEBOARD_FAB2_LIB.BASEBOARD_FAB2(SCH_1):M_BMC_DDR3_DQ<8>
   E3  M_BMC_DDR3_DQ<7>   DQL0  @BASEBOARD_FAB2_LIB.BASEBOARD_FAB2(SCH_1):M_BMC_DDR3_DQ<7>
   H8  M_BMC_DDR3_DQ<6>   DQL5  @BASEBOARD_FAB2_LIB.BASEBOARD_FAB2(SCH_1):M_BMC_DDR3_DQ<6>
   G2  M_BMC_DDR3_DQ<5>   DQL6  @BASEBOARD_FAB2_LIB.BASEBOARD_FAB2(SCH_1):M_BMC_DDR3_DQ<5>
   F2  M_BMC_DDR3_DQ<4>   DQL2  @BASEBOARD_FAB2_LIB.BASEBOARD_FAB2(SCH_1):M_BMC_DDR3_DQ<4>
   F7  M_BMC_DDR3_DQ<3>   DQL1  @BASEBOARD_FAB2_LIB.BASEBOARD_FAB2(SCH_1):M_BMC_DDR3_DQ<3>
   F8  M_BMC_DDR3_DQ<2>   DQL3  @BASEBOARD_FAB2_LIB.BASEBOARD_FAB2(SCH_1):M_BMC_DDR3_DQ<2>
   H3  M_BMC_DDR3_DQ<1>   DQL4  @BASEBOARD_FAB2_LIB.BASEBOARD_FAB2(SCH_1):M_BMC_DDR3_DQ<1>
   A2  M_BMC_DDR3_DQ<15>   DQU5  @BASEBOARD_FAB2_LIB.BASEBOARD_FAB2(SCH_1):M_BMC_DDR3_DQ<15>
   A3  M_BMC_DDR3_DQ<14>   DQU7  @BASEBOARD_FAB2_LIB.BASEBOARD_FAB2(SCH_1):M_BMC_DDR3_DQ<14>
   C8  M_BMC_DDR3_DQ<13>   DQU2  @BASEBOARD_FAB2_LIB.BASEBOARD_FAB2(SCH_1):M_BMC_DDR3_DQ<13>
   C2  M_BMC_DDR3_DQ<12>   DQU3  @BASEBOARD_FAB2_LIB.BASEBOARD_FAB2(SCH_1):M_BMC_DDR3_DQ<12>
   C3  M_BMC_DDR3_DQ<11>   DQU1  @BASEBOARD_FAB2_LIB.BASEBOARD_FAB2(SCH_1):M_BMC_DDR3_DQ<11>
   A7  M_BMC_DDR3_DQ<10>   DQU4  @BASEBOARD_FAB2_LIB.BASEBOARD_FAB2(SCH_1):M_BMC_DDR3_DQ<10>
   H7  M_BMC_DDR3_DQ<0>   DQL7  @BASEBOARD_FAB2_LIB.BASEBOARD_FAB2(SCH_1):M_BMC_DDR3_DQ<0>
   G9  GND            VSSQ<8>  @BASEBOARD_FAB2_LIB.BASEBOARD_FAB2(SCH_1):GND
   G1  GND            VSSQ<7>  @BASEBOARD_FAB2_LIB.BASEBOARD_FAB2(SCH_1):GND
   F9  GND            VSSQ<6>  @BASEBOARD_FAB2_LIB.BASEBOARD_FAB2(SCH_1):GND
   E8  GND            VSSQ<5>  @BASEBOARD_FAB2_LIB.BASEBOARD_FAB2(SCH_1):GND
   E2  GND            VSSQ<4>  @BASEBOARD_FAB2_LIB.BASEBOARD_FAB2(SCH_1):GND
   D8  GND            VSSQ<3>  @BASEBOARD_FAB2_LIB.BASEBOARD_FAB2(SCH_1):GND
   D1  GND            VSSQ<2>  @BASEBOARD_FAB2_LIB.BASEBOARD_FAB2(SCH_1):GND
   B9  GND            VSSQ<1>  @BASEBOARD_FAB2_LIB.BASEBOARD_FAB2(SCH_1):GND
   B1  GND            VSSQ<0>  @BASEBOARD_FAB2_LIB.BASEBOARD_FAB2(SCH_1):GND
   T9  GND            VSS<11>  @BASEBOARD_FAB2_LIB.BASEBOARD_FAB2(SCH_1):GND
   T1  GND            VSS<10>  @BASEBOARD_FAB2_LIB.BASEBOARD_FAB2(SCH_1):GND
   P9  GND            VSS<9>  @BASEBOARD_FAB2_LIB.BASEBOARD_FAB2(SCH_1):GND
   P1  GND            VSS<8>  @BASEBOARD_FAB2_LIB.BASEBOARD_FAB2(SCH_1):GND
   M9  GND            VSS<7>  @BASEBOARD_FAB2_LIB.BASEBOARD_FAB2(SCH_1):GND
   M1  GND            VSS<6>  @BASEBOARD_FAB2_LIB.BASEBOARD_FAB2(SCH_1):GND
   J8  GND            VSS<5>  @BASEBOARD_FAB2_LIB.BASEBOARD_FAB2(SCH_1):GND
   J2  GND            VSS<4>  @BASEBOARD_FAB2_LIB.BASEBOARD_FAB2(SCH_1):GND
   G8  GND            VSS<3>  @BASEBOARD_FAB2_LIB.BASEBOARD_FAB2(SCH_1):GND
   E1  GND            VSS<2>  @BASEBOARD_FAB2_LIB.BASEBOARD_FAB2(SCH_1):GND
   B3  GND            VSS<1>  @BASEBOARD_FAB2_LIB.BASEBOARD_FAB2(SCH_1):GND
   A9  GND            VSS<0>  @BASEBOARD_FAB2_LIB.BASEBOARD_FAB2(SCH_1):GND
   L8  A_M_BMC_ZQ        ZQ  @BASEBOARD_FAB2_LIB.BASEBOARD_FAB2(SCH_1):A_M_BMC_ZQ

GTL2014_SM  I1   U9G1   [GTL2014_SM-IC,D66151-001]
    1  PD_DIR_2         DIR  @BASEBOARD_FAB2_LIB.BASEBOARD_FAB2(SCH_1):PD_DIR_2
   14  P3V3             VCC  @BASEBOARD_FAB2_LIB.BASEBOARD_FAB2(SCH_1):P3V3
    4  P0V7_GTL2014_2   VREF  @BASEBOARD_FAB2_LIB.BASEBOARD_FAB2(SCH_1):P0V7_GTL2014_2
    2  H_CPU1_MEMKLM_MEMHOT_G_R_N     B0  @BASEBOARD_FAB2_LIB.BASEBOARD_FAB2(SCH_1):H_CPU1_MEMKLM_MEMHOT_G_R_N
    3  H_CPU1_MEMGHJ_MEMHOT_G_R_N     B1  @BASEBOARD_FAB2_LIB.BASEBOARD_FAB2(SCH_1):H_CPU1_MEMGHJ_MEMHOT_G_R_N
   13  H_CPU1_KLM_MEMHOT_LVT3_R_N     A0  @BASEBOARD_FAB2_LIB.BASEBOARD_FAB2(SCH_1):H_CPU1_KLM_MEMHOT_LVT3_R_N
   12  H_CPU1_GHJ_MEMHOT_LVT3_R_N     A1  @BASEBOARD_FAB2_LIB.BASEBOARD_FAB2(SCH_1):H_CPU1_GHJ_MEMHOT_LVT3_R_N
    5  H_CPU0_MEMDEF_MEMHOT_G_R_N     B2  @BASEBOARD_FAB2_LIB.BASEBOARD_FAB2(SCH_1):H_CPU0_MEMDEF_MEMHOT_G_R_N
    6  H_CPU0_MEMABC_MEMHOT_G_R_N     B3  @BASEBOARD_FAB2_LIB.BASEBOARD_FAB2(SCH_1):H_CPU0_MEMABC_MEMHOT_G_R_N
   10  H_CPU0_DEF_MEMHOT_LVT3_R_N     A2  @BASEBOARD_FAB2_LIB.BASEBOARD_FAB2(SCH_1):H_CPU0_DEF_MEMHOT_LVT3_R_N
    9  H_CPU0_ABC_MEMHOT_LVT3_R_N     A3  @BASEBOARD_FAB2_LIB.BASEBOARD_FAB2(SCH_1):H_CPU0_ABC_MEMHOT_LVT3_R_N
   11  GND            GND<2>  @BASEBOARD_FAB2_LIB.BASEBOARD_FAB2(SCH_1):GND
    8  GND            GND<1>  @BASEBOARD_FAB2_LIB.BASEBOARD_FAB2(SCH_1):GND
    7  GND            GND<0>  @BASEBOARD_FAB2_LIB.BASEBOARD_FAB2(SCH_1):GND

TPS3700_SM  I163  U9P1   [TPS3700_SM-IC,H69492-001]
    2  P12V_STBY        VDD  @BASEBOARD_FAB2_LIB.BASEBOARD_FAB2(SCH_1):P12V_STBY
    5  GND              GND  @BASEBOARD_FAB2_LIB.BASEBOARD_FAB2(SCH_1):GND
    6  FM_UV_ADR_TRIGGER_N   OUTA  @BASEBOARD_FAB2_LIB.BASEBOARD_FAB2(SCH_1):FM_UV_ADR_TRIGGER_N
    3  A_P12V_STBY_FP_TRIGGER   INBN  @BASEBOARD_FAB2_LIB.BASEBOARD_FAB2(SCH_1):A_P12V_STBY_FP_TRIGGER
    1  A_P12V_STBY_FPH_GATE   OUTB  @BASEBOARD_FAB2_LIB.BASEBOARD_FAB2(SCH_1):A_P12V_STBY_FPH_GATE
    4  A_P12V_STBY_ADR_TRIGGER   INAP  @BASEBOARD_FAB2_LIB.BASEBOARD_FAB2(SCH_1):A_P12V_STBY_ADR_TRIGGER

TPS3700_SM  I200  U9P2   [TPS3700_SM-IC,H69492-001]
    6  PWRGD_DSW_PWROK   OUTA  @BASEBOARD_FAB2_LIB.BASEBOARD_FAB2(SCH_1):PWRGD_DSW_PWROK
    2  P3V3_STBY        VDD  @BASEBOARD_FAB2_LIB.BASEBOARD_FAB2(SCH_1):P3V3_STBY
    5  GND              GND  @BASEBOARD_FAB2_LIB.BASEBOARD_FAB2(SCH_1):GND
    1  FM_HSC_TIMER_EXP_N   OUTB  @BASEBOARD_FAB2_LIB.BASEBOARD_FAB2(SCH_1):FM_HSC_TIMER_EXP_N
    3  A_HSC_TIMER_R   INBN  @BASEBOARD_FAB2_LIB.BASEBOARD_FAB2(SCH_1):A_HSC_TIMER_R
    4  A_HSC_INAP      INAP  @BASEBOARD_FAB2_LIB.BASEBOARD_FAB2(SCH_1):A_HSC_INAP

ZENER_SM  I99  VR1D1  [ZENER_SM-13V,IC,H69095-001]
    1  P12V_PSU           C  @BASEBOARD_FAB2_LIB.BASEBOARD_FAB2(SCH_1):P12V_PSU
    2  GND                A  @BASEBOARD_FAB2_LIB.BASEBOARD_FAB2(SCH_1):GND

VERT_BATT_3PIN_PIP  I51  XBT8G1  [VERT_BATT_3PIN_PIP-3PVERT,C686A]
    2  P3V_BAT_SOURCE     P2  @BASEBOARD_FAB2_LIB.BASEBOARD_FAB2(SCH_1):P3V_BAT_SOURCE
    1  P3V_BAT_SOURCE     P1  @BASEBOARD_FAB2_LIB.BASEBOARD_FAB2(SCH_1):P3V_BAT_SOURCE
    3  GND                N  @BASEBOARD_FAB2_LIB.BASEBOARD_FAB2(SCH_1):GND

SOCKET_P_MECH_A_LEFT  I217  XLU1   [SOCKET_P_MECH_A_LEFT-P0,PLASTIA]

SOCKET_P_MECH_A_LEFT  I153  XLU2   [SOCKET_P_MECH_A_LEFT-P0,PLASTIA]

SOCKET_P_MECH_A_RIGHT  I216  XRU1   [SOCKET_P_MECH_A_RIGHT-P0,PLASTA]

SOCKET_P_MECH_A_RIGHT  I152  XRU2   [SOCKET_P_MECH_A_RIGHT-P0,PLASTA]

OSC_C_6P10  I72  Y3F1   [OSC_C_6P10-156.25MHZ,OSC,G6383A]
    6  P3V3             VCC  @BASEBOARD_FAB2_LIB.BASEBOARD_FAB2(SCH_1):P3V3
    2  NC_CLK_156M_CPU1_OSC  NC_GND  @BASEBOARD_FAB2_LIB.BASEBOARD_FAB2(SCH_1):NC_CLK_156M_CPU1_OSC
    3  GND              GND  @BASEBOARD_FAB2_LIB.BASEBOARD_FAB2(SCH_1):GND
    1  FM_CPU1_STL_BRD_OSC_EN  ENABLE_DISABLE  @BASEBOARD_FAB2_LIB.BASEBOARD_FAB2(SCH_1):FM_CPU1_STL_BRD_OSC_EN
    4  CLK_156M_OSC_BRD_CPU1_DP    OUT  @BASEBOARD_FAB2_LIB.BASEBOARD_FAB2(SCH_1):CLK_156M_OSC_BRD_CPU1_DP
    5  CLK_156M_OSC_BRD_CPU1_DN  OUT_N  @BASEBOARD_FAB2_LIB.BASEBOARD_FAB2(SCH_1):CLK_156M_OSC_BRD_CPU1_DN

OSC_C_6P10  I71  Y6F1   [OSC_C_6P10-156.25MHZ,OSC,G6383A]
    6  P3V3             VCC  @BASEBOARD_FAB2_LIB.BASEBOARD_FAB2(SCH_1):P3V3
    2  NC_CLK_156M_CPU0_OSC  NC_GND  @BASEBOARD_FAB2_LIB.BASEBOARD_FAB2(SCH_1):NC_CLK_156M_CPU0_OSC
    3  GND              GND  @BASEBOARD_FAB2_LIB.BASEBOARD_FAB2(SCH_1):GND
    1  FM_CPU0_STL_BRD_OSC_EN  ENABLE_DISABLE  @BASEBOARD_FAB2_LIB.BASEBOARD_FAB2(SCH_1):FM_CPU0_STL_BRD_OSC_EN
    4  CLK_156M_OSC_BRD_CPU0_DP    OUT  @BASEBOARD_FAB2_LIB.BASEBOARD_FAB2(SCH_1):CLK_156M_OSC_BRD_CPU0_DP
    5  CLK_156M_OSC_BRD_CPU0_DN  OUT_N  @BASEBOARD_FAB2_LIB.BASEBOARD_FAB2(SCH_1):CLK_156M_OSC_BRD_CPU0_DN

CRYSTAL_2013  I49  Y7C1   [CRYSTAL_2013-48.000MHZ,IC,D717A]
    3  XTAL_PCH_48M_OUT      B  @BASEBOARD_FAB2_LIB.BASEBOARD_FAB2(SCH_1):XTAL_PCH_48M_OUT
    1  XTAL_PCH_48M_IN      A  @BASEBOARD_FAB2_LIB.BASEBOARD_FAB2(SCH_1):XTAL_PCH_48M_IN

CRYSTAL_SM  I55  Y7C2   [CRYSTAL_SM-32.768KHZ,IC,C13544A]
    2  XTAL_33K_RTC2      B  @BASEBOARD_FAB2_LIB.BASEBOARD_FAB2(SCH_1):XTAL_33K_RTC2
    1  XTAL_33K_RTC1      A  @BASEBOARD_FAB2_LIB.BASEBOARD_FAB2(SCH_1):XTAL_33K_RTC1

CRYSTAL_2013  I76  Y8C1   [CRYSTAL_2013-25.000MHZ,IC,H196A]
    3  XTAL_KR_25M_OUT      B  @BASEBOARD_FAB2_LIB.BASEBOARD_FAB2(SCH_1):XTAL_KR_25M_OUT
    1  XTAL_KR_25M_IN      A  @BASEBOARD_FAB2_LIB.BASEBOARD_FAB2(SCH_1):XTAL_KR_25M_IN

CRYSTAL_2013LF  I52  Y8F1   [CRYSTAL_2013LF-25.000MHZ,IC,D7B]
    3  XTAL_CK_MNG_OUT      B  @BASEBOARD_FAB2_LIB.BASEBOARD_FAB2(SCH_1):XTAL_CK_MNG_OUT
    1  XTAL_CK_MNG_IN      A  @BASEBOARD_FAB2_LIB.BASEBOARD_FAB2(SCH_1):XTAL_CK_MNG_IN

CRYSTAL_2013  I109  Y9E1   [CRYSTAL_2013-25.000MHZ,IC,D717A]
    3  XTAL_25MHZ_OUT_R      B  @BASEBOARD_FAB2_LIB.BASEBOARD_FAB2(SCH_1):XTAL_25MHZ_OUT_R
    1  XTAL_25MHZ_IN      A  @BASEBOARD_FAB2_LIB.BASEBOARD_FAB2(SCH_1):XTAL_25MHZ_IN

CRYSTAL_SM  I19  Y9F1   [CRYSTAL_SM-24.000MHZ,IC,D95126A]
    2  XTAL_24MHZ_PI7C9X1172_OUT      B  @BASEBOARD_FAB2_LIB.BASEBOARD_FAB2(SCH_1):XTAL_24MHZ_PI7C9X1172_OUT
    1  XTAL_24MHZ_PI7C9X1172_IN      A  @BASEBOARD_FAB2_LIB.BASEBOARD_FAB2(SCH_1):XTAL_24MHZ_PI7C9X1172_IN

OSC_C_SM4  I250  Y9F2   [OSC_C_SM4-24MHZ,OSC,D34520-021]
    1  PU_24M_OSC_OE  ENABLE_CONTROL  @BASEBOARD_FAB2_LIB.BASEBOARD_FAB2(SCH_1):PU_24M_OSC_OE
    4  P3V3_STBY        VDD  @BASEBOARD_FAB2_LIB.BASEBOARD_FAB2(SCH_1):P3V3_STBY
    2  GND              GND  @BASEBOARD_FAB2_LIB.BASEBOARD_FAB2(SCH_1):GND
    3  CLK_24M_BMC_CLKIN_R    OUT  @BASEBOARD_FAB2_LIB.BASEBOARD_FAB2(SCH_1):CLK_24M_BMC_CLKIN_R
END OF PART CROSS REFERENCE

SIGNAL CROSS REFERENCE (forward interface)

AGND_HSC        @BASEBOARD_FAB2_LIB.BASEBOARD_FAB2(SCH_1):AGND_HSC
  C1D9     2      B  CAP_A       I187
  C1D11    2      B  CAP_A       I53
  C1D19    2      B  CAP_0402    I119
  C1D21    2      B  CAP_A       I121
  C1D25    2      B  CAP_0402     I3
  C1D26    2      B  CAP_A       I107
  C1D27    2      B  CAP_A        I7
  C9P6     2      B  CAP_A       I185
  C9P12    2      B  CAP_A       I67
  C9P14    2      B  CAP         I24
  C9P15    2      B  CAP_A       I105
  C9P16    2      B  CAP_A       I40
  C9P17    2      B  CAP_A       I36
  EU1D2   22    GND  ADM1278_SM  I10
  EU1D2   33     EP  ADM1278_SM  I10
  Q1D1     1  SOURCE<0>  FET_N_DUAL_SMLF  I86
  Q1D1     4  SOURCE<0>  FET_N_DUAL_SMLF  I82
  R1D11    2      B  RES         I88
  R1D12    2      B  RES         I174
  R1D18    2      B  RES         I87
  R1D19    2      B  RES         I175
  R1D28    2      B  RES         I26
  R1D34    2      B  RES         I102
  R1D40    2      B  RES         I100
  R1D41    2      B  RES         I19
  R1D42    2      B  RES         I13
  R1D43    2      B  RES          I9
  R9P9     2      B  RES         I146
  R9P11    2      B  RES         I108
  R9P12    2      B  RES         I218
  R9P16    2      B  RES         I36
  R9P17    2      B  RES         I33
  R9P19    2      B  RES         I70
  R9P24    2      B  RES         I55

AGND_P3V3_STBY   @BASEBOARD_FAB2_LIB.BASEBOARD_FAB2(SCH_1):AGND_P3V3_STBY
  C2R11    2      B  CAP         I109
  C8E17    2      B  CAP         I113
  EU8F1   11     G0  RT8240_QFN  I125
  EU8F1   12  GND<0>  RT8240_QFN  I125
  EU8F1   13  GND<1>  RT8240_QFN  I125
  R8E34    2      B  RES         I142
  R8E38    2      B  RES         I140
  R8F9     2      B  RES         I106
  R8F11    2      B  RES         I146

AGND_P5V_STBY   @BASEBOARD_FAB2_LIB.BASEBOARD_FAB2(SCH_1):AGND_P5V_STBY
  C8E13    2      B  CAP         I41
  C8E15    2      B  CAP         I63
  C8E16    2      B  CAP         I53
  C8F1     2      B  CAP         I57
  R7E13    2      B  RES         I58
  R7E14    2      B  RES         I18
  R7E16    2      B  RES         I51

AGND_PVPP_ABC   @BASEBOARD_FAB2_LIB.BASEBOARD_FAB2(SCH_1):AGND_PVPP_ABC
  C3T11    2      B  CAP         I202
  C7F8     2      B  CAP         I140
  C7F10    2      B  CAP_0402    I194
  EU7F1    5   AGND  NCP3232L_SM  I193
  EU7F1    6    OTS  NCP3232L_SM  I193
  R7F11    2      B  RES         I166
  R7F15    2      B  RES         I134
  R7F35    2      B  RES         I170

AGND_PVPP_DEF   @BASEBOARD_FAB2_LIB.BASEBOARD_FAB2(SCH_1):AGND_PVPP_DEF
  C3M10    2      B  CAP         I253
  C7B9     2      B  CAP         I185
  C7B11    2      B  CAP_0402    I197
  EU7B1    5   AGND  NCP3232L_SM  I214
  EU7B1    6    OTS  NCP3232L_SM  I214
  R7B13    2      B  RES         I304
  R7B14    2      B  RES         I193
  R7B20    2      B  RES         I150

AGND_PVPP_GHJ   @BASEBOARD_FAB2_LIB.BASEBOARD_FAB2(SCH_1):AGND_PVPP_GHJ
  C4G7     2      B  CAP         I183
  C4G8     2      B  CAP_0402    I194
  C6U6     2      B  CAP         I187
  EU4G1    5   AGND  NCP3232L_SM  I225
  EU4G1    6    OTS  NCP3232L_SM  I225
  R4G9     2      B  RES         I269
  R4G11    2      B  RES         I184
  R4G25    2      B  RES         I157

AGND_PVPP_KLM   @BASEBOARD_FAB2_LIB.BASEBOARD_FAB2(SCH_1):AGND_PVPP_KLM
  C4B5     2      B  CAP         I129
  C4B6     2      B  CAP_0402    I146
  C6L12    2      B  CAP         I144
  EU4A3    5   AGND  NCP3232L_SM  I184
  EU4A3    6    OTS  NCP3232L_SM  I184
  R4B4     2      B  RES         I216
  R4B6     2      B  RES         I140
  R4B14    2      B  RES         I29

A_1P8_3P3_RCOMP   @BASEBOARD_FAB2_LIB.BASEBOARD_FAB2(SCH_1):A_1P8_3P3_RCOMP
  R8C26    1      A  RES         I35
  U7C1   AM4  GPIO_RCOMP_1P8_3P3  LBG_CORE_QAT_EXT_D  I34

A_ADM1085_CEXT   @BASEBOARD_FAB2_LIB.BASEBOARD_FAB2(SCH_1):A_ADM1085_CEXT
  C3P45    1      A  CAP_0402    I60
  U7D3     5   CEXT  ADM1085_SMT  I70

A_CBOT          @BASEBOARD_FAB2_LIB.BASEBOARD_FAB2(SCH_1):A_CBOT
  C9E7     2      B  CAP         I76
  EU9E1   37   CBOT  SPRINGVILLE_SM1  I72

A_COMP_CKMNG    @BASEBOARD_FAB2_LIB.BASEBOARD_FAB2(SCH_1):A_COMP_CKMNG
  EU8F2   11   IREF  ICS9FGP204_MLFP  I34
  R8F25    1      A  RES         I28

A_CPU0_ABC_RCOMP0   @BASEBOARD_FAB2_LIB.BASEBOARD_FAB2(SCH_1):A_CPU0_ABC_RCOMP0
  R4P8     1      A  RES         I180
  U5D1   Y43  DDR012_RCOMP<0>  SKX_EXT_B_BGA1  I259

A_CPU0_ABC_RCOMP1   @BASEBOARD_FAB2_LIB.BASEBOARD_FAB2(SCH_1):A_CPU0_ABC_RCOMP1
  R4P10    1      A  RES         I181
  U5D1   AB43  DDR012_RCOMP<1>  SKX_EXT_B_BGA1  I259

A_CPU0_ABC_RCOMP2   @BASEBOARD_FAB2_LIB.BASEBOARD_FAB2(SCH_1):A_CPU0_ABC_RCOMP2
  R4P11    1      A  RES         I182
  U5D1   AC42  DDR012_RCOMP<2>  SKX_EXT_B_BGA1  I259

A_CPU0_DEF_RCOMP0   @BASEBOARD_FAB2_LIB.BASEBOARD_FAB2(SCH_1):A_CPU0_DEF_RCOMP0
  R5D1     1      A  RES         I177
  U5D1   DC48  DDR345_RCOMP<0>  SKX_EXT_B_BGA1  I259

A_CPU0_DEF_RCOMP1   @BASEBOARD_FAB2_LIB.BASEBOARD_FAB2(SCH_1):A_CPU0_DEF_RCOMP1
  R5D2     1      A  RES         I178
  U5D1   DD47  DDR345_RCOMP<1>  SKX_EXT_B_BGA1  I259

A_CPU0_DEF_RCOMP2   @BASEBOARD_FAB2_LIB.BASEBOARD_FAB2(SCH_1):A_CPU0_DEF_RCOMP2
  R6D1     1      A  RES         I179
  U5D1   DD49  DDR345_RCOMP<2>  SKX_EXT_B_BGA1  I259

A_CPU0_MCP01_RBIAS   @BASEBOARD_FAB2_LIB.BASEBOARD_FAB2(SCH_1):A_CPU0_MCP01_RBIAS
  R6D2     1      A  RES         I204
  U5D1   CT31  MCP01_RBIAS<1>  SKX_EXT_B_BGA1  I259
  U5D1   CU32  MCP01_RBIAS<0>  SKX_EXT_B_BGA1  I259

A_CPU0_PE012_RBIAS   @BASEBOARD_FAB2_LIB.BASEBOARD_FAB2(SCH_1):A_CPU0_PE012_RBIAS
  R4P3     1      A  RES         I186
  U5D1   CL30  PE012_RBIAS<1>  SKX_EXT_B_BGA1  I259
  U5D1   CN30  PE012_RBIAS<0>  SKX_EXT_B_BGA1  I259

A_CPU0_PE3_RBIAS   @BASEBOARD_FAB2_LIB.BASEBOARD_FAB2(SCH_1):A_CPU0_PE3_RBIAS
  R4P2     1      A  RES         I188
  U5D1   CP29  PE3_RBIAS<0>  SKX_EXT_B_BGA1  I259
  U5D1   CR30  PE3_RBIAS<1>  SKX_EXT_B_BGA1  I259

A_CPU0_UPI01_RBIAS   @BASEBOARD_FAB2_LIB.BASEBOARD_FAB2(SCH_1):A_CPU0_UPI01_RBIAS
  R6D11    1      A  RES         I184
  U5D1   AP29  UPI01_RBIAS<1>  SKX_EXT_B_BGA1  I259
  U5D1   AT29  UPI01_RBIAS<0>  SKX_EXT_B_BGA1  I259

A_CPU0_UPI2_RBIAS   @BASEBOARD_FAB2_LIB.BASEBOARD_FAB2(SCH_1):A_CPU0_UPI2_RBIAS
  R4P4     1      A  RES         I189
  U5D1   CK29  UPI2_RBIAS<1>  SKX_EXT_B_BGA1  I259
  U5D1   CL28  UPI2_RBIAS<0>  SKX_EXT_B_BGA1  I259

A_CPU1_GHJ_RCOMP0   @BASEBOARD_FAB2_LIB.BASEBOARD_FAB2(SCH_1):A_CPU1_GHJ_RCOMP0
  R7P16    1      A  RES         I119
  U2D1   Y43  DDR012_RCOMP<0>  SKX_EXT_B_BGA1  I172

A_CPU1_GHJ_RCOMP1   @BASEBOARD_FAB2_LIB.BASEBOARD_FAB2(SCH_1):A_CPU1_GHJ_RCOMP1
  R7P17    1      A  RES         I140
  U2D1   AB43  DDR012_RCOMP<1>  SKX_EXT_B_BGA1  I172

A_CPU1_GHJ_RCOMP2   @BASEBOARD_FAB2_LIB.BASEBOARD_FAB2(SCH_1):A_CPU1_GHJ_RCOMP2
  R7P19    1      A  RES         I115
  U2D1   AC42  DDR012_RCOMP<2>  SKX_EXT_B_BGA1  I172

A_CPU1_KLM_RCOMP0   @BASEBOARD_FAB2_LIB.BASEBOARD_FAB2(SCH_1):A_CPU1_KLM_RCOMP0
  R3D1     1      A  RES         I116
  U2D1   DC48  DDR345_RCOMP<0>  SKX_EXT_B_BGA1  I172

A_CPU1_KLM_RCOMP1   @BASEBOARD_FAB2_LIB.BASEBOARD_FAB2(SCH_1):A_CPU1_KLM_RCOMP1
  R3D2     1      A  RES         I117
  U2D1   DD47  DDR345_RCOMP<1>  SKX_EXT_B_BGA1  I172

A_CPU1_KLM_RCOMP2   @BASEBOARD_FAB2_LIB.BASEBOARD_FAB2(SCH_1):A_CPU1_KLM_RCOMP2
  R3D3     1      A  RES         I118
  U2D1   DD49  DDR345_RCOMP<2>  SKX_EXT_B_BGA1  I172

A_CPU1_MCP01_RBIAS   @BASEBOARD_FAB2_LIB.BASEBOARD_FAB2(SCH_1):A_CPU1_MCP01_RBIAS
  R3D4     1      A  RES         I155
  U2D1   CT31  MCP01_RBIAS<1>  SKX_EXT_B_BGA1  I172
  U2D1   CU32  MCP01_RBIAS<0>  SKX_EXT_B_BGA1  I172

A_CPU1_PE012_RBIAS   @BASEBOARD_FAB2_LIB.BASEBOARD_FAB2(SCH_1):A_CPU1_PE012_RBIAS
  R7P10    1      A  RES         I124
  U2D1   CL30  PE012_RBIAS<1>  SKX_EXT_B_BGA1  I172
  U2D1   CN30  PE012_RBIAS<0>  SKX_EXT_B_BGA1  I172

A_CPU1_PE3_RBIAS   @BASEBOARD_FAB2_LIB.BASEBOARD_FAB2(SCH_1):A_CPU1_PE3_RBIAS
  R7P8     1      A  RES         I123
  U2D1   CP29  PE3_RBIAS<0>  SKX_EXT_B_BGA1  I172
  U2D1   CR30  PE3_RBIAS<1>  SKX_EXT_B_BGA1  I172

A_CPU1_UPI01_RBIAS   @BASEBOARD_FAB2_LIB.BASEBOARD_FAB2(SCH_1):A_CPU1_UPI01_RBIAS
  R3D19    1      A  RES         I125
  U2D1   AP29  UPI01_RBIAS<1>  SKX_EXT_B_BGA1  I172
  U2D1   AT29  UPI01_RBIAS<0>  SKX_EXT_B_BGA1  I172

A_CPU1_UPI2_RBIAS   @BASEBOARD_FAB2_LIB.BASEBOARD_FAB2(SCH_1):A_CPU1_UPI2_RBIAS
  R7P11    1      A  RES         I126
  U2D1   CK29  UPI2_RBIAS<1>  SKX_EXT_B_BGA1  I172
  U2D1   CL28  UPI2_RBIAS<0>  SKX_EXT_B_BGA1  I172

A_CTOP          @BASEBOARD_FAB2_LIB.BASEBOARD_FAB2(SCH_1):A_CTOP
  C9E7     1      A  CAP         I76
  EU9E1   40   CTOP  SPRINGVILLE_SM1  I72

A_DACRSET       @BASEBOARD_FAB2_LIB.BASEBOARD_FAB2(SCH_1):A_DACRSET
  R9G8     1      A  RES         I457
  U9F4    R1  DACRSET  AST1250_BGA  I347

A_EXTCLKN       @BASEBOARD_FAB2_LIB.BASEBOARD_FAB2(SCH_1):A_EXTCLKN
  R7B8     1      A  RES         I229
  U7C1   D66  EXTCLKN  LBG_CORE_QAT_EXT_D  I220

A_EXTCLKP       @BASEBOARD_FAB2_LIB.BASEBOARD_FAB2(SCH_1):A_EXTCLKP
  R7B7     1      A  RES         I230
  U7C1   E67  EXTCLKP  LBG_CORE_QAT_EXT_D  I220

A_HSC_C         @BASEBOARD_FAB2_LIB.BASEBOARD_FAB2(SCH_1):A_HSC_C
  C1E2     1      A  CAP         I155
  R1D51    1      A  RES         I154

A_HSC_CSOUT     @BASEBOARD_FAB2_LIB.BASEBOARD_FAB2(SCH_1):A_HSC_CSOUT
  EU1D2   19  CSOUT  ADM1278_SM  I10
  R1D14    1      A  RES         I173
  R1D20    1      A  RES         I172

A_HSC_GATE      @BASEBOARD_FAB2_LIB.BASEBOARD_FAB2(SCH_1):A_HSC_GATE
  EU1D2   24   GATE  ADM1278_SM  I10
  R1D48    1      A  RES         I60
  R1D51    2      B  RES         I154
  R1E1     1      A  RES         I56
  R9R4     1      A  RES         I58

A_HSC_GATE1_R   @BASEBOARD_FAB2_LIB.BASEBOARD_FAB2(SCH_1):A_HSC_GATE1_R
  EU1E3    4      G  MOSFETN_1D3S_SOT5  I54
  R1E1     2      B  RES         I56

A_HSC_GATE2_R   @BASEBOARD_FAB2_LIB.BASEBOARD_FAB2(SCH_1):A_HSC_GATE2_R
  EU9R1    4      G  MOSFETN_1D3S_SOT5  I57
  R9R4     2      B  RES         I58

A_HSC_GATE3_R   @BASEBOARD_FAB2_LIB.BASEBOARD_FAB2(SCH_1):A_HSC_GATE3_R
  EU1E1    4      G  MOSFETN_1D3S_SOT5  I59
  R1D48    2      B  RES         I60

A_HSC_HIGH      @BASEBOARD_FAB2_LIB.BASEBOARD_FAB2(SCH_1):A_HSC_HIGH
  R1D19    1      A  RES         I175
  R1D20    2      B  RES         I172
  U1D2     3   INBN  TPS3700_SM  I170

A_HSC_HIGH_EN   @BASEBOARD_FAB2_LIB.BASEBOARD_FAB2(SCH_1):A_HSC_HIGH_EN
  J1B3     1    IO1  CONN3_C95678002_PIP  I123
  J1B4     1    IO1  SCONN3_D53458001_SM  I124
  Q1D1     5  GATE<0>  FET_N_DUAL_SMLF  I82
  R1D18    1      A  RES         I87

A_HSC_HSN       @BASEBOARD_FAB2_LIB.BASEBOARD_FAB2(SCH_1):A_HSC_HSN
  EU1D2   27    HSN  ADM1278_SM  I10
  R1D45    2      B  RES         I43
  R1D47    2      B  RES         I52
  R9P26    2      B  RES         I51

A_HSC_HSP       @BASEBOARD_FAB2_LIB.BASEBOARD_FAB2(SCH_1):A_HSC_HSP
  EU1D2   28    HSP  ADM1278_SM  I10
  R1D44    2      B  RES         I44
  R1D46    2      B  RES         I48
  R9P27    2      B  RES         I47

A_HSC_INAP      @BASEBOARD_FAB2_LIB.BASEBOARD_FAB2(SCH_1):A_HSC_INAP
  R9P12    1      A  RES         I218
  R9P33    2      B  RES         I222
  U9P2     4   INAP  TPS3700_SM  I200

A_HSC_ISET      @BASEBOARD_FAB2_LIB.BASEBOARD_FAB2(SCH_1):A_HSC_ISET
  C9P15    1      A  CAP_A       I105
  EU1D2    3   ISET  ADM1278_SM  I10
  R1D13    2      B  RES         I84
  R1D16    1      A  RES         I85
  R1D37    2      B  RES         I15

A_HSC_ISET_S    @BASEBOARD_FAB2_LIB.BASEBOARD_FAB2(SCH_1):A_HSC_ISET_S
  Q1D1     3  DRAIN<0>  FET_N_DUAL_SMLF  I82
  R1D13    1      A  RES         I84

A_HSC_ISET_S2   @BASEBOARD_FAB2_LIB.BASEBOARD_FAB2(SCH_1):A_HSC_ISET_S2
  Q1D1     6  DRAIN<0>  FET_N_DUAL_SMLF  I86
  R1D16    2      B  RES         I85

A_HSC_ISTART    @BASEBOARD_FAB2_LIB.BASEBOARD_FAB2(SCH_1):A_HSC_ISTART
  EU1D2    4  ISTART  ADM1278_SM  I10
  R1D32    2      B  RES         I17
  R1D34    1      A  RES         I102

A_HSC_LOW       @BASEBOARD_FAB2_LIB.BASEBOARD_FAB2(SCH_1):A_HSC_LOW
  R1D12    1      A  RES         I174
  R1D14    2      B  RES         I173
  U1D2     4   INAP  TPS3700_SM  I170

A_HSC_LOW_DRAIN   @BASEBOARD_FAB2_LIB.BASEBOARD_FAB2(SCH_1):A_HSC_LOW_DRAIN
  Q9P1     6  DRAIN<0>  FET_N_DUAL_SMLF  I196
  R9P15    1      A  RES         I198

A_HSC_LOW_EN    @BASEBOARD_FAB2_LIB.BASEBOARD_FAB2(SCH_1):A_HSC_LOW_EN
  J1B3     3    IO3  CONN3_C95678002_PIP  I123
  J1B4     3    IO3  SCONN3_D53458001_SM  I124
  Q1D1     2  GATE<0>  FET_N_DUAL_SMLF  I86
  R1D11    1      A  RES         I88

A_HSC_LOW_GATE   @BASEBOARD_FAB2_LIB.BASEBOARD_FAB2(SCH_1):A_HSC_LOW_GATE
  Q9P1     2  GATE<0>  FET_N_DUAL_SMLF  I196
  R1D10    2      B  RES         I189
  U1D2     6   OUTA  TPS3700_SM  I170

A_HSC_MON       @BASEBOARD_FAB2_LIB.BASEBOARD_FAB2(SCH_1):A_HSC_MON
  C1D22    1      A  CAP_A       I42
  C9P17    1      A  CAP_A       I36
  EU1D2   26    MON  ADM1278_SM  I10
  R1D45    1      A  RES         I43

A_HSC_MOP       @BASEBOARD_FAB2_LIB.BASEBOARD_FAB2(SCH_1):A_HSC_MOP
  C1D22    2      B  CAP_A       I42
  C9P16    1      A  CAP_A       I40
  EU1D2   29    MOP  ADM1278_SM  I10
  R1D44    1      A  RES         I44

A_HSC_OCP_SEL   @BASEBOARD_FAB2_LIB.BASEBOARD_FAB2(SCH_1):A_HSC_OCP_SEL
  J1B3     2    IO2  CONN3_C95678002_PIP  I123
  J1B4     2    IO2  SCONN3_D53458001_SM  I124
  R1D15    2      B  RES         I92

A_HSC_OV        @BASEBOARD_FAB2_LIB.BASEBOARD_FAB2(SCH_1):A_HSC_OV
  C1D27    1      A  CAP_A        I7
  EU1D2   32     OV  ADM1278_SM  I10
  R1D43    1      A  RES          I9
  R9P28    2      B  RES          I6

A_HSC_PSET      @BASEBOARD_FAB2_LIB.BASEBOARD_FAB2(SCH_1):A_HSC_PSET
  C1D21    1      A  CAP_A       I121
  EU1D2    1   PSET  ADM1278_SM  I10
  R1D39    2      B  RES         I16
  R1D40    1      A  RES         I100

A_HSC_PWGIN     @BASEBOARD_FAB2_LIB.BASEBOARD_FAB2(SCH_1):A_HSC_PWGIN
  EU1D2   21  PWGIN  ADM1278_SM  I10
  R9P23    2      B  RES         I54
  R9P24    1      A  RES         I55

A_HSC_TEMP      @BASEBOARD_FAB2_LIB.BASEBOARD_FAB2(SCH_1):A_HSC_TEMP
  EU1D2   25   TEMP  ADM1278_SM  I10
  Q1D3     1      B  NPN_SM      I58
  Q1D3     3      C  NPN_SM      I58

A_HSC_TIMER     @BASEBOARD_FAB2_LIB.BASEBOARD_FAB2(SCH_1):A_HSC_TIMER
  C9P14    1      A  CAP         I24
  EU1D2    5  TIMER  ADM1278_SM  I10
  R9P21    1      A  RES         I71

A_HSC_TIMER_R   @BASEBOARD_FAB2_LIB.BASEBOARD_FAB2(SCH_1):A_HSC_TIMER_R
  R9P19    1      A  RES         I70
  R9P21    2      B  RES         I71
  U9P2     3   INBN  TPS3700_SM  I200

A_HSC_UV        @BASEBOARD_FAB2_LIB.BASEBOARD_FAB2(SCH_1):A_HSC_UV
  C1D26    1      A  CAP_A       I107
  EU1D2   31     UV  ADM1278_SM  I10
  R1D42    1      A  RES         I13
  R9P29    2      B  RES         I12

A_HSC_VCAP      @BASEBOARD_FAB2_LIB.BASEBOARD_FAB2(SCH_1):A_HSC_VCAP
  C1D19    1      A  CAP_0402    I119
  EU1D2    2   VCAP  ADM1278_SM  I10
  R1D27    1      A  RES         I38
  R1D29    1      A  RES         I37
  R1D32    1      A  RES         I17
  R1D37    1      A  RES         I15
  R1D39    1      A  RES         I16

A_HSC_VOUT      @BASEBOARD_FAB2_LIB.BASEBOARD_FAB2(SCH_1):A_HSC_VOUT
  C9P12    1      A  CAP_A       I67
  EU1D2   20   VOUT  ADM1278_SM  I10
  R1D36    2      B  RES         I65

A_KR0_RBIAS     @BASEBOARD_FAB2_LIB.BASEBOARD_FAB2(SCH_1):A_KR0_RBIAS
  R2N4     2      B  RES         I96
  U7C1   BB29  LAN_RBIAS_0  LBG_CORE_QAT_EXT_D  I73

A_KR1_RBIAS     @BASEBOARD_FAB2_LIB.BASEBOARD_FAB2(SCH_1):A_KR1_RBIAS
  R2M6     1      A  RES         I99
  U7C1   BD42  LAN_RBIAS_1  LBG_CORE_QAT_EXT_D  I73

A_M_BMC_ZQ      @BASEBOARD_FAB2_LIB.BASEBOARD_FAB2(SCH_1):A_M_BMC_ZQ
  R1T27    1      A  RES         I32
  U9F5    L8     ZQ  K4B1G16_BGA1   I1

A_P12V_STBY_ADR_TRIGGER   @BASEBOARD_FAB2_LIB.BASEBOARD_FAB2(SCH_1):A_P12V_STBY_ADR_TRIGGER
  R9P7     2      B  RES         I145
  R9P9     1      A  RES         I146
  U9P1     4   INAP  TPS3700_SM  I163

A_P12V_STBY_FPH_GATE   @BASEBOARD_FAB2_LIB.BASEBOARD_FAB2(SCH_1):A_P12V_STBY_FPH_GATE
  Q9P1     5  GATE<0>  FET_N_DUAL_SMLF  I199
  R9P10    2      B  RES         I192
  U9P1     1   OUTB  TPS3700_SM  I163

A_P12V_STBY_FP_TRIGGER   @BASEBOARD_FAB2_LIB.BASEBOARD_FAB2(SCH_1):A_P12V_STBY_FP_TRIGGER
  R9P11    1      A  RES         I108
  R9P13    2      B  RES         I107
  U9P1     3   INBN  TPS3700_SM  I163

A_P12V_STBY_SCALED   @BASEBOARD_FAB2_LIB.BASEBOARD_FAB2(SCH_1):A_P12V_STBY_SCALED
  C9G17    1      A  CAP         I80
  EU9G1   14    IN2  ADC128D818_SM  I52
  R1U32    2      B  RES         I82
  R1U33    1      A  RES         I83
  U9F4    L3  ADC2_GPIW2  AST1250_BGA   I1

A_P1V05_STBY_PCH_SENSOR   @BASEBOARD_FAB2_LIB.BASEBOARD_FAB2(SCH_1):A_P1V05_STBY_PCH_SENSOR
  C1U21    1      A  CAP         I56
  EU9G1   13    IN3  ADC128D818_SM  I52
  FB1U3    1      A  FERRITE     I57
  U9F4    L2  ADC3_GPIW3  AST1250_BGA   I1

A_P3V3_SCALED   @BASEBOARD_FAB2_LIB.BASEBOARD_FAB2(SCH_1):A_P3V3_SCALED
  C9G14    1      A  CAP         I146
  EU9G1   16    IN0  ADC128D818_SM  I52
  R1U26    2      B  RES         I148
  R1U27    1      A  RES         I149
  U9F4    L5  ADC0_GPIW0  AST1250_BGA   I1

A_P3V3_STBY_SCALED   @BASEBOARD_FAB2_LIB.BASEBOARD_FAB2(SCH_1):A_P3V3_STBY_SCALED
  C9G20    1      A  CAP         I86
  EU9G1   11    IN5  ADC128D818_SM  I52
  R1U38    1      A  RES         I114
  R1U39    2      B  RES         I88
  U9F4    M5  ADC5_GPIW5  AST1250_BGA   I1

A_P3V_BAT_R     @BASEBOARD_FAB2_LIB.BASEBOARD_FAB2(SCH_1):A_P3V_BAT_R
  CR2U1    2     A2  DIODE2A_DUAL  I53
  R1U50    1      A  RES         I126
  R2U43    2      B  RES         I46

A_P3V_BAT_SCALED   @BASEBOARD_FAB2_LIB.BASEBOARD_FAB2(SCH_1):A_P3V_BAT_SCALED
  C9G22    1      A  CAP         I108
  EU9G1    9    IN7  ADC128D818_SM  I52
  Q9G1     4  SOURCE<0>  FET_N_DUAL_SMLF  I157
  R9G26    1      A  RES         I106
  U9F4    M3  ADC7_GPIW7  AST1250_BGA   I1

A_P5V_SCALED    @BASEBOARD_FAB2_LIB.BASEBOARD_FAB2(SCH_1):A_P5V_SCALED
  C9G15    1      A  CAP         I139
  EU9G1   15    IN1  ADC128D818_SM  I52
  R1U28    1      A  RES         I142
  R1U29    2      B  RES         I141
  U9F4    L4  ADC1_GPIW1  AST1250_BGA   I1

A_P5V_STBY_SCALED   @BASEBOARD_FAB2_LIB.BASEBOARD_FAB2(SCH_1):A_P5V_STBY_SCALED
  C9G21    1      A  CAP         I68
  EU9G1   10    IN6  ADC128D818_SM  I52
  R1U44    1      A  RES         I116
  R1U47    2      B  RES         I115
  U9F4    M4  ADC6_GPIW6  AST1250_BGA   I1

A_PCH_XCLK_BIASREF   @BASEBOARD_FAB2_LIB.BASEBOARD_FAB2(SCH_1):A_PCH_XCLK_BIASREF
  R3N1     1      A  RES         I149
  U7C1   G44  XCLK_BIASREF  LBG_CORE_QAT_EXT_D  I40

A_PCIEUP_RCOMP_N   @BASEBOARD_FAB2_LIB.BASEBOARD_FAB2(SCH_1):A_PCIEUP_RCOMP_N
  R3M12    2      B  RES         I181
  U7C1   AF58  PCIEUP_RCOMPN  LBG_CORE_QAT_EXT_D  I220

A_PCIEUP_RCOMP_P   @BASEBOARD_FAB2_LIB.BASEBOARD_FAB2(SCH_1):A_PCIEUP_RCOMP_P
  R3M12    1      A  RES         I181
  U7C1   AH58  PCIEUP_RCOMPP  LBG_CORE_QAT_EXT_D  I220

A_PCIE_RCOMP_N   @BASEBOARD_FAB2_LIB.BASEBOARD_FAB2(SCH_1):A_PCIE_RCOMP_N
  R3M11    2      B  RES         I108
  U7C1   BD58  PCIE_RCOMPN  LBG_CORE_QAT_EXT_D  I220

A_PCIE_RCOMP_P   @BASEBOARD_FAB2_LIB.BASEBOARD_FAB2(SCH_1):A_PCIE_RCOMP_P
  R3M11    1      A  RES         I108
  U7C1   BB56  PCIE_RCOMPP  LBG_CORE_QAT_EXT_D  I220

A_PG_P12V_MAIN   @BASEBOARD_FAB2_LIB.BASEBOARD_FAB2(SCH_1):A_PG_P12V_MAIN
  R8D38    2      B  RES         I112
  R8D40    1      A  RES         I113
  U8D8     4   INAP  TPS3700_SM  I104

A_PG_P5V        @BASEBOARD_FAB2_LIB.BASEBOARD_FAB2(SCH_1):A_PG_P5V
  R8D37    1      A  RES         I115
  R8D39    2      B  RES         I114
  U8D8     3   INBN  TPS3700_SM  I104

A_PVCCRTC_EXT_CAP   @BASEBOARD_FAB2_LIB.BASEBOARD_FAB2(SCH_1):A_PVCCRTC_EXT_CAP
  C3N29    1      A  CAP_A       I16
  U7C1   AG22  VCCRTCEXT  LBG_CORE_QAT_EXT_D  I63

A_PVNN_STBY_PCH_SENSOR   @BASEBOARD_FAB2_LIB.BASEBOARD_FAB2(SCH_1):A_PVNN_STBY_PCH_SENSOR
  C9G18    1      A  CAP         I153
  EU9G1   12    IN4  ADC128D818_SM  I52
  FB1U4    1      A  FERRITE     I155
  U9F4    L1  ADC4_GPIW4  AST1250_BGA   I1

A_RCOMP_3P3     @BASEBOARD_FAB2_LIB.BASEBOARD_FAB2(SCH_1):A_RCOMP_3P3
  R8C21    1      A  RES         I148
  U7C1   BY25  GPIO_RCOMP_3P3  LBG_CORE_QAT_EXT_D  I147

A_TSENSE_P1V05_PCH_STBY_TMON   @BASEBOARD_FAB2_LIB.BASEBOARD_FAB2(SCH_1):A_TSENSE_P1V05_PCH_STBY_TMON
  CTI69    1      A  CAP         I134
  EU7A2   36  TOUT_FLT  IR354XX_SM  I117
  EU8A1   34  BTSEN  PXE1110B_QFN  I229

A_TSENSE_PVCCIN_CPU0   @BASEBOARD_FAB2_LIB.BASEBOARD_FAB2(SCH_1):A_TSENSE_PVCCIN_CPU0
  C4D17    1      A  CAP         I66
  CTI2     1      A  CAP         I78
  CTI4     1      A  CAP         I85
  CTI34    1      A  CAP         I88
  CTI37    1      A  CAP         I99
  CTI42    1      A  CAP         I108
  EU4C2   36  TOUT_FLT  IR354XX_SM  I71
  EU4D1   36  TOUT_FLT  IR354XX_SM  I71
  EU4D3   36  TOUT_FLT  IR354XX_SM  I70
  EU4D4   43  ATSEN  PXE1610B_QFN  I155
  EU4D6   36  TOUT_FLT  IR354XX_SM  I64
  EU4E1   36  TOUT_FLT  IR354XX_SM  I63

A_TSENSE_PVCCIN_CPU1   @BASEBOARD_FAB2_LIB.BASEBOARD_FAB2(SCH_1):A_TSENSE_PVCCIN_CPU1
  C1C10    1      A  CAP         I69
  CTI15    1      A  CAP         I67
  CTI17    1      A  CAP         I82
  CTI19    1      A  CAP         I90
  CTI22    1      A  CAP         I74
  CTI26    1      A  CAP         I82
  EU1C2   43  ATSEN  PXE1610B_QFN  I130
  EU1C3   36  TOUT_FLT  IR354XX_SM  I56
  EU1D1   36  TOUT_FLT  IR354XX_SM  I71
  EU1D3   36  TOUT_FLT  IR354XX_SM  I27
  EU1D4   36  TOUT_FLT  IR354XX_SM  I24
  EU1E2   36  TOUT_FLT  IR354XX_SM  I20

A_TSENSE_PVCCIO_CPU0   @BASEBOARD_FAB2_LIB.BASEBOARD_FAB2(SCH_1):A_TSENSE_PVCCIO_CPU0
  CTI71    1      A  CAP         I109
  EU3P1   35  ATSEN  PXE1110B_QFN  I93
  EU7C1   36  TOUT_FLT  IR354XX_SM  I101

A_TSENSE_PVCCIO_CPU1   @BASEBOARD_FAB2_LIB.BASEBOARD_FAB2(SCH_1):A_TSENSE_PVCCIO_CPU1
  CTI61    1      A  CAP         I134
  EU4D5   35  ATSEN  PXE1110B_QFN  I96
  EU4E2   36  TOUT_FLT  IR354XX_SM  I126

A_TSENSE_PVDDQ_ABC   @BASEBOARD_FAB2_LIB.BASEBOARD_FAB2(SCH_1):A_TSENSE_PVDDQ_ABC
  C7G3     1      A  CAP         I320
  CTI49    1      A  CAP         I118
  CTI54    1      A  CAP         I121
  EU7G1   35  ATSEN  PXM1310B_QFN  I358
  EU7G2   36  TOUT_FLT  IR354XX_SM  I102
  EU7G3   36  TOUT_FLT  IR354XX_SM  I103

A_TSENSE_PVDDQ_DEF   @BASEBOARD_FAB2_LIB.BASEBOARD_FAB2(SCH_1):A_TSENSE_PVDDQ_DEF
  C7A29    1      A  CAP         I39
  CTI43    1      A  CAP         I124
  CTI48    1      A  CAP         I119
  EU7A1   36  TOUT_FLT  IR354XX_SM  I106
  EU7A4   36  TOUT_FLT  IR354XX_SM  I107
  EU7A5   35  ATSEN  PXM1310B_QFN  I75

A_TSENSE_PVDDQ_GHJ   @BASEBOARD_FAB2_LIB.BASEBOARD_FAB2(SCH_1):A_TSENSE_PVDDQ_GHJ
  C1G24    1      A  CAP         I36
  CTI28    1      A  CAP         I122
  CTI32    1      A  CAP         I130
  EU1F1   36  TOUT_FLT  IR354XX_SM  I111
  EU1G1   36  TOUT_FLT  IR354XX_SM  I110
  EU1G2   35  ATSEN  PXM1310B_QFN  I90

A_TSENSE_PVDDQ_KLM   @BASEBOARD_FAB2_LIB.BASEBOARD_FAB2(SCH_1):A_TSENSE_PVDDQ_KLM
  C1B11    1      A  CAP         I36
  CTI8     1      A  CAP         I114
  CTI10    1      A  CAP         I119
  EU1A1   36  TOUT_FLT  IR354XX_SM  I102
  EU1A2   36  TOUT_FLT  IR354XX_SM  I101
  EU1B1   35  ATSEN  PXM1310B_QFN  I90

A_TSENSE_PVNN_PCH_TMON   @BASEBOARD_FAB2_LIB.BASEBOARD_FAB2(SCH_1):A_TSENSE_PVNN_PCH_TMON
  CTI64    1      A  CAP         I136
  EU7A3   36  TOUT_FLT  IR354XX_SM  I116
  EU8A1   35  ATSEN  PXE1110B_QFN  I229

A_TSENSE_PVSA_CPU0   @BASEBOARD_FAB2_LIB.BASEBOARD_FAB2(SCH_1):A_TSENSE_PVSA_CPU0
  C4D18    1      A  CAP         I68
  CTI58    1      A  CAP         I65
  EU4C1   36  TOUT_FLT  IR354XX_SM  I46
  EU4D4   42  BTSEN  PXE1610B_QFN  I155

A_TSENSE_PVSA_CPU1   @BASEBOARD_FAB2_LIB.BASEBOARD_FAB2(SCH_1):A_TSENSE_PVSA_CPU1
  C1C11    1      A  CAP         I71
  CTI55    1      A  CAP         I60
  EU1C1   36  TOUT_FLT  IR354XX_SM  I51
  EU1C2   42  BTSEN  PXE1610B_QFN  I130

A_USB2VRES      @BASEBOARD_FAB2_LIB.BASEBOARD_FAB2(SCH_1):A_USB2VRES
  R1T25    1      A  RES         I461
  U9F4   AA20  USB2VRES  AST1250_BGA  I347

A_USB2_COMP     @BASEBOARD_FAB2_LIB.BASEBOARD_FAB2(SCH_1):A_USB2_COMP
  R8B9     1      A  RES         I90
  U7C1   BN70  USB2_COMP  LBG_CORE_QAT_EXT_D  I74

A_USB2_VBUS     @BASEBOARD_FAB2_LIB.BASEBOARD_FAB2(SCH_1):A_USB2_VBUS
  R8B32    1      A  RES         I114
  U7C1   BR67  USB2_VBUS  LBG_CORE_QAT_EXT_D  I74

CLK_100M_AIRMAX8_PE1_DN   @BASEBOARD_FAB2_LIB.BASEBOARD_FAB2(SCH_1):CLK_100M_AIRMAX8_PE1_DN
  J1F1    I4   IOI4  CONN76_H22707001_THMT1  I111
  U7C1   K38  CLKOUT_SRCN<0>  LBG_CORE_QAT_EXT_D  I40

CLK_100M_AIRMAX8_PE1_DP   @BASEBOARD_FAB2_LIB.BASEBOARD_FAB2(SCH_1):CLK_100M_AIRMAX8_PE1_DP
  J1F1    H4   IOH4  CONN76_H22707001_THMT1  I111
  U7C1   H38  CLKOUT_SRCP<0>  LBG_CORE_QAT_EXT_D  I40

CLK_100M_BMC_PE_DN   @BASEBOARD_FAB2_LIB.BASEBOARD_FAB2(SCH_1):CLK_100M_BMC_PE_DN
  R7C2     2      B  RES         I141
  U7C1   B29  CLKOUT_PLAT0N  LBG_CORE_QAT_EXT_D  I40

CLK_100M_BMC_PE_DP   @BASEBOARD_FAB2_LIB.BASEBOARD_FAB2(SCH_1):CLK_100M_BMC_PE_DP
  R7C4     2      B  RES         I142
  U7C1   D29  CLKOUT_PLAT0P  LBG_CORE_QAT_EXT_D  I40

CLK_100M_BMC_PE_R_DN   @BASEBOARD_FAB2_LIB.BASEBOARD_FAB2(SCH_1):CLK_100M_BMC_PE_R_DN
  R7C2     1      A  RES         I141
  R9F44    1      A  RES         I211
  U9F4   G21  NC_PEREFCLKN  AST1250_BGA  I100

CLK_100M_BMC_PE_R_DP   @BASEBOARD_FAB2_LIB.BASEBOARD_FAB2(SCH_1):CLK_100M_BMC_PE_R_DP
  R7C4     1      A  RES         I142
  R9F45    1      A  RES         I210
  U9F4   G22  NC_PEREFCLKP  AST1250_BGA  I100

CLK_100M_CPU0_BCLK0_DN   @BASEBOARD_FAB2_LIB.BASEBOARD_FAB2(SCH_1):CLK_100M_CPU0_BCLK0_DN
  R4D25    2      B  RES          I1
  R6P15    1      A  RES         I167
  U5D1   AU24  BCLK0_DN  SKX_EXT_B_BGA1  I259

CLK_100M_CPU0_BCLK0_DP   @BASEBOARD_FAB2_LIB.BASEBOARD_FAB2(SCH_1):CLK_100M_CPU0_BCLK0_DP
  R4D29    2      B  RES         I69
  R6P17    1      A  RES         I165
  U5D1   AW24  BCLK0_DP  SKX_EXT_B_BGA1  I259

CLK_100M_CPU0_BCLK0_R_DN   @BASEBOARD_FAB2_LIB.BASEBOARD_FAB2(SCH_1):CLK_100M_CPU0_BCLK0_R_DN
  EU4D2   18  DIF_0N  NB3W1200L_LCC   I1
  R4D25    1      A  RES          I1

CLK_100M_CPU0_BCLK0_R_DP   @BASEBOARD_FAB2_LIB.BASEBOARD_FAB2(SCH_1):CLK_100M_CPU0_BCLK0_R_DP
  EU4D2   17  DIF_0P  NB3W1200L_LCC   I1
  R4D29    1      A  RES         I69

CLK_100M_CPU0_BCLK1_DN   @BASEBOARD_FAB2_LIB.BASEBOARD_FAB2(SCH_1):CLK_100M_CPU0_BCLK1_DN
  R4D18    1      A  RES         I163
  R4D20    2      B  RES         I119
  U5D1   CR26  BCLK1_DN  SKX_EXT_B_BGA1  I259

CLK_100M_CPU0_BCLK1_DP   @BASEBOARD_FAB2_LIB.BASEBOARD_FAB2(SCH_1):CLK_100M_CPU0_BCLK1_DP
  R4D22    2      B  RES         I114
  R4D24    1      A  RES         I161
  U5D1   CP27  BCLK1_DP  SKX_EXT_B_BGA1  I259

CLK_100M_CPU0_BCLK1_R_DN   @BASEBOARD_FAB2_LIB.BASEBOARD_FAB2(SCH_1):CLK_100M_CPU0_BCLK1_R_DN
  EU4D2   22  DIF_1N  NB3W1200L_LCC   I1
  R4D20    1      A  RES         I119

CLK_100M_CPU0_BCLK1_R_DP   @BASEBOARD_FAB2_LIB.BASEBOARD_FAB2(SCH_1):CLK_100M_CPU0_BCLK1_R_DP
  EU4D2   21  DIF_1P  NB3W1200L_LCC   I1
  R4D22    1      A  RES         I114

CLK_100M_CPU0_BCLK2_DN   @BASEBOARD_FAB2_LIB.BASEBOARD_FAB2(SCH_1):CLK_100M_CPU0_BCLK2_DN
  R4D14    2      B  RES         I109
  R6P12    1      A  RES         I159
  U5D1   CT25  BCLK2_DN  SKX_EXT_B_BGA1  I259

CLK_100M_CPU0_BCLK2_DP   @BASEBOARD_FAB2_LIB.BASEBOARD_FAB2(SCH_1):CLK_100M_CPU0_BCLK2_DP
  R4D17    2      B  RES         I104
  R6P13    1      A  RES         I157
  U5D1   CU26  BCLK2_DP  SKX_EXT_B_BGA1  I259

CLK_100M_CPU0_BCLK2_R_DN   @BASEBOARD_FAB2_LIB.BASEBOARD_FAB2(SCH_1):CLK_100M_CPU0_BCLK2_R_DN
  EU4D2   27  DIF_2N  NB3W1200L_LCC   I1
  R4D14    1      A  RES         I109

CLK_100M_CPU0_BCLK2_R_DP   @BASEBOARD_FAB2_LIB.BASEBOARD_FAB2(SCH_1):CLK_100M_CPU0_BCLK2_R_DP
  EU4D2   26  DIF_2P  NB3W1200L_LCC   I1
  R4D17    1      A  RES         I104

CLK_100M_CPU0_PE_REFCLK_DN   @BASEBOARD_FAB2_LIB.BASEBOARD_FAB2(SCH_1):CLK_100M_CPU0_PE_REFCLK_DN
  R4D10    2      B  RES         I99
  R6P9     1      A  RES         I155
  U5D1   BU24  CD_PE_REFCLK_DN  SKX_EXT_B_BGA1  I61

CLK_100M_CPU0_PE_REFCLK_DP   @BASEBOARD_FAB2_LIB.BASEBOARD_FAB2(SCH_1):CLK_100M_CPU0_PE_REFCLK_DP
  R4D12    2      B  RES         I94
  R6P11    1      A  RES         I153
  U5D1   BW24  CD_PE_REFCLK_DP  SKX_EXT_B_BGA1  I61

CLK_100M_CPU0_PE_REFCLK_R_DN   @BASEBOARD_FAB2_LIB.BASEBOARD_FAB2(SCH_1):CLK_100M_CPU0_PE_REFCLK_R_DN
  EU4D2   31  DIF_3N  NB3W1200L_LCC   I1
  R4D10    1      A  RES         I99

CLK_100M_CPU0_PE_REFCLK_R_DP   @BASEBOARD_FAB2_LIB.BASEBOARD_FAB2(SCH_1):CLK_100M_CPU0_PE_REFCLK_R_DP
  EU4D2   30  DIF_3P  NB3W1200L_LCC   I1
  R4D12    1      A  RES         I94

CLK_100M_CPU0_RC_REFCLK0_DN   @BASEBOARD_FAB2_LIB.BASEBOARD_FAB2(SCH_1):CLK_100M_CPU0_RC_REFCLK0_DN
  R4D7     2      B  RES         I89
  R6P2     1      A  RES         I151
  U5D1   AP27  RSVD<195>  SKX_EXT_B_BGA1  I204

CLK_100M_CPU0_RC_REFCLK0_DP   @BASEBOARD_FAB2_LIB.BASEBOARD_FAB2(SCH_1):CLK_100M_CPU0_RC_REFCLK0_DP
  R4D8     2      B  RES         I84
  R6P1     1      A  RES         I149
  U5D1   AM27  RSVD<206>  SKX_EXT_B_BGA1  I204

CLK_100M_CPU0_RC_REFCLK0_R_DN   @BASEBOARD_FAB2_LIB.BASEBOARD_FAB2(SCH_1):CLK_100M_CPU0_RC_REFCLK0_R_DN
  EU4D2   35  DIF_4N  NB3W1200L_LCC   I1
  R4D7     1      A  RES         I89

CLK_100M_CPU0_RC_REFCLK0_R_DP   @BASEBOARD_FAB2_LIB.BASEBOARD_FAB2(SCH_1):CLK_100M_CPU0_RC_REFCLK0_R_DP
  EU4D2   34  DIF_4P  NB3W1200L_LCC   I1
  R4D8     1      A  RES         I84

CLK_100M_CPU0_RC_REFCLK1_DN   @BASEBOARD_FAB2_LIB.BASEBOARD_FAB2(SCH_1):CLK_100M_CPU0_RC_REFCLK1_DN
  R4D5     2      B  RES         I79
  R6P4     1      A  RES         I147
  U5D1   BB25  RSVD<165>  SKX_EXT_B_BGA1  I15

CLK_100M_CPU0_RC_REFCLK1_DP   @BASEBOARD_FAB2_LIB.BASEBOARD_FAB2(SCH_1):CLK_100M_CPU0_RC_REFCLK1_DP
  R4D6     2      B  RES         I74
  R6P3     1      A  RES         I145
  U5D1   BD25  RSVD<153>  SKX_EXT_B_BGA1  I15

CLK_100M_CPU0_RC_REFCLK1_R_DN   @BASEBOARD_FAB2_LIB.BASEBOARD_FAB2(SCH_1):CLK_100M_CPU0_RC_REFCLK1_R_DN
  EU4D2   39  DIF_5N  NB3W1200L_LCC   I1
  R4D5     1      A  RES         I79

CLK_100M_CPU0_RC_REFCLK1_R_DP   @BASEBOARD_FAB2_LIB.BASEBOARD_FAB2(SCH_1):CLK_100M_CPU0_RC_REFCLK1_R_DP
  EU4D2   38  DIF_5P  NB3W1200L_LCC   I1
  R4D6     1      A  RES         I74

CLK_100M_CPU1_BCLK0_DN   @BASEBOARD_FAB2_LIB.BASEBOARD_FAB2(SCH_1):CLK_100M_CPU1_BCLK0_DN
  R4D3     2      B  RES         I64
  R6P6     1      A  RES         I143
  U2D1   AU24  BCLK0_DN  SKX_EXT_B_BGA1  I172

CLK_100M_CPU1_BCLK0_DP   @BASEBOARD_FAB2_LIB.BASEBOARD_FAB2(SCH_1):CLK_100M_CPU1_BCLK0_DP
  R4D4     2      B  RES         I59
  R6P5     1      A  RES         I141
  U2D1   AW24  BCLK0_DP  SKX_EXT_B_BGA1  I172

CLK_100M_CPU1_BCLK0_R_DN   @BASEBOARD_FAB2_LIB.BASEBOARD_FAB2(SCH_1):CLK_100M_CPU1_BCLK0_R_DN
  EU4D2   43  DIF_6N  NB3W1200L_LCC   I1
  R4D3     1      A  RES         I64

CLK_100M_CPU1_BCLK0_R_DP   @BASEBOARD_FAB2_LIB.BASEBOARD_FAB2(SCH_1):CLK_100M_CPU1_BCLK0_R_DP
  EU4D2   42  DIF_6P  NB3W1200L_LCC   I1
  R4D4     1      A  RES         I59

CLK_100M_CPU1_BCLK1_DN   @BASEBOARD_FAB2_LIB.BASEBOARD_FAB2(SCH_1):CLK_100M_CPU1_BCLK1_DN
  R4D1     2      B  RES         I54
  R6P8     1      A  RES         I139
  U2D1   CR26  BCLK1_DN  SKX_EXT_B_BGA1  I172

CLK_100M_CPU1_BCLK1_DP   @BASEBOARD_FAB2_LIB.BASEBOARD_FAB2(SCH_1):CLK_100M_CPU1_BCLK1_DP
  R4D2     2      B  RES         I49
  R6P7     1      A  RES         I137
  U2D1   CP27  BCLK1_DP  SKX_EXT_B_BGA1  I172

CLK_100M_CPU1_BCLK1_R_DN   @BASEBOARD_FAB2_LIB.BASEBOARD_FAB2(SCH_1):CLK_100M_CPU1_BCLK1_R_DN
  EU4D2   47  DIF_7N  NB3W1200L_LCC   I1
  R4D1     1      A  RES         I54

CLK_100M_CPU1_BCLK1_R_DP   @BASEBOARD_FAB2_LIB.BASEBOARD_FAB2(SCH_1):CLK_100M_CPU1_BCLK1_R_DP
  EU4D2   46  DIF_7P  NB3W1200L_LCC   I1
  R4D2     1      A  RES         I49

CLK_100M_CPU1_BCLK2_DN   @BASEBOARD_FAB2_LIB.BASEBOARD_FAB2(SCH_1):CLK_100M_CPU1_BCLK2_DN
  R4D11    2      B  RES         I44
  R7P2     1      A  RES         I135
  U2D1   CT25  BCLK2_DN  SKX_EXT_B_BGA1  I172

CLK_100M_CPU1_BCLK2_DP   @BASEBOARD_FAB2_LIB.BASEBOARD_FAB2(SCH_1):CLK_100M_CPU1_BCLK2_DP
  R4D9     2      B  RES         I39
  R7P1     1      A  RES         I133
  U2D1   CU26  BCLK2_DP  SKX_EXT_B_BGA1  I172

CLK_100M_CPU1_BCLK2_R_DN   @BASEBOARD_FAB2_LIB.BASEBOARD_FAB2(SCH_1):CLK_100M_CPU1_BCLK2_R_DN
  EU4D2   51  DIF_8N  NB3W1200L_LCC   I1
  R4D11    1      A  RES         I44

CLK_100M_CPU1_BCLK2_R_DP   @BASEBOARD_FAB2_LIB.BASEBOARD_FAB2(SCH_1):CLK_100M_CPU1_BCLK2_R_DP
  EU4D2   50  DIF_8P  NB3W1200L_LCC   I1
  R4D9     1      A  RES         I39

CLK_100M_CPU1_PE_REFCLK_DN   @BASEBOARD_FAB2_LIB.BASEBOARD_FAB2(SCH_1):CLK_100M_CPU1_PE_REFCLK_DN
  R4D16    2      B  RES         I34
  R7P4     1      A  RES         I131
  U2D1   BU24  CD_PE_REFCLK_DN  SKX_EXT_B_BGA1  I23

CLK_100M_CPU1_PE_REFCLK_DP   @BASEBOARD_FAB2_LIB.BASEBOARD_FAB2(SCH_1):CLK_100M_CPU1_PE_REFCLK_DP
  R4D13    2      B  RES         I29
  R7P3     1      A  RES         I129
  U2D1   BW24  CD_PE_REFCLK_DP  SKX_EXT_B_BGA1  I23

CLK_100M_CPU1_PE_REFCLK_R_DN   @BASEBOARD_FAB2_LIB.BASEBOARD_FAB2(SCH_1):CLK_100M_CPU1_PE_REFCLK_R_DN
  EU4D2   55  DIF_9N  NB3W1200L_LCC   I1
  R4D16    1      A  RES         I34

CLK_100M_CPU1_PE_REFCLK_R_DP   @BASEBOARD_FAB2_LIB.BASEBOARD_FAB2(SCH_1):CLK_100M_CPU1_PE_REFCLK_R_DP
  EU4D2   54  DIF_9P  NB3W1200L_LCC   I1
  R4D13    1      A  RES         I29

CLK_100M_CPU1_RC_REFCLK0_DN   @BASEBOARD_FAB2_LIB.BASEBOARD_FAB2(SCH_1):CLK_100M_CPU1_RC_REFCLK0_DN
  R4D21    2      B  RES         I24
  R7P7     1      A  RES         I127
  U2D1   AP27  RSVD<195>  SKX_EXT_B_BGA1  I169

CLK_100M_CPU1_RC_REFCLK0_DP   @BASEBOARD_FAB2_LIB.BASEBOARD_FAB2(SCH_1):CLK_100M_CPU1_RC_REFCLK0_DP
  R4D19    2      B  RES         I19
  R7P6     1      A  RES         I125
  U2D1   AM27  RSVD<206>  SKX_EXT_B_BGA1  I169

CLK_100M_CPU1_RC_REFCLK0_R_DN   @BASEBOARD_FAB2_LIB.BASEBOARD_FAB2(SCH_1):CLK_100M_CPU1_RC_REFCLK0_R_DN
  EU4D2   60  DIF_10N  NB3W1200L_LCC   I1
  R4D21    1      A  RES         I24

CLK_100M_CPU1_RC_REFCLK0_R_DP   @BASEBOARD_FAB2_LIB.BASEBOARD_FAB2(SCH_1):CLK_100M_CPU1_RC_REFCLK0_R_DP
  EU4D2   59  DIF_10P  NB3W1200L_LCC   I1
  R4D19    1      A  RES         I19

CLK_100M_CPU1_RC_REFCLK1_DN   @BASEBOARD_FAB2_LIB.BASEBOARD_FAB2(SCH_1):CLK_100M_CPU1_RC_REFCLK1_DN
  R4D28    2      B  RES         I14
  R7P12    1      A  RES         I123
  U2D1   BB25  RSVD<165>  SKX_EXT_B_BGA1   I9

CLK_100M_CPU1_RC_REFCLK1_DP   @BASEBOARD_FAB2_LIB.BASEBOARD_FAB2(SCH_1):CLK_100M_CPU1_RC_REFCLK1_DP
  R4D23    2      B  RES          I9
  R7P9     1      A  RES         I121
  U2D1   BD25  RSVD<153>  SKX_EXT_B_BGA1   I9

CLK_100M_CPU1_RC_REFCLK1_R_DN   @BASEBOARD_FAB2_LIB.BASEBOARD_FAB2(SCH_1):CLK_100M_CPU1_RC_REFCLK1_R_DN
  EU4D2   64  DIF_11N  NB3W1200L_LCC   I1
  R4D28    1      A  RES         I14

CLK_100M_CPU1_RC_REFCLK1_R_DP   @BASEBOARD_FAB2_LIB.BASEBOARD_FAB2(SCH_1):CLK_100M_CPU1_RC_REFCLK1_R_DP
  EU4D2   63  DIF_11P  NB3W1200L_LCC   I1
  R4D23    1      A  RES          I9

CLK_100M_DB1200_DN   @BASEBOARD_FAB2_LIB.BASEBOARD_FAB2(SCH_1):CLK_100M_DB1200_DN
  EU4D2   10  CLK_INN  NB3W1200L_LCC   I1
  U7C1   K35  CLKOUT_SRCN<1>  LBG_CORE_QAT_EXT_D  I40

CLK_100M_DB1200_DP   @BASEBOARD_FAB2_LIB.BASEBOARD_FAB2(SCH_1):CLK_100M_DB1200_DP
  EU4D2    9  CLK_INP  NB3W1200L_LCC   I1
  U7C1   H35  CLKOUT_SRCP<1>  LBG_CORE_QAT_EXT_D  I40

CLK_100M_M2_DN   @BASEBOARD_FAB2_LIB.BASEBOARD_FAB2(SCH_1):CLK_100M_M2_DN
  J8F1    53  REFCLKN  SCONN75K_H17033002_SMT1  I53
  U7C1   K27  CLKOUT_SRCN<15>  LBG_CORE_QAT_EXT_D  I40

CLK_100M_M2_DP   @BASEBOARD_FAB2_LIB.BASEBOARD_FAB2(SCH_1):CLK_100M_M2_DP
  J8F1    55  REFCLKP  SCONN75K_H17033002_SMT1  I53
  U7C1   H27  CLKOUT_SRCP<15>  LBG_CORE_QAT_EXT_D  I40

CLK_100M_MEZZ1_DN   @BASEBOARD_FAB2_LIB.BASEBOARD_FAB2(SCH_1):CLK_100M_MEZZ1_DN
  J9B3    50   IO50  SCONN120_A28699018_SM  I336
  U7C1   D31  CLKOUT_SRCN<8>  LBG_CORE_QAT_EXT_D  I40

CLK_100M_MEZZ1_DP   @BASEBOARD_FAB2_LIB.BASEBOARD_FAB2(SCH_1):CLK_100M_MEZZ1_DP
  J9B3    48   IO48  SCONN120_A28699018_SM  I336
  U7C1   B31  CLKOUT_SRCP<8>  LBG_CORE_QAT_EXT_D  I40

CLK_100M_MEZZ2_DN   @BASEBOARD_FAB2_LIB.BASEBOARD_FAB2(SCH_1):CLK_100M_MEZZ2_DN
  J9B3    53   IO53  SCONN120_A28699018_SM  I336
  U7C1   J26  CLKOUT_SRCN<9>  LBG_CORE_QAT_EXT_D  I40

CLK_100M_MEZZ2_DP   @BASEBOARD_FAB2_LIB.BASEBOARD_FAB2(SCH_1):CLK_100M_MEZZ2_DP
  J9B3    51   IO51  SCONN120_A28699018_SM  I336
  U7C1   G26  CLKOUT_SRCP<9>  LBG_CORE_QAT_EXT_D  I40

CLK_100M_MEZZ3_DN   @BASEBOARD_FAB2_LIB.BASEBOARD_FAB2(SCH_1):CLK_100M_MEZZ3_DN
  J8E3    71   IO71  SCONN80_E67482007_SM  I119
  U7C1   B23  CLKOUT_SRCN<10>  LBG_CORE_QAT_EXT_D  I40

CLK_100M_MEZZ3_DP   @BASEBOARD_FAB2_LIB.BASEBOARD_FAB2(SCH_1):CLK_100M_MEZZ3_DP
  J8E3    69   IO69  SCONN80_E67482007_SM  I119
  U7C1   D23  CLKOUT_SRCP<10>  LBG_CORE_QAT_EXT_D  I40

CLK_100M_MEZZ4_DN   @BASEBOARD_FAB2_LIB.BASEBOARD_FAB2(SCH_1):CLK_100M_MEZZ4_DN
  J8E3    76   IO76  SCONN80_E67482007_SM  I119
  U7C1   B21  CLKOUT_SRCN<11>  LBG_CORE_QAT_EXT_D  I40

CLK_100M_MEZZ4_DP   @BASEBOARD_FAB2_LIB.BASEBOARD_FAB2(SCH_1):CLK_100M_MEZZ4_DP
  J8E3    74   IO74  SCONN80_E67482007_SM  I119
  U7C1   D21  CLKOUT_SRCP<11>  LBG_CORE_QAT_EXT_D  I40

CLK_100M_PCH_SLOTX24_S0_DN   @BASEBOARD_FAB2_LIB.BASEBOARD_FAB2(SCH_1):CLK_100M_PCH_SLOTX24_S0_DN
  J8G1    35   IO35  SCONN200_H68296001_SM  I258
  U7C1   J33  CLKOUT_SRCN<2>  LBG_CORE_QAT_EXT_D  I40

CLK_100M_PCH_SLOTX24_S0_DP   @BASEBOARD_FAB2_LIB.BASEBOARD_FAB2(SCH_1):CLK_100M_PCH_SLOTX24_S0_DP
  J8G1    33   IO33  SCONN200_H68296001_SM  I258
  U7C1   G33  CLKOUT_SRCP<2>  LBG_CORE_QAT_EXT_D  I40

CLK_100M_PCH_SLOTX24_S1_DN   @BASEBOARD_FAB2_LIB.BASEBOARD_FAB2(SCH_1):CLK_100M_PCH_SLOTX24_S1_DN
  J8G1    38   IO38  SCONN200_H68296001_SM  I258
  U7C1   K42  CLKOUT_SRCN<3>  LBG_CORE_QAT_EXT_D  I40

CLK_100M_PCH_SLOTX24_S1_DP   @BASEBOARD_FAB2_LIB.BASEBOARD_FAB2(SCH_1):CLK_100M_PCH_SLOTX24_S1_DP
  J8G1    36   IO36  SCONN200_H68296001_SM  I258
  U7C1   H42  CLKOUT_SRCP<3>  LBG_CORE_QAT_EXT_D  I40

CLK_100M_PCH_SLOTX24_S2_DN   @BASEBOARD_FAB2_LIB.BASEBOARD_FAB2(SCH_1):CLK_100M_PCH_SLOTX24_S2_DN
  J8G1    41   IO41  SCONN200_H68296001_SM  I258
  U7C1   A28  CLKOUT_SRCN<4>  LBG_CORE_QAT_EXT_D  I40

CLK_100M_PCH_SLOTX24_S2_DP   @BASEBOARD_FAB2_LIB.BASEBOARD_FAB2(SCH_1):CLK_100M_PCH_SLOTX24_S2_DP
  J8G1    39   IO39  SCONN200_H68296001_SM  I258
  U7C1   C28  CLKOUT_SRCP<4>  LBG_CORE_QAT_EXT_D  I40

CLK_100M_PCH_SLOTX24_S3_DN   @BASEBOARD_FAB2_LIB.BASEBOARD_FAB2(SCH_1):CLK_100M_PCH_SLOTX24_S3_DN
  J8G1    44   IO44  SCONN200_H68296001_SM  I258
  U7C1   J40  CLKOUT_SRCN<5>  LBG_CORE_QAT_EXT_D  I40

CLK_100M_PCH_SLOTX24_S3_DP   @BASEBOARD_FAB2_LIB.BASEBOARD_FAB2(SCH_1):CLK_100M_PCH_SLOTX24_S3_DP
  J8G1    42   IO42  SCONN200_H68296001_SM  I258
  U7C1   G40  CLKOUT_SRCP<5>  LBG_CORE_QAT_EXT_D  I40

CLK_100M_PCH_SLOTX24_S4_DN   @BASEBOARD_FAB2_LIB.BASEBOARD_FAB2(SCH_1):CLK_100M_PCH_SLOTX24_S4_DN
  J8G1    47   IO47  SCONN200_H68296001_SM  I258
  U7C1   D33  CLKOUT_SRCN<6>  LBG_CORE_QAT_EXT_D  I40

CLK_100M_PCH_SLOTX24_S4_DP   @BASEBOARD_FAB2_LIB.BASEBOARD_FAB2(SCH_1):CLK_100M_PCH_SLOTX24_S4_DP
  J8G1    45   IO45  SCONN200_H68296001_SM  I258
  U7C1   B33  CLKOUT_SRCP<6>  LBG_CORE_QAT_EXT_D  I40

CLK_100M_PCH_SLOTX24_S5_DN   @BASEBOARD_FAB2_LIB.BASEBOARD_FAB2(SCH_1):CLK_100M_PCH_SLOTX24_S5_DN
  J8G1    50   IO50  SCONN200_H68296001_SM  I258
  U7C1   H31  CLKOUT_SRCN<7>  LBG_CORE_QAT_EXT_D  I40

CLK_100M_PCH_SLOTX24_S5_DP   @BASEBOARD_FAB2_LIB.BASEBOARD_FAB2(SCH_1):CLK_100M_PCH_SLOTX24_S5_DP
  J8G1    48   IO48  SCONN200_H68296001_SM  I258
  U7C1   K31  CLKOUT_SRCP<7>  LBG_CORE_QAT_EXT_D  I40

CLK_100M_PCH_XDP_DN   @BASEBOARD_FAB2_LIB.BASEBOARD_FAB2(SCH_1):CLK_100M_PCH_XDP_DN
  J9A3    42   IO42  SCONN60_C21100002  I26
  U7C1   A39  CLKOUT_ITPXDPN  LBG_CORE_QAT_EXT_D  I40

CLK_100M_PCH_XDP_DP   @BASEBOARD_FAB2_LIB.BASEBOARD_FAB2(SCH_1):CLK_100M_PCH_XDP_DP
  J9A3    40   IO40  SCONN60_C21100002  I26
  U7C1   C39  CLKOUT_ITPXDPP  LBG_CORE_QAT_EXT_D  I40

CLK_100M_SPRV_DN   @BASEBOARD_FAB2_LIB.BASEBOARD_FAB2(SCH_1):CLK_100M_SPRV_DN
  EU9E1   25  PECLKN  SPRINGVILLE_SM1  I72
  U7C1   C20  CLKOUT_SRCN<14>  LBG_CORE_QAT_EXT_D  I40

CLK_100M_SPRV_DP   @BASEBOARD_FAB2_LIB.BASEBOARD_FAB2(SCH_1):CLK_100M_SPRV_DP
  EU9E1   26  PECLKP  SPRINGVILLE_SM1  I72
  U7C1   A20  CLKOUT_SRCP<14>  LBG_CORE_QAT_EXT_D  I40

CLK_156M_OSC_BRD_CPU0_DN   @BASEBOARD_FAB2_LIB.BASEBOARD_FAB2(SCH_1):CLK_156M_OSC_BRD_CPU0_DN
  R6F7     1      A  RES         I67
  Y6F1     5  OUT_N  OSC_C_6P10  I71

CLK_156M_OSC_BRD_CPU0_DP   @BASEBOARD_FAB2_LIB.BASEBOARD_FAB2(SCH_1):CLK_156M_OSC_BRD_CPU0_DP
  R6F9     1      A  RES         I68
  Y6F1     4    OUT  OSC_C_6P10  I71

CLK_156M_OSC_BRD_CPU1_DN   @BASEBOARD_FAB2_LIB.BASEBOARD_FAB2(SCH_1):CLK_156M_OSC_BRD_CPU1_DN
  R3F2     1      A  RES         I69
  Y3F1     5  OUT_N  OSC_C_6P10  I72

CLK_156M_OSC_BRD_CPU1_DP   @BASEBOARD_FAB2_LIB.BASEBOARD_FAB2(SCH_1):CLK_156M_OSC_BRD_CPU1_DP
  R3F4     1      A  RES         I70
  Y3F1     4    OUT  OSC_C_6P10  I72

CLK_156M_OSC_CPU0_HFI_DN   @BASEBOARD_FAB2_LIB.BASEBOARD_FAB2(SCH_1):CLK_156M_OSC_CPU0_HFI_DN
  R6F6     2      B  RES         I41
  R6F7     2      B  RES         I67
  U5D1   BE16  CD_HFI_REFCLK_DN  SKX_EXT_B_BGA1  I61

CLK_156M_OSC_CPU0_HFI_DP   @BASEBOARD_FAB2_LIB.BASEBOARD_FAB2(SCH_1):CLK_156M_OSC_CPU0_HFI_DP
  R6F8     2      B  RES         I37
  R6F9     2      B  RES         I68
  U5D1   BG16  CD_HFI_REFCLK_DP  SKX_EXT_B_BGA1  I61

CLK_156M_OSC_CPU1_HFI_DN   @BASEBOARD_FAB2_LIB.BASEBOARD_FAB2(SCH_1):CLK_156M_OSC_CPU1_HFI_DN
  R3F1     2      B  RES         I51
  R3F2     2      B  RES         I69
  U2D1   BE16  CD_HFI_REFCLK_DN  SKX_EXT_B_BGA1  I23

CLK_156M_OSC_CPU1_HFI_DP   @BASEBOARD_FAB2_LIB.BASEBOARD_FAB2(SCH_1):CLK_156M_OSC_CPU1_HFI_DP
  R3F3     2      B  RES         I53
  R3F4     2      B  RES         I70
  U2D1   BG16  CD_HFI_REFCLK_DP  SKX_EXT_B_BGA1  I23

CLK_24M_25M_BMC_CLKIN   @BASEBOARD_FAB2_LIB.BASEBOARD_FAB2(SCH_1):CLK_24M_25M_BMC_CLKIN
  R9F60    2      B  RES         I257
  R9F62    2      B  RES         I256
  U9F4   AB22  CLKIN  AST1250_BGA  I100

CLK_24M_BMC_CLKIN_R   @BASEBOARD_FAB2_LIB.BASEBOARD_FAB2(SCH_1):CLK_24M_BMC_CLKIN_R
  R9F62    1      A  RES         I256
  Y9F2     3    OUT  OSC_C_SM4   I250

CLK_24M_BMC_LPC   @BASEBOARD_FAB2_LIB.BASEBOARD_FAB2(SCH_1):CLK_24M_BMC_LPC
  R2T15    1      A  RES         I532
  R7C26    1      A  RES         I189
  U9F4   B20   LCLK  AST1250_BGA  I347

CLK_24M_BMC_LPC_R   @BASEBOARD_FAB2_LIB.BASEBOARD_FAB2(SCH_1):CLK_24M_BMC_LPC_R
  R7C26    2      B  RES         I189
  U7C1    R3  GPP_A9_CLKOUT_LPC0_ESPI_CLK  LBG_CORE_QAT_EXT_D  I115

CLK_25M_BMC     @BASEBOARD_FAB2_LIB.BASEBOARD_FAB2(SCH_1):CLK_25M_BMC
  R8F29    2      B  RES         I20
  R9F60    1      A  RES         I257

CLK_25M_BMC_R   @BASEBOARD_FAB2_LIB.BASEBOARD_FAB2(SCH_1):CLK_25M_BMC_R
  EU8F2   16  25MHZ_0  ICS9FGP204_MLFP  I34
  R8F29    1      A  RES         I20

CLK_25M_CPLD    @BASEBOARD_FAB2_LIB.BASEBOARD_FAB2(SCH_1):CLK_25M_CPLD
  R2T47    2      B  RES         I130
  U8D7    L2  PL12A_PCLKT3_0  LCMXO2_A_256BGA  I179

CLK_25M_CPLD_R   @BASEBOARD_FAB2_LIB.BASEBOARD_FAB2(SCH_1):CLK_25M_CPLD_R
  EU8F2   17  25MHZ_1  ICS9FGP204_MLFP  I34
  R2T47    1      A  RES         I130

CLK_322M_156M_CPU0_OSC_VRM_DN   @BASEBOARD_FAB2_LIB.BASEBOARD_FAB2(SCH_1):CLK_322M_156M_CPU0_OSC_VRM_DN
  J6E1    F5   IOF5  SCONN120_H61426002_SM  I55
  R6F6     1      A  RES         I41
  R6F10    1      A  RES         I78

CLK_322M_156M_CPU0_OSC_VRM_DP   @BASEBOARD_FAB2_LIB.BASEBOARD_FAB2(SCH_1):CLK_322M_156M_CPU0_OSC_VRM_DP
  J6E1    E5   IOE5  SCONN120_H61426002_SM  I55
  R6F8     1      A  RES         I37
  R6F11    1      A  RES         I79

CLK_322M_156M_CPU1_OSC_VRM_DN   @BASEBOARD_FAB2_LIB.BASEBOARD_FAB2(SCH_1):CLK_322M_156M_CPU1_OSC_VRM_DN
  J4E1    F5   IOF5  SCONN120_H61426002_SM  I45
  R3F1     1      A  RES         I51
  R3F5     1      A  RES         I84

CLK_322M_156M_CPU1_OSC_VRM_DP   @BASEBOARD_FAB2_LIB.BASEBOARD_FAB2(SCH_1):CLK_322M_156M_CPU1_OSC_VRM_DP
  J4E1    E5   IOE5  SCONN120_H61426002_SM  I45
  R3F3     1      A  RES         I53
  R3F6     1      A  RES         I88

CLK_322M_OSC_CPU0_RC_DN   @BASEBOARD_FAB2_LIB.BASEBOARD_FAB2(SCH_1):CLK_322M_OSC_CPU0_RC_DN
  R6F10    2      B  RES         I78
  U5D1   AL26  RSVD<213>  SKX_EXT_B_BGA1  I204

CLK_322M_OSC_CPU0_RC_DP   @BASEBOARD_FAB2_LIB.BASEBOARD_FAB2(SCH_1):CLK_322M_OSC_CPU0_RC_DP
  R6F11    2      B  RES         I79
  U5D1   AK27  RSVD<220>  SKX_EXT_B_BGA1  I204

CLK_322M_OSC_CPU1_RC_DN   @BASEBOARD_FAB2_LIB.BASEBOARD_FAB2(SCH_1):CLK_322M_OSC_CPU1_RC_DN
  R3F5     2      B  RES         I84
  U2D1   AL26  RSVD<213>  SKX_EXT_B_BGA1  I169

CLK_322M_OSC_CPU1_RC_DP   @BASEBOARD_FAB2_LIB.BASEBOARD_FAB2(SCH_1):CLK_322M_OSC_CPU1_RC_DP
  R3F6     2      B  RES         I88
  U2D1   AK27  RSVD<220>  SKX_EXT_B_BGA1  I169

CLK_32K_SUSCLK_PLD   @BASEBOARD_FAB2_LIB.BASEBOARD_FAB2(SCH_1):CLK_32K_SUSCLK_PLD
  R8F27    2      B  RES         I129
  U8D7    E1  PL3A_PCLKT5_0  LCMXO2_A_256BGA  I179

CLK_32K_SUSCLK_PLD_R   @BASEBOARD_FAB2_LIB.BASEBOARD_FAB2(SCH_1):CLK_32K_SUSCLK_PLD_R
  EU8F2   13  32KHZ  ICS9FGP204_MLFP  I34
  R8F27    1      A  RES         I129

CLK_48M_USB_BMC   @BASEBOARD_FAB2_LIB.BASEBOARD_FAB2(SCH_1):CLK_48M_USB_BMC
  U7C1   BW50  CLOCKSE_BMCCLK  LBG_CORE_QAT_EXT_D  I40
  U9F4   Y21  GPIOG5_WDTRST2_USBCKI  AST1250_BGA  I100

CLK_50M_CKMNG_BMC_1   @BASEBOARD_FAB2_LIB.BASEBOARD_FAB2(SCH_1):CLK_50M_CKMNG_BMC_1
  R2T46    2      B  RES         I125
  U9F4   E11  RGMII1RXCK_RMII1RCLK_GPIOU4  AST1250_BGA   I1

CLK_50M_CKMNG_BMC_1_R   @BASEBOARD_FAB2_LIB.BASEBOARD_FAB2(SCH_1):CLK_50M_CKMNG_BMC_1_R
  EU8F2   32  RMII<1>  ICS9FGP204_MLFP  I34
  R2T46    1      A  RES         I125

CLK_50M_CKMNG_BMC_2   @BASEBOARD_FAB2_LIB.BASEBOARD_FAB2(SCH_1):CLK_50M_CKMNG_BMC_2
  R8G1     2      B  RES         I133
  U9F4    C9  RGMII2RXCK_RMII2RCLK_GPIOV2  AST1250_BGA   I1

CLK_50M_CKMNG_BMC_2_R   @BASEBOARD_FAB2_LIB.BASEBOARD_FAB2(SCH_1):CLK_50M_CKMNG_BMC_2_R
  EU8F2   29  RMII<2>  ICS9FGP204_MLFP  I34
  R8G1     1      A  RES         I133

CLK_50M_CKMNG_OCP   @BASEBOARD_FAB2_LIB.BASEBOARD_FAB2(SCH_1):CLK_50M_CKMNG_OCP
  J9B3    29   IO29  SCONN120_A28699018_SM  I336
  R2T42    2      B  RES         I124

CLK_50M_CKMNG_OCP_R   @BASEBOARD_FAB2_LIB.BASEBOARD_FAB2(SCH_1):CLK_50M_CKMNG_OCP_R
  EU8F2   33  RMII<0>  ICS9FGP204_MLFP  I34
  R2T42    1      A  RES         I124

CLK_50M_CKMNG_PCH_10GBE   @BASEBOARD_FAB2_LIB.BASEBOARD_FAB2(SCH_1):CLK_50M_CKMNG_PCH_10GBE
  R7C20    1      A  RES         I73
  R8G24    2      B  RES         I132
  U7C1   AJ1  GPP_K0_LAN_NCSI_CLK_IN  LBG_CORE_QAT_EXT_D  I34

CLK_50M_CKMNG_PCH_10GBE_R   @BASEBOARD_FAB2_LIB.BASEBOARD_FAB2(SCH_1):CLK_50M_CKMNG_PCH_10GBE_R
  EU8F2   25  RMII<4>  ICS9FGP204_MLFP  I34
  R8G24    1      A  RES         I132

CLK_50M_CKMNG_SPRVLLE   @BASEBOARD_FAB2_LIB.BASEBOARD_FAB2(SCH_1):CLK_50M_CKMNG_SPRVLLE
  EU9E1    2  NC_SI_CLK_IN  SPRINGVILLE_SM1  I72
  R1R12    1      A  RES         I213
  R8G25    2      B  RES         I131

CLK_50M_CKMNG_SPRVLLE_R   @BASEBOARD_FAB2_LIB.BASEBOARD_FAB2(SCH_1):CLK_50M_CKMNG_SPRVLLE_R
  EU8F2   28  RMII<3>  ICS9FGP204_MLFP  I34
  R8G25    1      A  RES         I131

DMI_CPU0_PCH_RX_C_DN<0>   @BASEBOARD_FAB2_LIB.BASEBOARD_FAB2(SCH_1):DMI_CPU0_PCH_RX_C_DN<0>
  C3M44    2      B  CAP_0402    I80
  U5D1   CK9  DMI_RX_DN<0>  SKX_EXT_B_BGA1  I61

DMI_CPU0_PCH_RX_C_DN<1>   @BASEBOARD_FAB2_LIB.BASEBOARD_FAB2(SCH_1):DMI_CPU0_PCH_RX_C_DN<1>
  C3M41    2      B  CAP_0402    I81
  U5D1   CM11  DMI_RX_DN<1>  SKX_EXT_B_BGA1  I61

DMI_CPU0_PCH_RX_C_DN<2>   @BASEBOARD_FAB2_LIB.BASEBOARD_FAB2(SCH_1):DMI_CPU0_PCH_RX_C_DN<2>
  C3M45    2      B  CAP_0402    I82
  U5D1   CR12  DMI_RX_DN<2>  SKX_EXT_B_BGA1  I61

DMI_CPU0_PCH_RX_C_DN<3>   @BASEBOARD_FAB2_LIB.BASEBOARD_FAB2(SCH_1):DMI_CPU0_PCH_RX_C_DN<3>
  C3N13    2      B  CAP_0402    I83
  U5D1   CT11  DMI_RX_DN<3>  SKX_EXT_B_BGA1  I61

DMI_CPU0_PCH_RX_C_DP<0>   @BASEBOARD_FAB2_LIB.BASEBOARD_FAB2(SCH_1):DMI_CPU0_PCH_RX_C_DP<0>
  C3M40    2      B  CAP_0402    I72
  U5D1   CL10  DMI_RX_DP<0>  SKX_EXT_B_BGA1  I61

DMI_CPU0_PCH_RX_C_DP<1>   @BASEBOARD_FAB2_LIB.BASEBOARD_FAB2(SCH_1):DMI_CPU0_PCH_RX_C_DP<1>
  C3M37    2      B  CAP_0402    I73
  U5D1   CN10  DMI_RX_DP<1>  SKX_EXT_B_BGA1  I61

DMI_CPU0_PCH_RX_C_DP<2>   @BASEBOARD_FAB2_LIB.BASEBOARD_FAB2(SCH_1):DMI_CPU0_PCH_RX_C_DP<2>
  C3N9     2      B  CAP_0402    I74
  U5D1   CP11  DMI_RX_DP<2>  SKX_EXT_B_BGA1  I61

DMI_CPU0_PCH_RX_C_DP<3>   @BASEBOARD_FAB2_LIB.BASEBOARD_FAB2(SCH_1):DMI_CPU0_PCH_RX_C_DP<3>
  C3N8     2      B  CAP_0402    I75
  U5D1   CV11  DMI_RX_DP<3>  SKX_EXT_B_BGA1  I61

DMI_CPU0_PCH_RX_DN<0>   @BASEBOARD_FAB2_LIB.BASEBOARD_FAB2(SCH_1):DMI_CPU0_PCH_RX_DN<0>
  C3M44    1      A  CAP_0402    I80
  U7C1   H46  DMI_TXN<0>  LBG_CORE_QAT_EXT_D   I9

DMI_CPU0_PCH_RX_DN<1>   @BASEBOARD_FAB2_LIB.BASEBOARD_FAB2(SCH_1):DMI_CPU0_PCH_RX_DN<1>
  C3M41    1      A  CAP_0402    I81
  U7C1   J48  DMI_TXN<1>  LBG_CORE_QAT_EXT_D   I9

DMI_CPU0_PCH_RX_DN<2>   @BASEBOARD_FAB2_LIB.BASEBOARD_FAB2(SCH_1):DMI_CPU0_PCH_RX_DN<2>
  C3M45    1      A  CAP_0402    I82
  U7C1   K50  DMI_TXN<2>  LBG_CORE_QAT_EXT_D   I9

DMI_CPU0_PCH_RX_DN<3>   @BASEBOARD_FAB2_LIB.BASEBOARD_FAB2(SCH_1):DMI_CPU0_PCH_RX_DN<3>
  C3N13    1      A  CAP_0402    I83
  U7C1   P52  DMI_TXN<3>  LBG_CORE_QAT_EXT_D   I9

DMI_CPU0_PCH_RX_DP<0>   @BASEBOARD_FAB2_LIB.BASEBOARD_FAB2(SCH_1):DMI_CPU0_PCH_RX_DP<0>
  C3M40    1      A  CAP_0402    I72
  U7C1   K46  DMI_TXP<0>  LBG_CORE_QAT_EXT_D   I9

DMI_CPU0_PCH_RX_DP<1>   @BASEBOARD_FAB2_LIB.BASEBOARD_FAB2(SCH_1):DMI_CPU0_PCH_RX_DP<1>
  C3M37    1      A  CAP_0402    I73
  U7C1   H50  DMI_TXP<1>  LBG_CORE_QAT_EXT_D   I9

DMI_CPU0_PCH_RX_DP<2>   @BASEBOARD_FAB2_LIB.BASEBOARD_FAB2(SCH_1):DMI_CPU0_PCH_RX_DP<2>
  C3N9     1      A  CAP_0402    I74
  U7C1   M52  DMI_TXP<2>  LBG_CORE_QAT_EXT_D   I9

DMI_CPU0_PCH_RX_DP<3>   @BASEBOARD_FAB2_LIB.BASEBOARD_FAB2(SCH_1):DMI_CPU0_PCH_RX_DP<3>
  C3N8     1      A  CAP_0402    I75
  U7C1   N54  DMI_TXP<3>  LBG_CORE_QAT_EXT_D   I9

DMI_CPU0_PCH_TX_C_DN<0>   @BASEBOARD_FAB2_LIB.BASEBOARD_FAB2(SCH_1):DMI_CPU0_PCH_TX_C_DN<0>
  C7C3     2      B  CAP_0402    I76
  U7C1   D42  DMI_RXN<0>  LBG_CORE_QAT_EXT_D   I9

DMI_CPU0_PCH_TX_C_DN<1>   @BASEBOARD_FAB2_LIB.BASEBOARD_FAB2(SCH_1):DMI_CPU0_PCH_TX_C_DN<1>
  C7C1     2      B  CAP_0402    I77
  U7C1   C43  DMI_RXN<1>  LBG_CORE_QAT_EXT_D   I9

DMI_CPU0_PCH_TX_C_DN<2>   @BASEBOARD_FAB2_LIB.BASEBOARD_FAB2(SCH_1):DMI_CPU0_PCH_TX_C_DN<2>
  C7B29    2      B  CAP_0402    I78
  U7C1   D44  DMI_RXN<2>  LBG_CORE_QAT_EXT_D   I9

DMI_CPU0_PCH_TX_C_DN<3>   @BASEBOARD_FAB2_LIB.BASEBOARD_FAB2(SCH_1):DMI_CPU0_PCH_TX_C_DN<3>
  C7B26    2      B  CAP_0402    I79
  U7C1   C45  DMI_RXN<3>  LBG_CORE_QAT_EXT_D   I9

DMI_CPU0_PCH_TX_C_DP<0>   @BASEBOARD_FAB2_LIB.BASEBOARD_FAB2(SCH_1):DMI_CPU0_PCH_TX_C_DP<0>
  C7C2     2      B  CAP_0402    I71
  U7C1   B42  DMI_RXP<0>  LBG_CORE_QAT_EXT_D   I9

DMI_CPU0_PCH_TX_C_DP<1>   @BASEBOARD_FAB2_LIB.BASEBOARD_FAB2(SCH_1):DMI_CPU0_PCH_TX_C_DP<1>
  C7B28    2      B  CAP_0402    I70
  U7C1   A43  DMI_RXP<1>  LBG_CORE_QAT_EXT_D   I9

DMI_CPU0_PCH_TX_C_DP<2>   @BASEBOARD_FAB2_LIB.BASEBOARD_FAB2(SCH_1):DMI_CPU0_PCH_TX_C_DP<2>
  C7B27    2      B  CAP_0402    I69
  U7C1   B44  DMI_RXP<2>  LBG_CORE_QAT_EXT_D   I9

DMI_CPU0_PCH_TX_C_DP<3>   @BASEBOARD_FAB2_LIB.BASEBOARD_FAB2(SCH_1):DMI_CPU0_PCH_TX_C_DP<3>
  C7B25    2      B  CAP_0402    I35
  U7C1   A45  DMI_RXP<3>  LBG_CORE_QAT_EXT_D   I9

DMI_CPU0_PCH_TX_DN<0>   @BASEBOARD_FAB2_LIB.BASEBOARD_FAB2(SCH_1):DMI_CPU0_PCH_TX_DN<0>
  C7C3     1      A  CAP_0402    I76
  U5D1   CG4  DMI_TX_DN<0>  SKX_EXT_B_BGA1  I61

DMI_CPU0_PCH_TX_DN<1>   @BASEBOARD_FAB2_LIB.BASEBOARD_FAB2(SCH_1):DMI_CPU0_PCH_TX_DN<1>
  C7C1     1      A  CAP_0402    I77
  U5D1   CJ4  DMI_TX_DN<1>  SKX_EXT_B_BGA1  I61

DMI_CPU0_PCH_TX_DN<2>   @BASEBOARD_FAB2_LIB.BASEBOARD_FAB2(SCH_1):DMI_CPU0_PCH_TX_DN<2>
  C7B29    1      A  CAP_0402    I78
  U5D1   CN4  DMI_TX_DN<2>  SKX_EXT_B_BGA1  I61

DMI_CPU0_PCH_TX_DN<3>   @BASEBOARD_FAB2_LIB.BASEBOARD_FAB2(SCH_1):DMI_CPU0_PCH_TX_DN<3>
  C7B26    1      A  CAP_0402    I79
  U5D1   CP5  DMI_TX_DN<3>  SKX_EXT_B_BGA1  I61

DMI_CPU0_PCH_TX_DP<0>   @BASEBOARD_FAB2_LIB.BASEBOARD_FAB2(SCH_1):DMI_CPU0_PCH_TX_DP<0>
  C7C2     1      A  CAP_0402    I71
  U5D1   CH5  DMI_TX_DP<0>  SKX_EXT_B_BGA1  I61

DMI_CPU0_PCH_TX_DP<1>   @BASEBOARD_FAB2_LIB.BASEBOARD_FAB2(SCH_1):DMI_CPU0_PCH_TX_DP<1>
  C7B28    1      A  CAP_0402    I70
  U5D1   CL4  DMI_TX_DP<1>  SKX_EXT_B_BGA1  I61

DMI_CPU0_PCH_TX_DP<2>   @BASEBOARD_FAB2_LIB.BASEBOARD_FAB2(SCH_1):DMI_CPU0_PCH_TX_DP<2>
  C7B27    1      A  CAP_0402    I69
  U5D1   CM3  DMI_TX_DP<2>  SKX_EXT_B_BGA1  I61

DMI_CPU0_PCH_TX_DP<3>   @BASEBOARD_FAB2_LIB.BASEBOARD_FAB2(SCH_1):DMI_CPU0_PCH_TX_DP<3>
  C7B25    1      A  CAP_0402    I35
  U5D1   CR4  DMI_TX_DP<3>  SKX_EXT_B_BGA1  I61

FAN_PWM_OUT_SYS0   @BASEBOARD_FAB2_LIB.BASEBOARD_FAB2(SCH_1):FAN_PWM_OUT_SYS0
  U7C1   BG11  GPP_G8_FANPWM0_FANPWM0IE  LBG_CORE_QAT_EXT_D  I147
  U8G2     2      A  TTL1G07_A_SOP  I88
  U9F4    W4  GPION0_PWM0_VPIG0  AST1250_BGA   I1

FAN_PWM_OUT_SYS0_BUF   @BASEBOARD_FAB2_LIB.BASEBOARD_FAB2(SCH_1):FAN_PWM_OUT_SYS0_BUF
  R2U42    1      A  RES         I99
  U8G2     4      Y  TTL1G07_A_SOP  I88

FAN_PWM_OUT_SYS0_R   @BASEBOARD_FAB2_LIB.BASEBOARD_FAB2(SCH_1):FAN_PWM_OUT_SYS0_R
  CR1E1    2      A  DIODE_SM    I50
  J1F2     4    IO4  CONN6_C74770005   I1
  R1E12    2      B  RES         I51
  R2U42    2      B  RES         I99
  R9T1     1      A  RES         I261

FAN_PWM_OUT_SYS0_R1   @BASEBOARD_FAB2_LIB.BASEBOARD_FAB2(SCH_1):FAN_PWM_OUT_SYS0_R1
  J1F1    F4   IOF4  CONN76_H22707001_THMT1  I111
  R1F9     2      B  RES         I107
  R9T1     2      B  RES         I261

FAN_PWM_OUT_SYS1   @BASEBOARD_FAB2_LIB.BASEBOARD_FAB2(SCH_1):FAN_PWM_OUT_SYS1
  U7C1   AV11  GPP_G9_FANPWM1_FAMPWM1IE  LBG_CORE_QAT_EXT_D  I147
  U8G3     2      A  TTL1G07_A_SOP  I92
  U9F4    Y3  GPION1_PWM1_VPIG1  AST1250_BGA   I1

FAN_PWM_OUT_SYS1_BUF   @BASEBOARD_FAB2_LIB.BASEBOARD_FAB2(SCH_1):FAN_PWM_OUT_SYS1_BUF
  R2U44    1      A  RES         I102
  U8G3     4      Y  TTL1G07_A_SOP  I92

FAN_PWM_OUT_SYS1_R   @BASEBOARD_FAB2_LIB.BASEBOARD_FAB2(SCH_1):FAN_PWM_OUT_SYS1_R
  CR1B1    2      A  DIODE_SM    I64
  J1B2     4    IO4  CONN6_C74770005  I32
  R2U44    2      B  RES         I102
  R7F33    2      B  RES         I65

FAN_TACH0       @BASEBOARD_FAB2_LIB.BASEBOARD_FAB2(SCH_1):FAN_TACH0
  C1F9     1      A  CAP_A       I46
  R1F1     2      B  RES         I45
  R1F2     1      A  RES         I43
  R1F8     1      A  RES         I268
  R1U1     1      A  RES         I144
  U7C1   AY11  GPP_G0_FANTACH0_FANTACH0IE  LBG_CORE_QAT_EXT_D  I147
  U9F4    V6  GPIOO0_TACH0_VPIG8  AST1250_BGA   I1

FAN_TACH0_CPU0_D1   @BASEBOARD_FAB2_LIB.BASEBOARD_FAB2(SCH_1):FAN_TACH0_CPU0_D1
  CR1F1    1      C  DIODE_SM    I42
  J1F2     3    IO3  CONN6_C74770005   I1

FAN_TACH0_CPU0_D2   @BASEBOARD_FAB2_LIB.BASEBOARD_FAB2(SCH_1):FAN_TACH0_CPU0_D2
  CR1F1    2      A  DIODE_SM    I42
  R1F2     2      B  RES         I43

FAN_TACH0_R     @BASEBOARD_FAB2_LIB.BASEBOARD_FAB2(SCH_1):FAN_TACH0_R
  J1F1    D4  GNDD4  CONN76_H22707001_THMT1  I111
  R1C31    2      B  RES         I110
  R1F8     2      B  RES         I268

FAN_TACH1       @BASEBOARD_FAB2_LIB.BASEBOARD_FAB2(SCH_1):FAN_TACH1
  C9T1     1      A  CAP_A       I137
  R1U2     1      A  RES         I145
  R9R10    1      A  RES         I256
  R9T5     2      B  RES         I135
  R9T7     1      A  RES         I134
  U7C1   AV15  GPP_G1_FANTACH1_FANTACH1IE  LBG_CORE_QAT_EXT_D  I147
  U9F4    Y5  GPIOO1_TACH1_VPIG9  AST1250_BGA   I1

FAN_TACH1_CPU1_D1   @BASEBOARD_FAB2_LIB.BASEBOARD_FAB2(SCH_1):FAN_TACH1_CPU1_D1
  CR1F2    1      C  DIODE_SM    I133
  J1F2     5    IO5  CONN6_C74770005   I1

FAN_TACH1_CPU1_D2   @BASEBOARD_FAB2_LIB.BASEBOARD_FAB2(SCH_1):FAN_TACH1_CPU1_D2
  CR1F2    2      A  DIODE_SM    I133
  R9T7     2      B  RES         I134

FAN_TACH1_R     @BASEBOARD_FAB2_LIB.BASEBOARD_FAB2(SCH_1):FAN_TACH1_R
  J1F1    C4   IOC4  CONN76_H22707001_THMT1  I111
  R1C11    2      B  RES         I97
  R9R10    2      B  RES         I256

FAN_TACH2       @BASEBOARD_FAB2_LIB.BASEBOARD_FAB2(SCH_1):FAN_TACH2
  C1B15    1      A  CAP_A       I68
  R1B21    2      B  RES         I70
  R1B22    1      A  RES         I67
  R1U4     1      A  RES         I149
  R9R12    1      A  RES         I255
  U7C1   BE22  GPP_G2_FANTACH2_FANTACH2IE  LBG_CORE_QAT_EXT_D  I147
  U9F4   AA4  GPIOO2_TACH2_VPIR0  AST1250_BGA   I1

FAN_TACH2_CPU1_D1   @BASEBOARD_FAB2_LIB.BASEBOARD_FAB2(SCH_1):FAN_TACH2_CPU1_D1
  CR1B2    1      C  DIODE_SM    I62
  J1B2     3    IO3  CONN6_C74770005  I32

FAN_TACH2_CPU1_D2   @BASEBOARD_FAB2_LIB.BASEBOARD_FAB2(SCH_1):FAN_TACH2_CPU1_D2
  CR1B2    2      A  DIODE_SM    I62
  R1B22    2      B  RES         I67

FAN_TACH2_R     @BASEBOARD_FAB2_LIB.BASEBOARD_FAB2(SCH_1):FAN_TACH2_R
  J1F1    B4   IOB4  CONN76_H22707001_THMT1  I111
  R1C9     2      B  RES         I104
  R9R12    2      B  RES         I255

FAN_TACH3       @BASEBOARD_FAB2_LIB.BASEBOARD_FAB2(SCH_1):FAN_TACH3
  C1B17    1      A  CAP_A       I128
  R1B23    1      A  RES         I124
  R1B24    2      B  RES         I126
  R1U5     1      A  RES         I148
  R9R9     1      A  RES         I254
  U7C1   AY7  GPP_G3_FANTACH3_FANTACH3IE  LBG_CORE_QAT_EXT_D  I147
  U9F4   AB3  GPIOO3_TACH3_VPIR1  AST1250_BGA   I1

FAN_TACH3_CPU1_D1   @BASEBOARD_FAB2_LIB.BASEBOARD_FAB2(SCH_1):FAN_TACH3_CPU1_D1
  CR1B3    1      C  DIODE_SM    I123
  J1B2     5    IO5  CONN6_C74770005  I32

FAN_TACH3_CPU1_D2   @BASEBOARD_FAB2_LIB.BASEBOARD_FAB2(SCH_1):FAN_TACH3_CPU1_D2
  CR1B3    2      A  DIODE_SM    I123
  R1B23    2      B  RES         I124

FAN_TACH3_R     @BASEBOARD_FAB2_LIB.BASEBOARD_FAB2(SCH_1):FAN_TACH3_R
  J1F1    A4  GNDA4  CONN76_H22707001_THMT1  I111
  R1C10    2      B  RES         I101
  R9R9     2      B  RES         I254

FM_100M_N       @BASEBOARD_FAB2_LIB.BASEBOARD_FAB2(SCH_1):FM_100M_N
  EU4D2    4  100M_133M_N  NB3W1200L_LCC   I1
  R4D40    2      B  RES         I45
  R6P23    1      A  RES         I46

FM_10GBE_LOM_DISABLE_N   @BASEBOARD_FAB2_LIB.BASEBOARD_FAB2(SCH_1):FM_10GBE_LOM_DISABLE_N
  R8C23    2      B  RES         I125
  U7C1   BY21  GPP_I9_LAN_DIS_N  LBG_CORE_QAT_EXT_D  I147

FM_156M_CPU0_BRD_OSC_EN   @BASEBOARD_FAB2_LIB.BASEBOARD_FAB2(SCH_1):FM_156M_CPU0_BRD_OSC_EN
  R8D43    1      A  RES         I93
  U8D7   T10  PB18B  LCMXO2_A_256BGA  I179

FM_156M_CPU1_BRD_OSC_EN   @BASEBOARD_FAB2_LIB.BASEBOARD_FAB2(SCH_1):FM_156M_CPU1_BRD_OSC_EN
  R7D36    1      A  RES         I96
  U8D7    N8  PB12C  LCMXO2_A_256BGA  I179

FM_1GB_LOM_DISABLE_N   @BASEBOARD_FAB2_LIB.BASEBOARD_FAB2(SCH_1):FM_1GB_LOM_DISABLE_N
  EU9E1   28  DEV_OFF_N  SPRINGVILLE_SM1  I72
  R8C24    2      B  RES         I120

FM_ADC128_A0    @BASEBOARD_FAB2_LIB.BASEBOARD_FAB2(SCH_1):FM_ADC128_A0
  EU9G1    7     A0  ADC128D818_SM  I52
  R1U45    1      A  RES         I55
  R9G23    2      B  RES         I57

FM_ADC128_A1    @BASEBOARD_FAB2_LIB.BASEBOARD_FAB2(SCH_1):FM_ADC128_A1
  EU9G1    8     A1  ADC128D818_SM  I52
  R1U48    1      A  RES         I56
  R9G25    2      B  RES         I58

FM_ADR_COMPLETE   @BASEBOARD_FAB2_LIB.BASEBOARD_FAB2(SCH_1):FM_ADR_COMPLETE
  R2N26    1      A  RES         I219
  R4T2     1      A  RES          I1
  U8D7    C8  PT17A_PCLKT0_1  LCMXO2_A_256BGA  I59

FM_ADR_COMPLETE_ABC_N   @BASEBOARD_FAB2_LIB.BASEBOARD_FAB2(SCH_1):FM_ADR_COMPLETE_ABC_N
  J4G1   230  SAVE_N_NC  SCONN288_H44441004_PIP   I1
  J4G2   230  SAVE_N_NC  SCONN288_H44441004_PIP  I111
  J4G3   230  SAVE_N_NC  SCONN288_H44441004_PIP  I111
  J6T1   230  SAVE_N_NC  SCONN288_H44441003_PIP  I13
  J6U1   230  SAVE_N_NC  SCONN288_H44441003_PIP  I14
  J6U2   230  SAVE_N_NC  SCONN288_H44441003_PIP  I111
  R6F4     2      B  RES          I3

FM_ADR_COMPLETE_DEF_N   @BASEBOARD_FAB2_LIB.BASEBOARD_FAB2(SCH_1):FM_ADR_COMPLETE_DEF_N
  J4A1   230  SAVE_N_NC  SCONN288_H44441004_PIP  I111
  J4A2   230  SAVE_N_NC  SCONN288_H44441004_PIP  I111
  J4B1   230  SAVE_N_NC  SCONN288_H44441004_PIP  I111
  J6L1   230  SAVE_N_NC  SCONN288_H44441003_PIP  I111
  J6L2   230  SAVE_N_NC  SCONN288_H44441003_PIP  I12
  J6M1   230  SAVE_N_NC  SCONN288_H44441003_PIP  I158
  R6F1     2      B  RES          I4

FM_ADR_COMPLETE_DLY   @BASEBOARD_FAB2_LIB.BASEBOARD_FAB2(SCH_1):FM_ADR_COMPLETE_DLY
  R4T1     1      A  RES          I2
  U8D7   B16   PR1D  LCMXO2_A_256BGA  I59

FM_ADR_COMPLETE_GHJ_N   @BASEBOARD_FAB2_LIB.BASEBOARD_FAB2(SCH_1):FM_ADR_COMPLETE_GHJ_N
  J1G1   230  SAVE_N_NC  SCONN288_H44441004_PIP  I111
  J1G2   230  SAVE_N_NC  SCONN288_H44441004_PIP  I111
  J1G3   230  SAVE_N_NC  SCONN288_H44441004_PIP  I186
  J9T1   230  SAVE_N_NC  SCONN288_H44441003_PIP  I13
  J9U1   230  SAVE_N_NC  SCONN288_H44441003_PIP  I24
  J9U2   230  SAVE_N_NC  SCONN288_H44441003_PIP  I187
  R6F5     2      B  RES          I5

FM_ADR_COMPLETE_KLM_N   @BASEBOARD_FAB2_LIB.BASEBOARD_FAB2(SCH_1):FM_ADR_COMPLETE_KLM_N
  J1A1   230  SAVE_N_NC  SCONN288_H44441004_PIP  I186
  J1A2   230  SAVE_N_NC  SCONN288_H44441004_PIP  I111
  J1B1   230  SAVE_N_NC  SCONN288_H44441004_PIP  I111
  J9L1   230  SAVE_N_NC  SCONN288_H44441003_PIP  I111
  J9L2   230  SAVE_N_NC  SCONN288_H44441003_PIP  I12
  J9M1   230  SAVE_N_NC  SCONN288_H44441003_PIP  I14
  R6F2     2      B  RES          I6

FM_ADR_COMPLETE_R   @BASEBOARD_FAB2_LIB.BASEBOARD_FAB2(SCH_1):FM_ADR_COMPLETE_R
  Q6F1     1   GATE  FET_N       I18
  R4T1     2      B  RES          I2
  R4T2     2      B  RES          I1

FM_ADR_COMPLETE_R1   @BASEBOARD_FAB2_LIB.BASEBOARD_FAB2(SCH_1):FM_ADR_COMPLETE_R1
  R2N26    2      B  RES         I219
  U7C1   BD9  GPP_G17_ADR_COMPLETE  LBG_CORE_QAT_EXT_D  I147

FM_ADR_MODE_SEL   @BASEBOARD_FAB2_LIB.BASEBOARD_FAB2(SCH_1):FM_ADR_MODE_SEL
  R2M7     2      B  RES         I174
  U8D7    T2   PB3C  LCMXO2_A_256BGA  I179

FM_ADR_MODE_SEL_R   @BASEBOARD_FAB2_LIB.BASEBOARD_FAB2(SCH_1):FM_ADR_MODE_SEL_R
  R2M7     1      A  RES         I174
  U7C1   CA43  GPP_D19  LBG_CORE_QAT_EXT_D  I115

FM_ADR_SMI_GPIO_N   @BASEBOARD_FAB2_LIB.BASEBOARD_FAB2(SCH_1):FM_ADR_SMI_GPIO_N
  R2M2     2      B  RES         I346
  R2P12    2      B  RES         I23
  R2R4     2      B  RES         I184
  R8E11    2      B  RES         I279
  U7C1   BJ48  GPP_E7_CPU_GP1  LBG_CORE_QAT_EXT_D  I147

FM_ADR_SMI_GPIO_R_N   @BASEBOARD_FAB2_LIB.BASEBOARD_FAB2(SCH_1):FM_ADR_SMI_GPIO_R_N
  R2R4     1      A  RES         I184
  U8D7    C4   PT9A  LCMXO2_A_256BGA  I59

FM_ALL_WAKE_N   @BASEBOARD_FAB2_LIB.BASEBOARD_FAB2(SCH_1):FM_ALL_WAKE_N
  R8E21    2      B  RES         I33
  R8E26    2      B  RES         I30
  R8E27    2      B  RES         I32
  R8E28    2      B  RES         I31
  R8E29    2      B  RES         I18
  R8E30    2      B  RES         I23
  U8E4     2      A  TTL1G126_A_SOT   I1

FM_BACKUP_BIOS_SEL_N   @BASEBOARD_FAB2_LIB.BASEBOARD_FAB2(SCH_1):FM_BACKUP_BIOS_SEL_N
  Q8F1     1   GATE  FET_N       I126
  R2T6     2      B  RES         I127
  U2T2     1      A  TTL1G32_A   I100
  U7C1   AW4  GPP_H1_SRCCLKREQ7_N  LBG_CORE_QAT_EXT_D  I147
  U9F4    W5  GPION4_PWM4_VPIG4  AST1250_BGA   I1

FM_BATTERY_SENSE_EN   @BASEBOARD_FAB2_LIB.BASEBOARD_FAB2(SCH_1):FM_BATTERY_SENSE_EN
  Q9G1     5  GATE<0>  FET_N_DUAL_SMLF  I157
  Q9G1     6  DRAIN<0>  FET_N_DUAL_SMLF  I162
  R1U49    2      B  RES         I163

FM_BATTERY_SENSE_EN_N   @BASEBOARD_FAB2_LIB.BASEBOARD_FAB2(SCH_1):FM_BATTERY_SENSE_EN_N
  Q9G1     2  GATE<0>  FET_N_DUAL_SMLF  I162
  R9G35    2      B  RES         I164
  U7C1    H9   GPD7  LBG_CORE_QAT_EXT_D  I73
  U9F4   B13  GPIOG4_WDTRST1_OSCCLK  AST1250_BGA  I100

FM_BB_BMC_MP_GPIO   @BASEBOARD_FAB2_LIB.BASEBOARD_FAB2(SCH_1):FM_BB_BMC_MP_GPIO
  J1C1    C4   IOC4  CONN76_H22707001_THMT1  I18
  U7C1   BW39  GPP_C19  LBG_CORE_QAT_EXT_D  I115
  U9F4   A15  GPIOE3_NRI3  AST1250_BGA  I100

FM_BEEP_LED_P   @BASEBOARD_FAB2_LIB.BASEBOARD_FAB2(SCH_1):FM_BEEP_LED_P
  DS9A3    2      A  LED_1NCLF   I67
  R1L33    1      A  RES         I45

FM_BIOS_MRC_DEBUG_MSG_DIS_N   @BASEBOARD_FAB2_LIB.BASEBOARD_FAB2(SCH_1):FM_BIOS_MRC_DEBUG_MSG_DIS_N
  U7C1   BV25  GPP_I10  LBG_CORE_QAT_EXT_D  I147
  U9F4   U20  ROMD7_GPIOS3_VPOCLK  AST1250_BGA   I1

FM_BIOS_POST_CMPLT_N   @BASEBOARD_FAB2_LIB.BASEBOARD_FAB2(SCH_1):FM_BIOS_POST_CMPLT_N
  R8C6     2      B  RES         I303
  U7C1   BJ22  GPP_B20  LBG_CORE_QAT_EXT_D  I115
  U7C1   BY33  GPP_C21  LBG_CORE_QAT_EXT_D  I115
  U9F4    A4  GPIOA2_TIMER3  AST1250_BGA  I100

FM_BIOS_PREFRB2_GOOD   @BASEBOARD_FAB2_LIB.BASEBOARD_FAB2(SCH_1):FM_BIOS_PREFRB2_GOOD
  R2N13    1      A  RES         I142
  U7C1   BK20  GPP_B19  LBG_CORE_QAT_EXT_D  I115
  U9F4   AA2  GPION2_PWM2_VPIG2  AST1250_BGA   I1

FM_BIOS_SMI_ACTIVE_N   @BASEBOARD_FAB2_LIB.BASEBOARD_FAB2(SCH_1):FM_BIOS_SMI_ACTIVE_N
  R2N32    2      B  RES         I341
  U7C1   BA2  GPP_H21_SSATAXPCIE3_SSATAGP3  LBG_CORE_QAT_EXT_D  I147
  U7C1   BE15  GPP_G19_SMI_N  LBG_CORE_QAT_EXT_D  I147
  U9F4   J20  GPIOB1_SALT2  AST1250_BGA  I347

FM_BIOS_SPI_BMC_CTRL   @BASEBOARD_FAB2_LIB.BASEBOARD_FAB2(SCH_1):FM_BIOS_SPI_BMC_CTRL
  R1U6     1      A  RES         I128
  U2T1     1      S  PI3B3257A_TSSOPLF  I75
  U8F1     1      S  PI3B3257A_TSSOPLF  I74
  U9F4    Y4  GPION5_PWM5_VPIG5  AST1250_BGA   I1

FM_BIOS_TOP_SWAP   @BASEBOARD_FAB2_LIB.BASEBOARD_FAB2(SCH_1):FM_BIOS_TOP_SWAP
  J7G3    10   IO10  CONN12_C73564003  I174
  R8E16    1      A  RES         I140
  R8E19    2      B  RES         I361
  U7C1   AP15  GPP_F17_USB2_OC6_N  LBG_CORE_QAT_EXT_D  I147
  U8E3     2      A  TTL1G126_A_SOT  I130
  U9F4    V1  GPIOL3_NRI1_VPIHS  AST1250_BGA  I100

FM_BIOS_TOP_SWAP_SPKR   @BASEBOARD_FAB2_LIB.BASEBOARD_FAB2(SCH_1):FM_BIOS_TOP_SWAP_SPKR
  Q9A3     1   GATE  FET_N       I49
  R8E20    2      B  RES         I126
  U7C1   BH13  GPP_B14_SPKR  LBG_CORE_QAT_EXT_D  I115

FM_BIOS_TOP_SWAP_SPKR_R   @BASEBOARD_FAB2_LIB.BASEBOARD_FAB2(SCH_1):FM_BIOS_TOP_SWAP_SPKR_R
  R8E20    1      A  RES         I126
  U8E3     4      Y  TTL1G126_A_SOT  I130

FM_BIOS_USB_RECOVERY   @BASEBOARD_FAB2_LIB.BASEBOARD_FAB2(SCH_1):FM_BIOS_USB_RECOVERY
  J7G3     4    IO4  CONN12_C73564003  I174
  R3T14    1      A  RES         I156
  U7C1   AH17  GPP_F5_SATA_DEVSLP3  LBG_CORE_QAT_EXT_D  I147

FM_BMC_CPLD_GPO   @BASEBOARD_FAB2_LIB.BASEBOARD_FAB2(SCH_1):FM_BMC_CPLD_GPO
  R2M5     2      B  RES         I348
  U7C1   CA45  GPP_D7  LBG_CORE_QAT_EXT_D  I115
  U8D7    R1  PL14C  LCMXO2_A_256BGA  I179
  U9F4   E18  GPIOB7_EXTRST_N_SPICS1_N  AST1250_BGA  I100

FM_BMC_CPLD_MP_RST_N   @BASEBOARD_FAB2_LIB.BASEBOARD_FAB2(SCH_1):FM_BMC_CPLD_MP_RST_N
  R1L7     2      B  RES         I382
  U7C1   A15   GPD9  LBG_CORE_QAT_EXT_D  I73
  U8D7    R4   PB6D  LCMXO2_A_256BGA  I179
  U9F4   C14  GPIOE6_TXD3  AST1250_BGA  I100

FM_BMC_DISABLE   @BASEBOARD_FAB2_LIB.BASEBOARD_FAB2(SCH_1):FM_BMC_DISABLE
  J9G1     5    IO5  CONN12_C73564003  I128
  R1R11    1      A  RES         I66

FM_BMC_ENABLE_N   @BASEBOARD_FAB2_LIB.BASEBOARD_FAB2(SCH_1):FM_BMC_ENABLE_N
  R9E14    2      B  RES         I379
  R9E15    2      B  RES         I114
  U7C1   BM38  GPP_D5  LBG_CORE_QAT_EXT_D  I115

FM_BMC_FAULT_LED   @BASEBOARD_FAB2_LIB.BASEBOARD_FAB2(SCH_1):FM_BMC_FAULT_LED
  Q9F1     5  GATE<0>  FET_N_DUAL_SMLF  I79
  Q9F1     6  DRAIN<0>  FET_N_DUAL_SMLF  I80
  R9F52    2      B  RES         I82

FM_BMC_FAULT_LED_N   @BASEBOARD_FAB2_LIB.BASEBOARD_FAB2(SCH_1):FM_BMC_FAULT_LED_N
  Q9F1     2  GATE<0>  FET_N_DUAL_SMLF  I80
  R9F30    2      B  RES         I76
  U7C1   BR38  GPP_D8  LBG_CORE_QAT_EXT_D  I115
  U9F4    B5  GPIOA1_MAC2LINK  AST1250_BGA  I100

FM_BMC_HEARTBEAT_N   @BASEBOARD_FAB2_LIB.BASEBOARD_FAB2(SCH_1):FM_BMC_HEARTBEAT_N
  Q9E1     2  GATE<0>  FET_N_DUAL_SMLF  I135
  R8B25    2      B  RES         I140
  U7C1   CA48  GPP_D20  LBG_CORE_QAT_EXT_D  I115
  U9F4   J21  GPIOB0_SALT1  AST1250_BGA  I347

FM_BMC_NMI_N    @BASEBOARD_FAB2_LIB.BASEBOARD_FAB2(SCH_1):FM_BMC_NMI_N
  R2N25    2      B  RES         I302
  R2N27    2      B  RES         I97
  U7C1   BF3  GPP_H20_SSATAXPCIE2_SSATAGP2  LBG_CORE_QAT_EXT_D  I147
  U9F4   AA22  GPIOG6_FLBUSY_N  AST1250_BGA   I1

FM_BMC_ONCTL_N   @BASEBOARD_FAB2_LIB.BASEBOARD_FAB2(SCH_1):FM_BMC_ONCTL_N
  R1T15    1      A  RES         I183
  U8D7    C7  PT13B  LCMXO2_A_256BGA  I59

FM_BMC_ONCTL_R_N   @BASEBOARD_FAB2_LIB.BASEBOARD_FAB2(SCH_1):FM_BMC_ONCTL_R_N
  R1T15    2      B  RES         I183
  R1T23    1      A  RES         I184
  U9F4   K20  GPIOY3_SIOONCTRL_N  AST1250_BGA  I100

FM_BMC_PWRBTN_OUT_N   @BASEBOARD_FAB2_LIB.BASEBOARD_FAB2(SCH_1):FM_BMC_PWRBTN_OUT_N
  R2T34    2      B  RES         I206
  U8F3     3     2A  TTL2G07_SOT23LF  I201
  U9F4   A17  GPIOD3_SD2DAT1  AST1250_BGA  I100

FM_BMC_READY_N   @BASEBOARD_FAB2_LIB.BASEBOARD_FAB2(SCH_1):FM_BMC_READY_N
  R1F9     1      A  RES         I107
  R7D6     2      B  RES         I306
  U7C1   AH13  GPP_F4_SATAXPCIE7_SATAGP7  LBG_CORE_QAT_EXT_D  I147
  U7C1    V1  GPP_A23  LBG_CORE_QAT_EXT_D  I115
  U9F4    H4  GPIOQ4_SCL14  AST1250_BGA  I100

FM_BMC_SYS_THROTTLE_R_N   @BASEBOARD_FAB2_LIB.BASEBOARD_FAB2(SCH_1):FM_BMC_SYS_THROTTLE_R_N
  R2T41    2      B  RES         I203
  U9F4    E6  GPIOA3_TIMER4  AST1250_BGA  I100

FM_BOARD_REV_ID0   @BASEBOARD_FAB2_LIB.BASEBOARD_FAB2(SCH_1):FM_BOARD_REV_ID0
  R1T4     2      B  RES         I14
  R1T10    1      A  RES          I5
  U7C1   CA30  GPP_C12  LBG_CORE_QAT_EXT_D  I115
  U9F4   U21  ROMD4_GPIOS0_VPODE  AST1250_BGA   I1

FM_BOARD_REV_ID1   @BASEBOARD_FAB2_LIB.BASEBOARD_FAB2(SCH_1):FM_BOARD_REV_ID1
  R1T6     2      B  RES         I13
  R1T12    1      A  RES          I6
  U7C1   BV38  GPP_C13  LBG_CORE_QAT_EXT_D  I115
  U9F4   T19  ROMD5_GPIOS1_VPOHS  AST1250_BGA   I1

FM_BOARD_REV_ID2   @BASEBOARD_FAB2_LIB.BASEBOARD_FAB2(SCH_1):FM_BOARD_REV_ID2
  R1T5     2      B  RES         I11
  R1T11    1      A  RES          I7
  U7C1   BV33  GPP_C11  LBG_CORE_QAT_EXT_D  I115
  U9F4   V22  ROMD6_GPIOS2_VPOVS  AST1250_BGA   I1

FM_BOARD_SKU_ID0   @BASEBOARD_FAB2_LIB.BASEBOARD_FAB2(SCH_1):FM_BOARD_SKU_ID0
  R1U18    1      A  RES         I19
  R1U23    2      B  RES         I28
  U7C1   BD13  GPP_G12  LBG_CORE_QAT_EXT_D  I147
  U9F4    Y6  GPIOP0_TACH8_VPIR6  AST1250_BGA   I1

FM_BOARD_SKU_ID1   @BASEBOARD_FAB2_LIB.BASEBOARD_FAB2(SCH_1):FM_BOARD_SKU_ID1
  R1U16    1      A  RES         I20
  R1U22    2      B  RES         I27
  U7C1   AY18  GPP_G13  LBG_CORE_QAT_EXT_D  I147
  U9F4   AB5  GPIOP1_TACH9_VPIR7  AST1250_BGA   I1

FM_BOARD_SKU_ID2   @BASEBOARD_FAB2_LIB.BASEBOARD_FAB2(SCH_1):FM_BOARD_SKU_ID2
  R1U17    1      A  RES         I21
  R1U24    2      B  RES         I25
  U7C1   AV7  GPP_G14  LBG_CORE_QAT_EXT_D  I147
  U9F4    W7  GPIOP2_TACH10_VPIR8  AST1250_BGA   I1

FM_BOARD_SKU_ID3   @BASEBOARD_FAB2_LIB.BASEBOARD_FAB2(SCH_1):FM_BOARD_SKU_ID3
  R1U15    1      A  RES         I22
  R1U21    2      B  RES         I24
  U7C1   BE18  GPP_G15  LBG_CORE_QAT_EXT_D  I147
  U9F4   AA6  GPIOP3_TACH11_VPIR9  AST1250_BGA   I1

FM_BOARD_SKU_ID4   @BASEBOARD_FAB2_LIB.BASEBOARD_FAB2(SCH_1):FM_BOARD_SKU_ID4
  R2N17    2      B  RES         I29
  R2N18    1      A  RES         I32
  U7C1   BD17  GPP_G16  LBG_CORE_QAT_EXT_D  I147
  U9F4    W3  GPIOM4_NDTR2_VPIB6  AST1250_BGA  I100

FM_CPLD_ADR_TRIGGER_N   @BASEBOARD_FAB2_LIB.BASEBOARD_FAB2(SCH_1):FM_CPLD_ADR_TRIGGER_N
  R2M1     1      A  RES         I218
  U8D7   E14   PR2B  LCMXO2_A_256BGA  I59

FM_CPLD_ADR_TRIGGER_R_N   @BASEBOARD_FAB2_LIB.BASEBOARD_FAB2(SCH_1):FM_CPLD_ADR_TRIGGER_R_N
  R2M1     2      B  RES         I218
  U7C1   BE52  GPP_E3_CPU_GP0  LBG_CORE_QAT_EXT_D  I147

FM_CPLD_BMC_PWRDN_N   @BASEBOARD_FAB2_LIB.BASEBOARD_FAB2(SCH_1):FM_CPLD_BMC_PWRDN_N
  R2U4     2      B  RES         I367
  U7C1   BW41  GPP_D6  LBG_CORE_QAT_EXT_D  I115
  U8D7    N9  PB16D  LCMXO2_A_256BGA  I179
  U9F4    D6  GPIOA0_MAC1LINK  AST1250_BGA  I100

FM_CPLD_DBG_PWR_EN   @BASEBOARD_FAB2_LIB.BASEBOARD_FAB2(SCH_1):FM_CPLD_DBG_PWR_EN
  Q1L2     2  GATE<0>  FET_N_DUAL_SMLF  I188
  Q1L2     3  DRAIN<0>  FET_N_DUAL_SMLF  I187
  R1L9     2      B  RES         I130

FM_CPLD_DBG_PWR_EN_N   @BASEBOARD_FAB2_LIB.BASEBOARD_FAB2(SCH_1):FM_CPLD_DBG_PWR_EN_N
  R1L2     1      A  RES         I186
  U8D7    T8  PB12B  LCMXO2_A_256BGA  I179

FM_CPLD_DBG_PWR_EN_R_N   @BASEBOARD_FAB2_LIB.BASEBOARD_FAB2(SCH_1):FM_CPLD_DBG_PWR_EN_R_N
  Q1L2     5  GATE<0>  FET_N_DUAL_SMLF  I187
  R1L2     2      B  RES         I186

FM_CPLD_UART_CH_LOCK_N   @BASEBOARD_FAB2_LIB.BASEBOARD_FAB2(SCH_1):FM_CPLD_UART_CH_LOCK_N
  J8G2     9    IO9  CONN12_C73564003  I124
  R7D30    2      B  RES         I121
  U8D7    M9  PB18C  LCMXO2_A_256BGA  I179

FM_CPU0_AND_CPU1_MCP_PRES   @BASEBOARD_FAB2_LIB.BASEBOARD_FAB2(SCH_1):FM_CPU0_AND_CPU1_MCP_PRES
  U1M6     1   OE_N  74CBTLV1G125  I127
  U8D7   D11  PT21D  LCMXO2_A_256BGA  I59

FM_CPU0_CD_PRES   @BASEBOARD_FAB2_LIB.BASEBOARD_FAB2(SCH_1):FM_CPU0_CD_PRES
  U2M1     6      S  NC7SB3157   I255
  U8D7   C11  PT21B  LCMXO2_A_256BGA  I59

FM_CPU0_FIVR_FAULT_LVT3   @BASEBOARD_FAB2_LIB.BASEBOARD_FAB2(SCH_1):FM_CPU0_FIVR_FAULT_LVT3
  R7D29    2      B  RES         I30
  U8D7   M16  PR12B  LCMXO2_A_256BGA  I59

FM_CPU0_FIVR_FAULT_LVT3_N   @BASEBOARD_FAB2_LIB.BASEBOARD_FAB2(SCH_1):FM_CPU0_FIVR_FAULT_LVT3_N
  R9G16    1      A  RES         I188
  U7C1   BE11  GPP_G10_FANPWM2_FANPWM2IE  LBG_CORE_QAT_EXT_D  I147
  U8D7    F5   PL5C  LCMXO2_A_256BGA  I179

FM_CPU0_FIVR_FAULT_LVT3_R_N   @BASEBOARD_FAB2_LIB.BASEBOARD_FAB2(SCH_1):FM_CPU0_FIVR_FAULT_LVT3_R_N
  R9G16    2      B  RES         I188
  U9F4    H2  GPIOQ<6>  AST1250_BGA  I100

FM_CPU0_FIVR_FAULT_R_LVT3   @BASEBOARD_FAB2_LIB.BASEBOARD_FAB2(SCH_1):FM_CPU0_FIVR_FAULT_R_LVT3
  R7D29    1      A  RES         I30
  U7D2    12     A1  GTL2014_SM  I32

FM_CPU0_MCP_CLK_EN_N   @BASEBOARD_FAB2_LIB.BASEBOARD_FAB2(SCH_1):FM_CPU0_MCP_CLK_EN_N
  EU4D2   29  OE_3_N  NB3W1200L_LCC   I1
  EU4D2   36  OE_4_N  NB3W1200L_LCC   I1
  EU4D2   37  OE_5_N  NB3W1200L_LCC   I1
  R4D70    2      B  RES         I94
  U8D7   F15   PR3B  LCMXO2_A_256BGA  I59

FM_CPU0_OR_CPU1_MCP_PRES   @BASEBOARD_FAB2_LIB.BASEBOARD_FAB2(SCH_1):FM_CPU0_OR_CPU1_MCP_PRES
  U1M5     1   OE_N  74CBTLV1G125  I196
  U8D7   A11  PT21A  LCMXO2_A_256BGA  I59
  U9A5     1   OE_N  74CBTLV1G125  I185

FM_CPU0_PKGID0   @BASEBOARD_FAB2_LIB.BASEBOARD_FAB2(SCH_1):FM_CPU0_PKGID0
  R5N1     2      B  RES         I238
  U5D1   DC72  PKGID<0>  SKX_EXT_B_BGA1  I259
  U8D7    F2  PL3B_PCLKC5_0  LCMXO2_A_256BGA  I179

FM_CPU0_PKGID1   @BASEBOARD_FAB2_LIB.BASEBOARD_FAB2(SCH_1):FM_CPU0_PKGID1
  R5N5     2      B  RES         I239
  U4R1     1   OE_N  74CBTLV1G125  I206
  U5D1   CW72  PKGID<1>  SKX_EXT_B_BGA1  I259
  U8D7    G3   PL5B  LCMXO2_A_256BGA  I179

FM_CPU0_PKGID2   @BASEBOARD_FAB2_LIB.BASEBOARD_FAB2(SCH_1):FM_CPU0_PKGID2
  R5N3     2      B  RES         I240
  U5D1   DA72  PKGID<2>  SKX_EXT_B_BGA1  I259
  U8D7    G2   PL5A  LCMXO2_A_256BGA  I179

FM_CPU0_PROCHOT_LVT3_BMC_N   @BASEBOARD_FAB2_LIB.BASEBOARD_FAB2(SCH_1):FM_CPU0_PROCHOT_LVT3_BMC_N
  R1T36    2      B  RES         I122
  U9F4   AA7  GPIOP6_TACH14_BMCINT  AST1250_BGA   I1

FM_CPU0_PROCHOT_LVT3_K_N   @BASEBOARD_FAB2_LIB.BASEBOARD_FAB2(SCH_1):FM_CPU0_PROCHOT_LVT3_K_N
  R2T38    1      A  RES         I39
  R2T67    2      B  RES         I113
  R2T71    1      A  RES         I109

FM_CPU0_PROCHOT_LVT3_N   @BASEBOARD_FAB2_LIB.BASEBOARD_FAB2(SCH_1):FM_CPU0_PROCHOT_LVT3_N
  R1T35    1      A  RES         I135
  R1T36    1      A  RES         I122
  R2T38    2      B  RES         I39

FM_CPU0_PROCHOT_LVT3_R_N   @BASEBOARD_FAB2_LIB.BASEBOARD_FAB2(SCH_1):FM_CPU0_PROCHOT_LVT3_R_N
  R2T67    1      A  RES         I113
  U2T4    12     A1  GTL2014_SM  I30

FM_CPU0_PROCHOT_PCH_N   @BASEBOARD_FAB2_LIB.BASEBOARD_FAB2(SCH_1):FM_CPU0_PROCHOT_PCH_N
  R1T35    2      B  RES         I135
  U7C1    Y7  GPP_L16_TESTCH1_D5  LBG_CORE_QAT_EXT_D  I34

FM_CPU0_PROC_ID0   @BASEBOARD_FAB2_LIB.BASEBOARD_FAB2(SCH_1):FM_CPU0_PROC_ID0
  R5N4     2      B  RES         I241
  U5D1   CY71  PROC_ID<0>  SKX_EXT_B_BGA1  I259
  U8D7    F1   PL4B  LCMXO2_A_256BGA  I179

FM_CPU0_PROC_ID1   @BASEBOARD_FAB2_LIB.BASEBOARD_FAB2(SCH_1):FM_CPU0_PROC_ID1
  R5N2     2      B  RES         I227
  U5D1   DB71  PROC_ID<1>  SKX_EXT_B_BGA1  I259
  U8D7    F3   PL4A  LCMXO2_A_256BGA  I179

FM_CPU0_RC_EN   @BASEBOARD_FAB2_LIB.BASEBOARD_FAB2(SCH_1):FM_CPU0_RC_EN
  R8D44    2      B  RES         I362
  U7C1   BD20  GPP_G22_SSATA_DEVSLP2  LBG_CORE_QAT_EXT_D  I147
  U8D7    R3   PB3D  LCMXO2_A_256BGA  I179

FM_CPU0_RC_ERROR_N   @BASEBOARD_FAB2_LIB.BASEBOARD_FAB2(SCH_1):FM_CPU0_RC_ERROR_N
  R2M8     2      B  RES         I349
  U5D1   Y23  RSVD<257>  SKX_EXT_B_BGA1  I204
  U7C1   B14  GPD10_SLP_S5_N  LBG_CORE_QAT_EXT_D  I73
  U7C1   BH50  GPP_E0_SATAXPCIE0_SATAGP0  LBG_CORE_QAT_EXT_D  I147
  U9F4    V3  GPIOM0_NCTS2_VPIB2  AST1250_BGA  I100

FM_CPU0_SKTOCC_LVT3_N   @BASEBOARD_FAB2_LIB.BASEBOARD_FAB2(SCH_1):FM_CPU0_SKTOCC_LVT3_N
  R4R5     2      B  RES         I258
  U5D1   AB13  SKTOCC_N  SKX_EXT_B_BGA1  I259
  U7C1   G11  GPD6_SLP_A_N  LBG_CORE_QAT_EXT_D  I73
  U8D7   T14  PB22D  LCMXO2_A_256BGA  I179
  U9F4    C6  GPIOR6_MDC1  AST1250_BGA   I1

FM_CPU0_SM_WP   @BASEBOARD_FAB2_LIB.BASEBOARD_FAB2(SCH_1):FM_CPU0_SM_WP
  R3P54    2      B  RES         I331
  R3P56    1      A  RES         I333
  U5D1   CV59  SM_WP  SKX_EXT_B_BGA1  I259

FM_CPU0_STL_BRD_OSC_EN   @BASEBOARD_FAB2_LIB.BASEBOARD_FAB2(SCH_1):FM_CPU0_STL_BRD_OSC_EN
  R7D40    2      B  RES         I94
  R8D43    2      B  RES         I93
  Y6F1     1  ENABLE_DISABLE  OSC_C_6P10  I71

FM_CPU0_THERMTRIP_LATCH_LVT3_N   @BASEBOARD_FAB2_LIB.BASEBOARD_FAB2(SCH_1):FM_CPU0_THERMTRIP_LATCH_LVT3_N
  U7C1   BN44  GPP_D23  LBG_CORE_QAT_EXT_D  I115
  U8D7   G12   PR3D  LCMXO2_A_256BGA  I59
  U9F4   H19  GPIOB5_LPCPD_N_LPCSMI_N  AST1250_BGA  I347

FM_CPU0_THERMTRIP_LVT3_N   @BASEBOARD_FAB2_LIB.BASEBOARD_FAB2(SCH_1):FM_CPU0_THERMTRIP_LVT3_N
  R7D34    2      B  RES         I24
  U8D7   N15  PR13C  LCMXO2_A_256BGA  I59

FM_CPU0_THERMTRIP_LVT3_R_N   @BASEBOARD_FAB2_LIB.BASEBOARD_FAB2(SCH_1):FM_CPU0_THERMTRIP_LVT3_R_N
  R7D34    1      A  RES         I24
  U7D2     9     A3  GTL2014_SM  I32

FM_CPU0_VRM_322M_156M_OSC_EN   @BASEBOARD_FAB2_LIB.BASEBOARD_FAB2(SCH_1):FM_CPU0_VRM_322M_156M_OSC_EN
  J6B1    E1   IOE1  SCONN120_H61426002_SM  I56
  R7D39    2      B  RES         I95

FM_CPU0_VRM_OSC_EN   @BASEBOARD_FAB2_LIB.BASEBOARD_FAB2(SCH_1):FM_CPU0_VRM_OSC_EN
  R7D39    1      A  RES         I95
  R7D40    1      A  RES         I94
  U8D7   R13  PB22C  LCMXO2_A_256BGA  I179

FM_CPU1_CD_PRES   @BASEBOARD_FAB2_LIB.BASEBOARD_FAB2(SCH_1):FM_CPU1_CD_PRES
  U1M2     6      S  NC7SB3157   I107
  U8D7   F10  PT21C  LCMXO2_A_256BGA  I59

FM_CPU1_FIVR_FAULT_LVT3   @BASEBOARD_FAB2_LIB.BASEBOARD_FAB2(SCH_1):FM_CPU1_FIVR_FAULT_LVT3
  R3P46    2      B  RES         I12
  U8D7   G13   PR4D  LCMXO2_A_256BGA  I59

FM_CPU1_FIVR_FAULT_LVT3_N   @BASEBOARD_FAB2_LIB.BASEBOARD_FAB2(SCH_1):FM_CPU1_FIVR_FAULT_LVT3_N
  R9G10    1      A  RES         I187
  U7C1   BA20  GPP_G11_FANPWM3_FANPMW3IE  LBG_CORE_QAT_EXT_D  I147
  U8D7    E6  PT13C  LCMXO2_A_256BGA  I59

FM_CPU1_FIVR_FAULT_LVT3_R_N   @BASEBOARD_FAB2_LIB.BASEBOARD_FAB2(SCH_1):FM_CPU1_FIVR_FAULT_LVT3_R_N
  R9G10    2      B  RES         I187
  U9F4    H1  GPIOQ<7>  AST1250_BGA  I100

FM_CPU1_FIVR_FAULT_R_LVT3   @BASEBOARD_FAB2_LIB.BASEBOARD_FAB2(SCH_1):FM_CPU1_FIVR_FAULT_R_LVT3
  R3P46    1      A  RES         I12
  U3P2    12     A1  GTL2014_SM   I1

FM_CPU1_MCP_CLK_EN_N   @BASEBOARD_FAB2_LIB.BASEBOARD_FAB2(SCH_1):FM_CPU1_MCP_CLK_EN_N
  EU4D2   53  OE_9_N  NB3W1200L_LCC   I1
  EU4D2   61  OE_10_N  NB3W1200L_LCC   I1
  EU4D2   62  OE_11_N  NB3W1200L_LCC   I1
  R4D69    2      B  RES         I93
  U8D7   F16   PR4B  LCMXO2_A_256BGA  I59

FM_CPU1_PKGID0   @BASEBOARD_FAB2_LIB.BASEBOARD_FAB2(SCH_1):FM_CPU1_PKGID0
  R8N2     2      B  RES         I161
  U2D1   DC72  PKGID<0>  SKX_EXT_B_BGA1  I172
  U8D7   R12  PB25A_SN  LCMXO2_A_256BGA  I179

FM_CPU1_PKGID1   @BASEBOARD_FAB2_LIB.BASEBOARD_FAB2(SCH_1):FM_CPU1_PKGID1
  R8N5     2      B  RES         I160
  U2D1   CW72  PKGID<1>  SKX_EXT_B_BGA1  I172
  U6M1     1   OE_N  74CBTLV1G125  I190
  U8D7   P12  PB24A  LCMXO2_A_256BGA  I179

FM_CPU1_PKGID2   @BASEBOARD_FAB2_LIB.BASEBOARD_FAB2(SCH_1):FM_CPU1_PKGID2
  R8N3     2      B  RES         I159
  U2D1   DA72  PKGID<2>  SKX_EXT_B_BGA1  I172
  U8D7   T11  PB21A  LCMXO2_A_256BGA  I179

FM_CPU1_PROCHOT_LVT3_BMC_N   @BASEBOARD_FAB2_LIB.BASEBOARD_FAB2(SCH_1):FM_CPU1_PROCHOT_LVT3_BMC_N
  R1T37    2      B  RES         I123
  U9F4   AB7  GPIOP7_TACH15_FLACK  AST1250_BGA   I1

FM_CPU1_PROCHOT_LVT3_K_N   @BASEBOARD_FAB2_LIB.BASEBOARD_FAB2(SCH_1):FM_CPU1_PROCHOT_LVT3_K_N
  R7D24    1      A  RES         I62
  R7D41    2      B  RES         I114
  R7D43    1      A  RES         I110

FM_CPU1_PROCHOT_LVT3_N   @BASEBOARD_FAB2_LIB.BASEBOARD_FAB2(SCH_1):FM_CPU1_PROCHOT_LVT3_N
  R1T37    1      A  RES         I123
  R1T38    1      A  RES         I137
  R7D24    2      B  RES         I62

FM_CPU1_PROCHOT_LVT3_R_N   @BASEBOARD_FAB2_LIB.BASEBOARD_FAB2(SCH_1):FM_CPU1_PROCHOT_LVT3_R_N
  R7D41    1      A  RES         I114
  U2T4    13     A0  GTL2014_SM  I30

FM_CPU1_PROCHOT_PCH_N   @BASEBOARD_FAB2_LIB.BASEBOARD_FAB2(SCH_1):FM_CPU1_PROCHOT_PCH_N
  R1T38    2      B  RES         I137
  U7C1   AA9  GPP_L17_TESTCH1_D6  LBG_CORE_QAT_EXT_D  I34

FM_CPU1_PROC_ID0   @BASEBOARD_FAB2_LIB.BASEBOARD_FAB2(SCH_1):FM_CPU1_PROC_ID0
  R8N4     2      B  RES         I158
  U2D1   CY71  PROC_ID<0>  SKX_EXT_B_BGA1  I172
  U8D7   M15  PR13B  LCMXO2_A_256BGA  I59

FM_CPU1_PROC_ID1   @BASEBOARD_FAB2_LIB.BASEBOARD_FAB2(SCH_1):FM_CPU1_PROC_ID1
  R8N1     2      B  RES         I157
  U2D1   DB71  PROC_ID<1>  SKX_EXT_B_BGA1  I172
  U8D7   M14  PR13A  LCMXO2_A_256BGA  I59

FM_CPU1_RC_EN   @BASEBOARD_FAB2_LIB.BASEBOARD_FAB2(SCH_1):FM_CPU1_RC_EN
  R2P22    2      B  RES         I360
  U7C1   BY29  GPP_C9  LBG_CORE_QAT_EXT_D  I115
  U8D7    P4   PB3A  LCMXO2_A_256BGA  I179

FM_CPU1_RC_ERROR_N   @BASEBOARD_FAB2_LIB.BASEBOARD_FAB2(SCH_1):FM_CPU1_RC_ERROR_N
  R2N29    2      B  RES         I352
  U2D1   Y23  RSVD<257>  SKX_EXT_B_BGA1  I169
  U7C1   AY52  GPP_E1_SATAXPCIE1_SATAGP1  LBG_CORE_QAT_EXT_D  I147
  U7C1   BV23  GPP_I6_RESET_DONE  LBG_CORE_QAT_EXT_D  I147
  U9F4    W2  GPIOM1_NDCD2_VPIB3  AST1250_BGA  I100

FM_CPU1_SKTOCC_LVT3_N   @BASEBOARD_FAB2_LIB.BASEBOARD_FAB2(SCH_1):FM_CPU1_SKTOCC_LVT3_N
  R6P39    2      B  RES         I181
  U1M4     1   OE_N  74CBTLV1G125  I127
  U1M7     6      S  NC7SB3157   I40
  U2D1   AB13  SKTOCC_N  SKX_EXT_B_BGA1  I172
  U7C1   H13  GPD1_ACPRESENT  LBG_CORE_QAT_EXT_D  I73
  U8D7   T12  PB22B  LCMXO2_A_256BGA  I179
  U9F4    A5  GPIOR7_MDIO1  AST1250_BGA   I1

FM_CPU1_SM_WP   @BASEBOARD_FAB2_LIB.BASEBOARD_FAB2(SCH_1):FM_CPU1_SM_WP
  R1C35    2      B  RES         I336
  R1C36    1      A  RES         I337
  U2D1   CV59  SM_WP  SKX_EXT_B_BGA1  I172

FM_CPU1_STL_BRD_OSC_EN   @BASEBOARD_FAB2_LIB.BASEBOARD_FAB2(SCH_1):FM_CPU1_STL_BRD_OSC_EN
  R7D36    2      B  RES         I96
  R7D38    2      B  RES         I97
  Y3F1     1  ENABLE_DISABLE  OSC_C_6P10  I72

FM_CPU1_THERMTRIP_LATCH_LVT3_N   @BASEBOARD_FAB2_LIB.BASEBOARD_FAB2(SCH_1):FM_CPU1_THERMTRIP_LATCH_LVT3_N
  U7C1   AV18  GPP_G6_FANTACH6_FANTACH6IE  LBG_CORE_QAT_EXT_D  I147
  U8D7    C5  PT10B  LCMXO2_A_256BGA  I59
  U9F4   H20  GPIOB6_LPCPME_N  AST1250_BGA  I347

FM_CPU1_THERMTRIP_LVT3_N   @BASEBOARD_FAB2_LIB.BASEBOARD_FAB2(SCH_1):FM_CPU1_THERMTRIP_LVT3_N
  R3P42    2      B  RES         I14
  U8D7   G14   PR5B  LCMXO2_A_256BGA  I59

FM_CPU1_THERMTRIP_LVT3_R_N   @BASEBOARD_FAB2_LIB.BASEBOARD_FAB2(SCH_1):FM_CPU1_THERMTRIP_LVT3_R_N
  R3P42    1      A  RES         I14
  U3P2     9     A3  GTL2014_SM   I1

FM_CPU1_VRM_322M_156M_OSC_EN   @BASEBOARD_FAB2_LIB.BASEBOARD_FAB2(SCH_1):FM_CPU1_VRM_322M_156M_OSC_EN
  J4B2    E1   IOE1  SCONN120_H61426002_SM  I46
  R7D37    2      B  RES         I98

FM_CPU1_VRM_OSC_EN   @BASEBOARD_FAB2_LIB.BASEBOARD_FAB2(SCH_1):FM_CPU1_VRM_OSC_EN
  R7D37    1      A  RES         I98
  R7D38    1      A  RES         I97
  U8D7   N14  PR14B  LCMXO2_A_256BGA  I59

FM_CPU_BMC_INIT   @BASEBOARD_FAB2_LIB.BASEBOARD_FAB2(SCH_1):FM_CPU_BMC_INIT
  R3D31    1      A  RES         I300
  R6D16    1      A  RES         I299
  U7C1   AD1  GPP_A17  LBG_CORE_QAT_EXT_D  I115
  U9F4   A14  GPIOG0_SGPSCK  AST1250_BGA  I347

FM_CPU_CATERR_DLY_LVT3_N   @BASEBOARD_FAB2_LIB.BASEBOARD_FAB2(SCH_1):FM_CPU_CATERR_DLY_LVT3_N
  R2N1     2      B  RES         I173
  U8D7    E2  PL2A_L_GPLLT_IN  LCMXO2_A_256BGA  I179

FM_CPU_CATERR_DLY_LVT3_R_N   @BASEBOARD_FAB2_LIB.BASEBOARD_FAB2(SCH_1):FM_CPU_CATERR_DLY_LVT3_R_N
  R2N1     1      A  RES         I173
  U7C1   CA37  GPP_C23  LBG_CORE_QAT_EXT_D  I115

FM_CPU_CATERR_LVT3_N   @BASEBOARD_FAB2_LIB.BASEBOARD_FAB2(SCH_1):FM_CPU_CATERR_LVT3_N
  R3P43    2      B  RES         I13
  U8D7   R14  PB25D  LCMXO2_A_256BGA  I179
  U9F4   B19  GPIOF1_NDCD4_SIOPBI_N  AST1250_BGA  I100

FM_CPU_CATERR_LVT3_R2_N   @BASEBOARD_FAB2_LIB.BASEBOARD_FAB2(SCH_1):FM_CPU_CATERR_LVT3_R2_N
  R3P43    1      A  RES         I13
  U3P2    10     A2  GTL2014_SM   I1

FM_CPU_ERR0_LVT3_BMC_N   @BASEBOARD_FAB2_LIB.BASEBOARD_FAB2(SCH_1):FM_CPU_ERR0_LVT3_BMC_N
  R8F38    2      B  RES         I119
  U9F4   A16  GPIOD6_SD2CD_N  AST1250_BGA  I100

FM_CPU_ERR0_LVT3_K_N   @BASEBOARD_FAB2_LIB.BASEBOARD_FAB2(SCH_1):FM_CPU_ERR0_LVT3_K_N
  R2T30    1      A  RES         I42
  R2T58    2      B  RES         I94
  R2T65    2      B  RES         I111

FM_CPU_ERR0_LVT3_N   @BASEBOARD_FAB2_LIB.BASEBOARD_FAB2(SCH_1):FM_CPU_ERR0_LVT3_N
  R2T30    2      B  RES         I42
  R8F37    1      A  RES         I131
  R8F38    1      A  RES         I119

FM_CPU_ERR0_LVT3_R_N   @BASEBOARD_FAB2_LIB.BASEBOARD_FAB2(SCH_1):FM_CPU_ERR0_LVT3_R_N
  R2T65    1      A  RES         I111
  U2T4     9     A3  GTL2014_SM  I30

FM_CPU_ERR0_PCH_N   @BASEBOARD_FAB2_LIB.BASEBOARD_FAB2(SCH_1):FM_CPU_ERR0_PCH_N
  R8F37    2      B  RES         I131
  U7C1   AE7  GPP_L18_TESTCH1_D7  LBG_CORE_QAT_EXT_D  I34

FM_CPU_ERR1_LVT3_BMC_N   @BASEBOARD_FAB2_LIB.BASEBOARD_FAB2(SCH_1):FM_CPU_ERR1_LVT3_BMC_N
  R2T64    2      B  RES         I121
  U9F4   E15  GPIOD7_SD2WP_N  AST1250_BGA  I100

FM_CPU_ERR1_LVT3_K_N   @BASEBOARD_FAB2_LIB.BASEBOARD_FAB2(SCH_1):FM_CPU_ERR1_LVT3_K_N
  R2T33    1      A  RES         I40
  R2T62    2      B  RES         I93
  R2T66    2      B  RES         I112

FM_CPU_ERR1_LVT3_N   @BASEBOARD_FAB2_LIB.BASEBOARD_FAB2(SCH_1):FM_CPU_ERR1_LVT3_N
  R2T33    2      B  RES         I40
  R2T63    1      A  RES         I133
  R2T64    1      A  RES         I121

FM_CPU_ERR1_LVT3_R_N   @BASEBOARD_FAB2_LIB.BASEBOARD_FAB2(SCH_1):FM_CPU_ERR1_LVT3_R_N
  R2T66    1      A  RES         I112
  U2T4    10     A2  GTL2014_SM  I30

FM_CPU_ERR1_PCH_N   @BASEBOARD_FAB2_LIB.BASEBOARD_FAB2(SCH_1):FM_CPU_ERR1_PCH_N
  R2T63    2      B  RES         I133
  U7C1   AG11  GPP_L19_TESTCH1_CLK  LBG_CORE_QAT_EXT_D  I34

FM_CPU_ERR2_LVT3_N   @BASEBOARD_FAB2_LIB.BASEBOARD_FAB2(SCH_1):FM_CPU_ERR2_LVT3_N
  R7D31    2      B  RES         I29
  U7C1   AV52  GPP_E4_SATA_DEVSLP0  LBG_CORE_QAT_EXT_D  I147
  U9F4   N21  ROMWE_N_GPIOS5  AST1250_BGA   I1

FM_CPU_ERR2_LVT3_R_N   @BASEBOARD_FAB2_LIB.BASEBOARD_FAB2(SCH_1):FM_CPU_ERR2_LVT3_R_N
  R7D31    1      A  RES         I29
  U7D2    10     A2  GTL2014_SM  I32

FM_CPU_MSMI_LVT3_N   @BASEBOARD_FAB2_LIB.BASEBOARD_FAB2(SCH_1):FM_CPU_MSMI_LVT3_N
  R7D25    2      B  RES         I70
  U7C1   AT52  GPP_E5_SATA_DEVSLP1  LBG_CORE_QAT_EXT_D  I147
  U8D7   T13  PB24B  LCMXO2_A_256BGA  I179
  U9F4   AB1  GPION3_PWM3_VPIG3  AST1250_BGA   I1

FM_CPU_MSMI_LVT3_R_N   @BASEBOARD_FAB2_LIB.BASEBOARD_FAB2(SCH_1):FM_CPU_MSMI_LVT3_R_N
  R7D25    1      A  RES         I70
  U7D2    13     A0  GTL2014_SM  I32

FM_CTNR_PS_ON   @BASEBOARD_FAB2_LIB.BASEBOARD_FAB2(SCH_1):FM_CTNR_PS_ON
  EU8B1    2     ON  SLG55021_SM  I13
  R8B4     1      A  RES         I83
  R8E5     2      B  RES         I218
  R8E12    2      B  RES         I78
  U1E2     1   A<0>  TTL1G08     I121
  U8D7    B3   PT9C  LCMXO2_A_256BGA  I59

FM_CTNR_PS_ON_R   @BASEBOARD_FAB2_LIB.BASEBOARD_FAB2(SCH_1):FM_CTNR_PS_ON_R
  R8E5     1      A  RES         I218
  U8E1     8   Y<0>  TTL08_QFN15  I243

FM_DB1200ZL_BCLKS_EN_N   @BASEBOARD_FAB2_LIB.BASEBOARD_FAB2(SCH_1):FM_DB1200ZL_BCLKS_EN_N
  EU4D2   19  OE_0_N  NB3W1200L_LCC   I1
  EU4D2   20  OE_1_N  NB3W1200L_LCC   I1
  EU4D2   28  OE_2_N  NB3W1200L_LCC   I1
  EU4D2   44  OE_6_N  NB3W1200L_LCC   I1
  EU4D2   45  OE_7_N  NB3W1200L_LCC   I1
  EU4D2   52  OE_8_N  NB3W1200L_LCC   I1
  R6P48    2      B  RES         I91
  U8D7   R11  PB22A  LCMXO2_A_256BGA  I179

FM_DB1200_PWRGD   @BASEBOARD_FAB2_LIB.BASEBOARD_FAB2(SCH_1):FM_DB1200_PWRGD
  EU4D2    6  PWRGD_PWRDN_N  NB3W1200L_LCC   I1
  U8D7   C15   PR1C  LCMXO2_A_256BGA  I59

FM_DB1200_SMB_SA0   @BASEBOARD_FAB2_LIB.BASEBOARD_FAB2(SCH_1):FM_DB1200_SMB_SA0
  EU4D2   11   SA_0  NB3W1200L_LCC   I1
  R4D35    2      B  RES         I38
  R6P21    1      A  RES         I80

FM_DB1200_SMB_SA1   @BASEBOARD_FAB2_LIB.BASEBOARD_FAB2(SCH_1):FM_DB1200_SMB_SA1
  EU4D2   14   SA_1  NB3W1200L_LCC   I1
  R4D38    2      B  RES         I37
  R6P20    1      A  RES         I81

FM_DB_PRESENT   @BASEBOARD_FAB2_LIB.BASEBOARD_FAB2(SCH_1):FM_DB_PRESENT
  Q1L3     3      C  NPN_SM       I8
  Q1L4     2  GATE<0>  FET_N_DUAL_SMLF  I19
  R1L36    2      B  RES         I11

FM_DB_UART_SEL0_N   @BASEBOARD_FAB2_LIB.BASEBOARD_FAB2(SCH_1):FM_DB_UART_SEL0_N
  CR1L1    2      A  DIODE_SM     I2
  R1L6     2      B  RES          I6

FM_DB_UART_SEL1_N   @BASEBOARD_FAB2_LIB.BASEBOARD_FAB2(SCH_1):FM_DB_UART_SEL1_N
  CR1L1    1      C  DIODE_SM     I2
  CR1L2    2      A  DIODE_SM     I3

FM_DB_UART_SEL2_N   @BASEBOARD_FAB2_LIB.BASEBOARD_FAB2(SCH_1):FM_DB_UART_SEL2_N
  CR1L2    1      C  DIODE_SM     I3
  CR1L3    2      A  DIODE_SM     I4

FM_DB_UART_SEL3_N   @BASEBOARD_FAB2_LIB.BASEBOARD_FAB2(SCH_1):FM_DB_UART_SEL3_N
  CR1L3    1      C  DIODE_SM     I4
  CR1L4    2      A  DIODE_SM     I5

FM_DB_UART_SEL4_N   @BASEBOARD_FAB2_LIB.BASEBOARD_FAB2(SCH_1):FM_DB_UART_SEL4_N
  CR1L4    1      C  DIODE_SM     I5
  Q1L3     1      B  NPN_SM       I8

FM_DEBUG_RST_BTN_N   @BASEBOARD_FAB2_LIB.BASEBOARD_FAB2(SCH_1):FM_DEBUG_RST_BTN_N
  J9A2    11   IO11  CONN14_H54902001_PIP  I171
  R1L19    2      B  RES         I24
  R1L22    1      A  RES         I22
  R1L29    2      B  RES         I68
  S9A1     1   PIN1  SWITCH_D37771002_SM  I78
  S9A1     2   PIN2  SWITCH_D37771002_SM  I78
  U8D7    G5   PL4C  LCMXO2_A_256BGA  I179

FM_DEBUG_RST_BTN_R1_N   @BASEBOARD_FAB2_LIB.BASEBOARD_FAB2(SCH_1):FM_DEBUG_RST_BTN_R1_N
  R1L28    2      B  RES         I66
  R1L29    1      A  RES         I68
  U1L4     4      Y  TTL1G07_A_SOP  I85

FM_DIMM_EVENT_COD_N   @BASEBOARD_FAB2_LIB.BASEBOARD_FAB2(SCH_1):FM_DIMM_EVENT_COD_N
  J1A1    78  EVENT_N  SCONN288_H44441004_PIP  I186
  J1A2    78  EVENT_N  SCONN288_H44441004_PIP  I111
  J1B1    78  EVENT_N  SCONN288_H44441004_PIP  I111
  J1G1    78  EVENT_N  SCONN288_H44441004_PIP  I111
  J1G2    78  EVENT_N  SCONN288_H44441004_PIP  I111
  J1G3    78  EVENT_N  SCONN288_H44441004_PIP  I186
  J4A1    78  EVENT_N  SCONN288_H44441004_PIP  I111
  J4A2    78  EVENT_N  SCONN288_H44441004_PIP  I111
  J4B1    78  EVENT_N  SCONN288_H44441004_PIP  I111
  J4G1    78  EVENT_N  SCONN288_H44441004_PIP   I1
  J4G2    78  EVENT_N  SCONN288_H44441004_PIP  I111
  J4G3    78  EVENT_N  SCONN288_H44441004_PIP  I111
  J6L1    78  EVENT_N  SCONN288_H44441003_PIP  I111
  J6L2    78  EVENT_N  SCONN288_H44441003_PIP  I12
  J6M1    78  EVENT_N  SCONN288_H44441003_PIP  I158
  J6T1    78  EVENT_N  SCONN288_H44441003_PIP  I13
  J6U1    78  EVENT_N  SCONN288_H44441003_PIP  I14
  J6U2    78  EVENT_N  SCONN288_H44441003_PIP  I111
  J9L1    78  EVENT_N  SCONN288_H44441003_PIP  I111
  J9L2    78  EVENT_N  SCONN288_H44441003_PIP  I12
  J9M1    78  EVENT_N  SCONN288_H44441003_PIP  I14
  J9T1    78  EVENT_N  SCONN288_H44441003_PIP  I13
  J9U1    78  EVENT_N  SCONN288_H44441003_PIP  I24
  J9U2    78  EVENT_N  SCONN288_H44441003_PIP  I187
  Q4U1     2  GATE<0>  FET_N_DUAL_SMLF  I98
  R4U2     2      B  RES         I100

FM_DIMM_EVENT_FET   @BASEBOARD_FAB2_LIB.BASEBOARD_FAB2(SCH_1):FM_DIMM_EVENT_FET
  Q4U1     5  GATE<0>  FET_N_DUAL_SMLF  I102
  Q4U1     6  DRAIN<0>  FET_N_DUAL_SMLF  I98
  R4U3     2      B  RES         I94
  R4U4     1      A  RES         I104

FM_DISABLE_FAN_N   @BASEBOARD_FAB2_LIB.BASEBOARD_FAB2(SCH_1):FM_DISABLE_FAN_N
  CR9P1    2      A  DIODE_SMLF  I214
  CR9P2    2      A  DIODE_SMLF  I213
  R9P5     2      B  RES         I215
  U1E2     2   B<0>  TTL1G08     I121

FM_DIS_ADR_DLY   @BASEBOARD_FAB2_LIB.BASEBOARD_FAB2(SCH_1):FM_DIS_ADR_DLY
  J8G2    10   IO10  CONN12_C73564003  I124
  R2P19    2      B  RES         I107
  U8D7    T3   PB6C  LCMXO2_A_256BGA  I179

FM_DUAL_BIOS_SEL_N   @BASEBOARD_FAB2_LIB.BASEBOARD_FAB2(SCH_1):FM_DUAL_BIOS_SEL_N
  Q8F1     3    DRN  FET_N       I126
  R2T11    2      B  RES         I105
  U2T3     1      A  TTL1G32_A   I99

FM_ENABLE_FAN_POWER   @BASEBOARD_FAB2_LIB.BASEBOARD_FAB2(SCH_1):FM_ENABLE_FAN_POWER
  EU9M1    2     ON  SLG55021_SM  I69
  J1F1    I3  GNDI3  CONN76_H22707001_THMT1  I111
  R1E11    2      B  RES         I120
  U1E2     4   Y<0>  TTL1G08     I121

FM_FAST_PROCHOT_AND_OUT_0_N   @BASEBOARD_FAB2_LIB.BASEBOARD_FAB2(SCH_1):FM_FAST_PROCHOT_AND_OUT_0_N
  U8E1     3   Y<0>  TTL08_QFN15  I10
  U8E1    12   A<0>  TTL08_QFN15  I12

FM_FAST_PROCHOT_AND_OUT_1_N   @BASEBOARD_FAB2_LIB.BASEBOARD_FAB2(SCH_1):FM_FAST_PROCHOT_AND_OUT_1_N
  U8E1     6   Y<0>  TTL08_QFN15  I11
  U8E1    13   B<0>  TTL08_QFN15  I12

FM_FAST_PROCHOT_EN   @BASEBOARD_FAB2_LIB.BASEBOARD_FAB2(SCH_1):FM_FAST_PROCHOT_EN
  Q8F2     3    DRN  FET_N       I67
  R9F3     2      B  RES         I65
  U1R2     1     OE  TTL1G126_A_SOT  I20

FM_FAST_PROCHOT_EN_N   @BASEBOARD_FAB2_LIB.BASEBOARD_FAB2(SCH_1):FM_FAST_PROCHOT_EN_N
  Q8F2     1   GATE  FET_N       I67
  R2T3     2      B  RES         I54
  U7C1   BH17  GPP_B21  LBG_CORE_QAT_EXT_D  I115
  U9F4   F18  GPIOB3_SALT4  AST1250_BGA  I347

FM_FAST_PROCHOT_THROTTLE_DLY_BU   @BASEBOARD_FAB2_LIB.BASEBOARD_FAB2(SCH_1):FM_FAST_PROCHOT_THROTTLE_DLY_BUF_N
  R1R5     2      B  RES         I73
  U1R1     2      A  TTL1G07_A_SOP  I46
  U1R2     4      Y  TTL1G126_A_SOT  I20

FM_FAST_PROCHOT_THROTTLE_DLY_N   @BASEBOARD_FAB2_LIB.BASEBOARD_FAB2(SCH_1):FM_FAST_PROCHOT_THROTTLE_DLY_N
  U1R2     2      A  TTL1G126_A_SOT  I20
  U8D7   J12   PR6D  LCMXO2_A_256BGA  I59

FM_FAST_PROCHOT_THROTTLE_IN_N   @BASEBOARD_FAB2_LIB.BASEBOARD_FAB2(SCH_1):FM_FAST_PROCHOT_THROTTLE_IN_N
  U8D7   G16   PR6A  LCMXO2_A_256BGA  I59
  U8E1    11   Y<0>  TTL08_QFN15  I12

FM_FLASH_ATTACH_CFG_STRAP   @BASEBOARD_FAB2_LIB.BASEBOARD_FAB2(SCH_1):FM_FLASH_ATTACH_CFG_STRAP
  R3P62    2      B  RES         I22
  R3P64    1      A  RES         I23
  U7C1   BB1  GPP_H12_SML2ALERT_N_IE_N  LBG_CORE_QAT_EXT_D  I147

FM_FLASH_DESC_OVERRIDE   @BASEBOARD_FAB2_LIB.BASEBOARD_FAB2(SCH_1):FM_FLASH_DESC_OVERRIDE
  R1T24    2      B  RES         I127
  R3N2     2      B  RES         I72
  U7C1   U24  HDA_SDO  LBG_CORE_QAT_EXT_D  I34

FM_FLASH_DESC_OVERRIDE_R   @BASEBOARD_FAB2_LIB.BASEBOARD_FAB2(SCH_1):FM_FLASH_DESC_OVERRIDE_R
  R1T24    1      A  RES         I127
  U9F4   U19  GPIOR3_ROMCS4_N  AST1250_BGA   I1

FM_FORCE_ADR_N   @BASEBOARD_FAB2_LIB.BASEBOARD_FAB2(SCH_1):FM_FORCE_ADR_N
  R2R7     2      B  RES         I172
  U7C1   AR13  GPP_F15_USB2_OC4_N  LBG_CORE_QAT_EXT_D  I147
  U8D7    D7  PT13D  LCMXO2_A_256BGA  I59
  U9F4    A3  GPIOA6_TIMER7_MDC2  AST1250_BGA   I1

FM_GBE0_LVC3_MOD_ABS   @BASEBOARD_FAB2_LIB.BASEBOARD_FAB2(SCH_1):FM_GBE0_LVC3_MOD_ABS
  J8E4    37   IO37  SCONN64_H87568002_A_SMT  I27
  U7C1   BV10  GPP_J16_LAN_SDP_P0_0  LBG_CORE_QAT_EXT_D  I147

FM_GBE1_LVC3_MOD_ABS   @BASEBOARD_FAB2_LIB.BASEBOARD_FAB2(SCH_1):FM_GBE1_LVC3_MOD_ABS
  J8E4    38   IO38  SCONN64_H87568002_A_SMT  I27
  U7C1   BY10  GPP_J18_LAN_SDP_P1_0  LBG_CORE_QAT_EXT_D  I147

FM_GBE2_LVC3_MOD_ABS   @BASEBOARD_FAB2_LIB.BASEBOARD_FAB2(SCH_1):FM_GBE2_LVC3_MOD_ABS
  J8E4    31   IO31  SCONN64_H87568002_A_SMT  I27
  U7C1   BW13  GPP_J20_LAN_SDP_P2_0  LBG_CORE_QAT_EXT_D  I147

FM_GBE3_LVC3_MOD_ABS   @BASEBOARD_FAB2_LIB.BASEBOARD_FAB2(SCH_1):FM_GBE3_LVC3_MOD_ABS
  J8E4    32   IO32  SCONN64_H87568002_A_SMT  I27
  U7C1   BY12  GPP_J22_LAN_SDP_P3_0  LBG_CORE_QAT_EXT_D  I147

FM_GBE_LOM_DISABLE_N   @BASEBOARD_FAB2_LIB.BASEBOARD_FAB2(SCH_1):FM_GBE_LOM_DISABLE_N
  R2N6     2      B  RES         I128
  R8C23    1      A  RES         I125
  R8C24    1      A  RES         I120
  U7C1   A13  GPD11_GBEPHY  LBG_CORE_QAT_EXT_D  I73

FM_GLOBAL_RST_WARN_N   @BASEBOARD_FAB2_LIB.BASEBOARD_FAB2(SCH_1):FM_GLOBAL_RST_WARN_N
  U7C1   BL18  GPP_B12_GLB_RST_WARN_N  LBG_CORE_QAT_EXT_D  I115
  U8D7    P1  PL13D  LCMXO2_A_256BGA  I179

FM_HBW_BYPASS_LOWBW_N   @BASEBOARD_FAB2_LIB.BASEBOARD_FAB2(SCH_1):FM_HBW_BYPASS_LOWBW_N
  EU4D2    5  HBW_BYPASS_LOBW_N  NB3W1200L_LCC   I1
  R4D41    2      B  RES         I53
  R6P22    1      A  RES         I47

FM_HEARTBEAT_LED   @BASEBOARD_FAB2_LIB.BASEBOARD_FAB2(SCH_1):FM_HEARTBEAT_LED
  Q9E1     5  GATE<0>  FET_N_DUAL_SMLF  I55
  Q9E1     6  DRAIN<0>  FET_N_DUAL_SMLF  I135
  R9E21    2      B  RES         I137

FM_HEARTBEAT_LED_A   @BASEBOARD_FAB2_LIB.BASEBOARD_FAB2(SCH_1):FM_HEARTBEAT_LED_A
  DS9E1    1      A  LED_A1LF    I56
  R9E24    1      A  RES         I57

FM_HEARTBEAT_LED_K   @BASEBOARD_FAB2_LIB.BASEBOARD_FAB2(SCH_1):FM_HEARTBEAT_LED_K
  DS9E1    2      C  LED_A1LF    I56
  Q9E1     3  DRAIN<0>  FET_N_DUAL_SMLF  I55

FM_HSC_TIMER_EXP_N   @BASEBOARD_FAB2_LIB.BASEBOARD_FAB2(SCH_1):FM_HSC_TIMER_EXP_N
  R9P20    2      B  RES         I86
  U7C1   AK9  GPP_F1_SATAXPCIE4_SATAGP4  LBG_CORE_QAT_EXT_D  I147
  U8E1     5   B<0>  TTL08_QFN15  I11
  U9F4    U3  GPIOL2_NDSR1_VPIODD  AST1250_BGA  I100
  U9P2     1   OUTB  TPS3700_SM  I200

FM_IE_DISABLE_N   @BASEBOARD_FAB2_LIB.BASEBOARD_FAB2(SCH_1):FM_IE_DISABLE_N
  J8G2     4    IO4  CONN12_C73564003  I124
  R8D21    2      B  RES         I120
  U7C1   AU13  GPP_F16_USB2_OC5_N  LBG_CORE_QAT_EXT_D  I147
  U8D7    L9  PB12D  LCMXO2_A_256BGA  I179

FM_INTRUDER_HDR_PCH_N   @BASEBOARD_FAB2_LIB.BASEBOARD_FAB2(SCH_1):FM_INTRUDER_HDR_PCH_N
  R3N10    2      B  RES         I37
  U7C1   AG18  INTRUDER_N  LBG_CORE_QAT_EXT_D  I34

FM_JTAG_PLD_EN_DEBUG   @BASEBOARD_FAB2_LIB.BASEBOARD_FAB2(SCH_1):FM_JTAG_PLD_EN_DEBUG
  R3R11    1      A  RES         I45
  R3R15    2      B  RES         I44
  U8D7   C10  PT20C_JTAGENB  LCMXO2_A_256BGA  I59

FM_M2_DET_LVC3   @BASEBOARD_FAB2_LIB.BASEBOARD_FAB2(SCH_1):FM_M2_DET_LVC3
  R2P14    1      A  RES         I115
  R2P16    2      B  RES         I113
  U2P1     4      Y  TTL1G07_A_SOP  I110

FM_M2_SSD_PEDET   @BASEBOARD_FAB2_LIB.BASEBOARD_FAB2(SCH_1):FM_M2_SSD_PEDET
  J8F1    69  PEDET  SCONN75K_H17033002_SMT1  I53
  R2P15    2      B  RES         I111
  U2P1     2      A  TTL1G07_A_SOP  I110

FM_MATED_IN_D1_N   @BASEBOARD_FAB2_LIB.BASEBOARD_FAB2(SCH_1):FM_MATED_IN_D1_N
  CR1F3    2      A  DIODE_SM    I180
  CR1F4    1      C  DIODE_SM    I178

FM_MATED_IN_D2_N   @BASEBOARD_FAB2_LIB.BASEBOARD_FAB2(SCH_1):FM_MATED_IN_D2_N
  CR1F3    1      C  DIODE_SM    I180
  Q9T1     1      B  NPN_SM      I181

FM_MATED_IN_N   @BASEBOARD_FAB2_LIB.BASEBOARD_FAB2(SCH_1):FM_MATED_IN_N
  CR1F4    2      A  DIODE_SM    I178
  J1F1    E4   IOE4  CONN76_H22707001_THMT1  I111
  J1F3     4    IO4  CONN8_H62179001_PIP  I189
  R9T8     1      A  RES         I249
  R9T9     2      B  RES         I177

FM_MB_SLOT_ID0   @BASEBOARD_FAB2_LIB.BASEBOARD_FAB2(SCH_1):FM_MB_SLOT_ID0
  J1F1    F5  GNDF5  CONN76_H22707001_THMT1  I111
  R7D5     2      B  RES         I199
  U7C1    T4  GPP_A13_SUSWARN_N_SUSPWRDNACK  LBG_CORE_QAT_EXT_D  I115
  U9F4   V20  GPIOR0_ROMCS1_N  AST1250_BGA   I1

FM_MB_SLOT_ID1   @BASEBOARD_FAB2_LIB.BASEBOARD_FAB2(SCH_1):FM_MB_SLOT_ID1
  J1F1    G5   IOG5  CONN76_H22707001_THMT1  I111
  R7D9     2      B  RES         I200
  U7C1   AB3  GPP_A14_ESPI_RESET_N  LBG_CORE_QAT_EXT_D  I115
  U9F4   W21  GPIOR1_ROMCS2_N  AST1250_BGA   I1

FM_MB_SLOT_ID2   @BASEBOARD_FAB2_LIB.BASEBOARD_FAB2(SCH_1):FM_MB_SLOT_ID2
  J1F1    H5   IOH5  CONN76_H22707001_THMT1  I111
  R3P61    2      B  RES         I201
  U7C1   AC4  GPP_A15_SUSACK_N  LBG_CORE_QAT_EXT_D  I115
  U9F4   Y22  GPIOR2_ROMCS3_N  AST1250_BGA   I1

FM_MEM_EVENT_FUNC   @BASEBOARD_FAB2_LIB.BASEBOARD_FAB2(SCH_1):FM_MEM_EVENT_FUNC
  R7E19    2      B  RES         I57
  R7E20    1      A  RES         I59
  U8D7    D2   PL2D  LCMXO2_A_256BGA  I179

FM_MEM_THERM_EVENT_LVT3_N   @BASEBOARD_FAB2_LIB.BASEBOARD_FAB2(SCH_1):FM_MEM_THERM_EVENT_LVT3_N
  Q4U1     3  DRAIN<0>  FET_N_DUAL_SMLF  I102
  R4U1     2      B  RES         I91
  R8E11    1      A  RES         I279
  U8D7   K13  PR11C  LCMXO2_A_256BGA  I59

FM_MEM_THERM_EVENT_PCH_N   @BASEBOARD_FAB2_LIB.BASEBOARD_FAB2(SCH_1):FM_MEM_THERM_EVENT_PCH_N
  U7C1   AL15  GPP_F18_USB2_OC7_N  LBG_CORE_QAT_EXT_D  I147
  U8D7   K12  PR11D  LCMXO2_A_256BGA  I59
  U9F4    U4  GPIOL4_NDTR1_VPIVS  AST1250_BGA  I100

FM_MEZZA_PRSNT1_N   @BASEBOARD_FAB2_LIB.BASEBOARD_FAB2(SCH_1):FM_MEZZA_PRSNT1_N
  J9B3     1    IO1  SCONN120_A28699018_SM  I336
  R9B7     2      B  RES         I222

FM_MEZZ_PRSNTB1_N   @BASEBOARD_FAB2_LIB.BASEBOARD_FAB2(SCH_1):FM_MEZZ_PRSNTB1_N
  J8E3     1    IO1  SCONN80_E67482007_SM  I119
  R2R8     1      A  RES         I18

FM_ME_RECOVER_N   @BASEBOARD_FAB2_LIB.BASEBOARD_FAB2(SCH_1):FM_ME_RECOVER_N
  J7G3     3    IO3  CONN12_C73564003  I174
  R7G26    2      B  RES         I101
  U7C1    V3  GPP_A19  LBG_CORE_QAT_EXT_D  I115

FM_MODPRST_HFI0_CPU0_LVT2_N   @BASEBOARD_FAB2_LIB.BASEBOARD_FAB2(SCH_1):FM_MODPRST_HFI0_CPU0_LVT2_N
  J8B1     3    IO3  SCONN24_H46321001_SM   I1
  R8B3     2      B  RES         I24
  U5D1   BR20  CD_HFI0_MODPRST_N  SKX_EXT_B_BGA1  I61

FM_MODPRST_HFI1_CPU0_LVT2_N   @BASEBOARD_FAB2_LIB.BASEBOARD_FAB2(SCH_1):FM_MODPRST_HFI1_CPU0_LVT2_N
  J8B1    11   IO11  SCONN24_H46321001_SM   I1
  R8B19    2      B  RES         I21
  U5D1   BT19  CD_HFI1_MODPRST_N  SKX_EXT_B_BGA1  I61

FM_MP_PS_FAIL_N   @BASEBOARD_FAB2_LIB.BASEBOARD_FAB2(SCH_1):FM_MP_PS_FAIL_N
  J1F3     3    IO3  CONN8_H62179001_PIP  I189
  R3N12    2      B  RES         I342
  U7C1   AK20  GPP_F2_SATAXPCIE5_SATAGP5  LBG_CORE_QAT_EXT_D  I147
  U8D7    H4   PL6C  LCMXO2_A_256BGA  I179
  U9F4    W6  GPIOO4_TACH4_VPIR2  AST1250_BGA   I1

FM_MP_PS_REDUNDANT_LOST_N   @BASEBOARD_FAB2_LIB.BASEBOARD_FAB2(SCH_1):FM_MP_PS_REDUNDANT_LOST_N
  J1F3     2    IO2  CONN8_H62179001_PIP  I189
  R3N11    2      B  RES         I344
  U7C1   AK13  GPP_F3_SATAXPCIE6_SATAGP6  LBG_CORE_QAT_EXT_D  I147
  U9F4   AA5  GPIOO5_TACH5_VPIR3  AST1250_BGA   I1

FM_NMI_EVENT_N   @BASEBOARD_FAB2_LIB.BASEBOARD_FAB2(SCH_1):FM_NMI_EVENT_N
  R2N25    1      A  RES         I302
  U7C1   BE7  GPP_G18_NMI_N  LBG_CORE_QAT_EXT_D  I147

FM_OC0_USB_N    @BASEBOARD_FAB2_LIB.BASEBOARD_FAB2(SCH_1):FM_OC0_USB_N
  R1M24    2      B  RES         I105
  U1M3     3   OC_N  TPS2061_SM  I100
  U7C1   BL48  GPP_E9_USB2_OC0_N  LBG_CORE_QAT_EXT_D  I147

FM_OCP_MEZZA_PRES_N   @BASEBOARD_FAB2_LIB.BASEBOARD_FAB2(SCH_1):FM_OCP_MEZZA_PRES_N
  J9B3   120  IO120  SCONN120_A28699018_SM  I336
  R7D12    2      B  RES         I237
  U7C1   AE2  GPP_A21  LBG_CORE_QAT_EXT_D  I115

FM_OCP_MEZZB_PRES_N   @BASEBOARD_FAB2_LIB.BASEBOARD_FAB2(SCH_1):FM_OCP_MEZZB_PRES_N
  J8E3    80   IO80  SCONN80_E67482007_SM  I119
  R7D44    2      B  RES         I356
  U7C1   AD9  GPP_L8_TESTCH0_D6  LBG_CORE_QAT_EXT_D  I34

FM_OCP_MEZZC_PRES_N   @BASEBOARD_FAB2_LIB.BASEBOARD_FAB2(SCH_1):FM_OCP_MEZZC_PRES_N
  J8E4    64   IO64  SCONN64_H87568002_A_SMT  I27
  R3P53    2      B  RES         I357
  U7C1   AD17  GPP_L9_TESTCH0_D7  LBG_CORE_QAT_EXT_D  I34

FM_OC_DETECT_EN   @BASEBOARD_FAB2_LIB.BASEBOARD_FAB2(SCH_1):FM_OC_DETECT_EN
  Q1D2     3    DRN  FET_N       I203
  R1D21    2      B  RES         I204
  U1D1     1     OE  TTL1G126_A_SOT  I103

FM_OC_DETECT_EN_N   @BASEBOARD_FAB2_LIB.BASEBOARD_FAB2(SCH_1):FM_OC_DETECT_EN_N
  Q1D2     1   GATE  FET_N       I203
  R1D35    2      B  RES         I12
  R7D19    1      A  RES          I6
  U7C1   BC4  GPP_H18_SML4ALERT_N_IE_N  LBG_CORE_QAT_EXT_D  I147
  U9F4    V4  GPIOM3_NRI2_VPIB5  AST1250_BGA  I100

FM_OC_DETECT_N   @BASEBOARD_FAB2_LIB.BASEBOARD_FAB2(SCH_1):FM_OC_DETECT_N
  R1D22    2      B  RES         I158
  U1D1     4      Y  TTL1G126_A_SOT  I103
  U8E1     2   B<0>  TTL08_QFN15  I10

FM_P12V_HOTSWAP0_EN   @BASEBOARD_FAB2_LIB.BASEBOARD_FAB2(SCH_1):FM_P12V_HOTSWAP0_EN
  C1D11    1      A  CAP_A       I53
  EU1D2   12  ENABLE  ADM1278_SM  I10
  Q9T1     3      C  NPN_SM      I181
  R9T3     1      A  RES         I185
  R9T6     2      B  RES         I183

FM_P12V_HSC_ADR1   @BASEBOARD_FAB2_LIB.BASEBOARD_FAB2(SCH_1):FM_P12V_HSC_ADR1
  EU1D2    7   ADR1  ADM1278_SM  I10
  R1D29    2      B  RES         I37
  R9P17    1      A  RES         I33

FM_P12V_HSC_ADR2   @BASEBOARD_FAB2_LIB.BASEBOARD_FAB2(SCH_1):FM_P12V_HSC_ADR2
  EU1D2    8   ADR2  ADM1278_SM  I10
  R1D27    2      B  RES         I38
  R9P16    1      A  RES         I36

FM_P12V_MAIN_SW_EN   @BASEBOARD_FAB2_LIB.BASEBOARD_FAB2(SCH_1):FM_P12V_MAIN_SW_EN
  EU7E1    2     ON  SLG55021_SM  I19
  U8D7   R16  PR14D  LCMXO2_A_256BGA  I59

FM_P1V8MCP_CPU0_EN   @BASEBOARD_FAB2_LIB.BASEBOARD_FAB2(SCH_1):FM_P1V8MCP_CPU0_EN
  J6B1   A15  IOA15  SCONN120_H61426002_SM  I56
  U8D7   E16   PR3A  LCMXO2_A_256BGA  I59

FM_P1V8MCP_CPU1_EN   @BASEBOARD_FAB2_LIB.BASEBOARD_FAB2(SCH_1):FM_P1V8MCP_CPU1_EN
  J4B2   A15  IOA15  SCONN120_H61426002_SM  I46
  U8D7   F12   PR4C  LCMXO2_A_256BGA  I59

FM_P3V3_CPLD_EN   @BASEBOARD_FAB2_LIB.BASEBOARD_FAB2(SCH_1):FM_P3V3_CPLD_EN
  EU2T1    2     ON  SLG55021_SM   I1
  U8D7    A4  PT10A  LCMXO2_A_256BGA  I59

FM_PASSWORD_CLEAR_N   @BASEBOARD_FAB2_LIB.BASEBOARD_FAB2(SCH_1):FM_PASSWORD_CLEAR_N
  J7G3     9    IO9  CONN12_C73564003  I174
  R2N28    2      B  RES         I147
  U7C1   BW32  GPP_C8  LBG_CORE_QAT_EXT_D  I115

FM_PCH_BMC_THERMTRIP_EXI_STRAP_   @BASEBOARD_FAB2_LIB.BASEBOARD_FAB2(SCH_1):FM_PCH_BMC_THERMTRIP_EXI_STRAP_N
  Q8D2     2    SRC  FET_N        I4
  R2N10    2      B  RES         I10
  U7C1   BM20  GPP_B23_MEIE_SML1ALRT_N_PHOT_N  LBG_CORE_QAT_EXT_D  I115

FM_PCH_BMC_THERMTRIP_N   @BASEBOARD_FAB2_LIB.BASEBOARD_FAB2(SCH_1):FM_PCH_BMC_THERMTRIP_N
  Q8D2     3    DRN  FET_N        I4
  R2P17    2      B  RES          I3
  U7C1   BH2  GPP_H22_SSATAXPCIE4_SSATAGP4  LBG_CORE_QAT_EXT_D  I147
  U9F4   D18  GPIOF0_NCTS4  AST1250_BGA  I100

FM_PCH_LVC1_THERMTRIP_N   @BASEBOARD_FAB2_LIB.BASEBOARD_FAB2(SCH_1):FM_PCH_LVC1_THERMTRIP_N
  Q7D1     3    DRN  FET_N       I10
  R7C21    2      B  RES          I9
  U7C1   V15  THRMTRIP_N  LBG_CORE_QAT_EXT_D  I73

FM_PCH_PLD_DATA   @BASEBOARD_FAB2_LIB.BASEBOARD_FAB2(SCH_1):FM_PCH_PLD_DATA
  R2M3     2      B  RES         I172
  R2R5     2      B  RES         I258
  U8D7    C2   PL1D  LCMXO2_A_256BGA  I179

FM_PCH_PLD_DATA_R   @BASEBOARD_FAB2_LIB.BASEBOARD_FAB2(SCH_1):FM_PCH_PLD_DATA_R
  R2M3     1      A  RES         I172
  U7C1   BM42  GPP_D4  LBG_CORE_QAT_EXT_D  I115

FM_PCH_PRSNT_N   @BASEBOARD_FAB2_LIB.BASEBOARD_FAB2(SCH_1):FM_PCH_PRSNT_N
  R7B6     2      B  RES         I295
  U7C1   C70  CGC_DUT_DETECT_N  LBG_CORE_QAT_EXT_D  I34
  U8D7    A3  PT11C  LCMXO2_A_256BGA  I59

FM_PCH_PWRBTN_N   @BASEBOARD_FAB2_LIB.BASEBOARD_FAB2(SCH_1):FM_PCH_PWRBTN_N
  R2T28    2      B  RES         I289
  U7C1   C15  GPD3_PWRBTN_N  LBG_CORE_QAT_EXT_D  I73
  U8D7   B12  PT23B  LCMXO2_A_256BGA  I59

FM_PCH_PWRBTN_OUT_N   @BASEBOARD_FAB2_LIB.BASEBOARD_FAB2(SCH_1):FM_PCH_PWRBTN_OUT_N
  R8G2     2      B  RES         I267
  U7C1   BG15  GPP_B17  LBG_CORE_QAT_EXT_D  I115
  U8G1     3     2A  TTL2G07_SOT23LF  I269

FM_PCH_PWRBTN_R_N   @BASEBOARD_FAB2_LIB.BASEBOARD_FAB2(SCH_1):FM_PCH_PWRBTN_R_N
  R2T28    1      A  RES         I289
  R8F26    2      B  RES         I211
  U8F3     4     2Y  TTL2G07_SOT23LF  I201
  U8G1     4     2Y  TTL2G07_SOT23LF  I269

FM_PCH_SATA_RAID_KEY   @BASEBOARD_FAB2_LIB.BASEBOARD_FAB2(SCH_1):FM_PCH_SATA_RAID_KEY
  R9A13    2      B  RES         I118
  U7C1   BV31  GPP_C10  LBG_CORE_QAT_EXT_D  I115

FM_PCH_SATA_RAID_KEY_R   @BASEBOARD_FAB2_LIB.BASEBOARD_FAB2(SCH_1):FM_PCH_SATA_RAID_KEY_R
  J9A1     4    IO4  CONN4_D42317002_PIP  I131
  R9A12    1      A  RES         I117
  R9A13    1      A  RES         I118

FM_PE_BMC_WAKE_N   @BASEBOARD_FAB2_LIB.BASEBOARD_FAB2(SCH_1):FM_PE_BMC_WAKE_N
  R8E29    1      A  RES         I18
  R9F46    1      A  RES         I218
  U9F4   J22  NC_PEWAKE_N  AST1250_BGA  I100

FM_PE_M2_WAKE_N   @BASEBOARD_FAB2_LIB.BASEBOARD_FAB2(SCH_1):FM_PE_M2_WAKE_N
  J8F1    54  PEWAKE_N_NC  SCONN75K_H17033002_SMT1  I53
  R8E27    1      A  RES         I32

FM_PE_OCP_WAKE_N   @BASEBOARD_FAB2_LIB.BASEBOARD_FAB2(SCH_1):FM_PE_OCP_WAKE_N
  J9B3    34   IO34  SCONN120_A28699018_SM  I336
  R8E26    1      A  RES         I30

FM_PE_SLOTX24_WAKE_N   @BASEBOARD_FAB2_LIB.BASEBOARD_FAB2(SCH_1):FM_PE_SLOTX24_WAKE_N
  J8G1    28   IO28  SCONN200_H68296001_SM  I258
  R8E28    1      A  RES         I31
  R8E36    2      B  RES         I28

FM_PE_SPRV_WAKE_N   @BASEBOARD_FAB2_LIB.BASEBOARD_FAB2(SCH_1):FM_PE_SPRV_WAKE_N
  EU9E1   16  PE_WAKE_N  SPRINGVILLE_SM1  I72
  R8E21    1      A  RES         I33

FM_PI7C9X1172_A0   @BASEBOARD_FAB2_LIB.BASEBOARD_FAB2(SCH_1):FM_PI7C9X1172_A0
  EU9F3   30  A0_CS_N  PI7C9X1172_QFN   I1
  R9F49    2      B  RES         I14
  R9F51    1      A  RES         I12

FM_PI7C9X1172_A1   @BASEBOARD_FAB2_LIB.BASEBOARD_FAB2(SCH_1):FM_PI7C9X1172_A1
  EU9F3   31  A1_S1  PI7C9X1172_QFN   I1
  R9F48    2      B  RES         I13
  R9F50    1      A  RES         I11

FM_PLD_DEBUG_MODE_N   @BASEBOARD_FAB2_LIB.BASEBOARD_FAB2(SCH_1):FM_PLD_DEBUG_MODE_N
  R2R3     2      B  RES         I41
  U8D7    F7  PT16A  LCMXO2_A_256BGA  I59

FM_PMBUS_ALERT_BUF_EN   @BASEBOARD_FAB2_LIB.BASEBOARD_FAB2(SCH_1):FM_PMBUS_ALERT_BUF_EN
  Q2P1     3    DRN  FET_N       I58
  R2P5     2      B  RES         I56
  U8D5     1     OE  TTL1G126_A_SOT  I38

FM_PMBUS_ALERT_BUF_EN_N   @BASEBOARD_FAB2_LIB.BASEBOARD_FAB2(SCH_1):FM_PMBUS_ALERT_BUF_EN_N
  Q2P1     1   GATE  FET_N       I58
  R2P11    1      A  RES         I63
  R2P13    2      B  RES         I61
  U7C1   BK9  GPP_B11  LBG_CORE_QAT_EXT_D  I115
  U7C1   BY35  GPP_C18  LBG_CORE_QAT_EXT_D  I115
  U9F4    V2  GPIOL5_NRTS1_VPICLK  AST1250_BGA  I100

FM_POST_CARD_PRES_BMC_N   @BASEBOARD_FAB2_LIB.BASEBOARD_FAB2(SCH_1):FM_POST_CARD_PRES_BMC_N
  Q1L4     6  DRAIN<0>  FET_N_DUAL_SMLF  I19
  R1L38    2      B  RES         I22
  U7C1   BG52  GPP_E2_SATAXPCIE2_SATAGP2  LBG_CORE_QAT_EXT_D  I147
  U7C1    W4  GPP_A20  LBG_CORE_QAT_EXT_D  I115
  U9F4   H18  GPIOB2_SALT3  AST1250_BGA  I347

FM_PRSNT_2_1_N   @BASEBOARD_FAB2_LIB.BASEBOARD_FAB2(SCH_1):FM_PRSNT_2_1_N
  J8G1    27   IO27  SCONN200_H68296001_SM  I258
  R3P7     2      B  RES         I315
  U7C1   AE18  GPP_L2_TESTCH0_D0  LBG_CORE_QAT_EXT_D  I34

FM_PRSNT_2_2_N   @BASEBOARD_FAB2_LIB.BASEBOARD_FAB2(SCH_1):FM_PRSNT_2_2_N
  J8G1    30   IO30  SCONN200_H68296001_SM  I258
  R3P5     2      B  RES         I316
  U7C1   AE15  GPP_L3_TESTCH0_D1  LBG_CORE_QAT_EXT_D  I34

FM_PRSNT_2_3_N   @BASEBOARD_FAB2_LIB.BASEBOARD_FAB2(SCH_1):FM_PRSNT_2_3_N
  J8G1    32   IO32  SCONN200_H68296001_SM  I258
  R3P6     2      B  RES         I317
  U7C1   AE11  GPP_L4_TESTCH0_D2  LBG_CORE_QAT_EXT_D  I34

FM_PRSNT_2_4_N   @BASEBOARD_FAB2_LIB.BASEBOARD_FAB2(SCH_1):FM_PRSNT_2_4_N
  J8G1    63   IO63  SCONN200_H68296001_SM  I258
  R3N15    2      B  RES         I318
  U7C1   Y18  GPP_L5_TESTCH0_D3  LBG_CORE_QAT_EXT_D  I34

FM_PRSNT_2_5_N   @BASEBOARD_FAB2_LIB.BASEBOARD_FAB2(SCH_1):FM_PRSNT_2_5_N
  J8G1    66   IO66  SCONN200_H68296001_SM  I258
  R3N16    2      B  RES         I321
  U7C1   AA20  GPP_L6_TESTCH0_D4  LBG_CORE_QAT_EXT_D  I34

FM_PRSNT_2_6_N   @BASEBOARD_FAB2_LIB.BASEBOARD_FAB2(SCH_1):FM_PRSNT_2_6_N
  J8G1   199  IO199  SCONN200_H68296001_SM  I243
  R3P8     2      B  RES         I322
  U7C1   AA17  GPP_L7_TESTCH0_D5  LBG_CORE_QAT_EXT_D  I34

FM_PS_EN        @BASEBOARD_FAB2_LIB.BASEBOARD_FAB2(SCH_1):FM_PS_EN
  C2R6     1      A  CAP         I224
  U8D7    F9  PT19C  LCMXO2_A_256BGA  I59
  U8E1     9   A<0>  TTL08_QFN15  I243

FM_PVCCIN_CPU0_PWR_IN_ALERT_N   @BASEBOARD_FAB2_LIB.BASEBOARD_FAB2(SCH_1):FM_PVCCIN_CPU0_PWR_IN_ALERT_N
  EU4D4   14  PINALRT_N  PXE1610B_QFN  I155
  R4E4     2      B  RES         I19
  U7E2     1   A<0>  TTL1G08     I117

FM_PVCCIN_CPU1_PWR_IN_ALERT_N   @BASEBOARD_FAB2_LIB.BASEBOARD_FAB2(SCH_1):FM_PVCCIN_CPU1_PWR_IN_ALERT_N
  EU1C2   14  PINALRT_N  PXE1610B_QFN  I130
  R1D7     2      B  RES          I7
  U7E3     1   A<0>  TTL1G08     I118

FM_PVCCIN_PVCCSA_CPU0_EN_LVC1   @BASEBOARD_FAB2_LIB.BASEBOARD_FAB2(SCH_1):FM_PVCCIN_PVCCSA_CPU0_EN_LVC1
  R6P18    1      A  RES         I131
  U8D7   A10  PT19B  LCMXO2_A_256BGA  I59

FM_PVCCIN_PVCCSA_CPU1_EN_LVC1   @BASEBOARD_FAB2_LIB.BASEBOARD_FAB2(SCH_1):FM_PVCCIN_PVCCSA_CPU1_EN_LVC1
  R9N16    1      A  RES         I119
  U8D7   N16  PR14A  LCMXO2_A_256BGA  I59

FM_PVCCIOMCP_CPU0_EN   @BASEBOARD_FAB2_LIB.BASEBOARD_FAB2(SCH_1):FM_PVCCIOMCP_CPU0_EN
  J6B1   A16  IOA16  SCONN120_H61426002_SM  I56
  U8D7    K1   PL9B  LCMXO2_A_256BGA  I179

FM_PVCCIOMCP_CPU1_EN   @BASEBOARD_FAB2_LIB.BASEBOARD_FAB2(SCH_1):FM_PVCCIOMCP_CPU1_EN
  J4B2   A16  IOA16  SCONN120_H61426002_SM  I46
  U8D7    P7   PB9B  LCMXO2_A_256BGA  I179

FM_PVCCIO_CPU0_EN   @BASEBOARD_FAB2_LIB.BASEBOARD_FAB2(SCH_1):FM_PVCCIO_CPU0_EN
  R3P26    1      A  RES         I87
  U8D7    M7   PB9C  LCMXO2_A_256BGA  I179

FM_PVCCIO_CPU1_EN   @BASEBOARD_FAB2_LIB.BASEBOARD_FAB2(SCH_1):FM_PVCCIO_CPU1_EN
  R6P41    1      A  RES         I90
  U8D7    T7  PB11A_PCLKT2_0  LCMXO2_A_256BGA  I179

FM_PVCCMCP_CPU0_EN   @BASEBOARD_FAB2_LIB.BASEBOARD_FAB2(SCH_1):FM_PVCCMCP_CPU0_EN
  J6B1   C20  IOC20  SCONN120_H61426002_SM  I56
  U8D7    H2   PL6B  LCMXO2_A_256BGA  I179

FM_PVCCMCP_CPU1_EN   @BASEBOARD_FAB2_LIB.BASEBOARD_FAB2(SCH_1):FM_PVCCMCP_CPU1_EN
  J4B2   C20  IOC20  SCONN120_H61426002_SM  I46
  U8D7    M8  PB16C  LCMXO2_A_256BGA  I179

FM_PVDDQ_ABC_EN   @BASEBOARD_FAB2_LIB.BASEBOARD_FAB2(SCH_1):FM_PVDDQ_ABC_EN
  R7F21    1      A  RES         I343
  U8D7   K14  PR10A  LCMXO2_A_256BGA  I59

FM_PVDDQ_DEF_EN   @BASEBOARD_FAB2_LIB.BASEBOARD_FAB2(SCH_1):FM_PVDDQ_DEF_EN
  R3M6     1      A  RES         I59
  U8D7   K15  PR10B  LCMXO2_A_256BGA  I59

FM_PVDDQ_GHJ_EN   @BASEBOARD_FAB2_LIB.BASEBOARD_FAB2(SCH_1):FM_PVDDQ_GHJ_EN
  R9U7     1      A  RES         I84
  U8D7   H13   PR6C  LCMXO2_A_256BGA  I59

FM_PVDDQ_KLM_EN   @BASEBOARD_FAB2_LIB.BASEBOARD_FAB2(SCH_1):FM_PVDDQ_KLM_EN
  R9M9     1      A  RES         I84
  U8D7   H15   PR6B  LCMXO2_A_256BGA  I59

FM_PVPP_CPU0_EN   @BASEBOARD_FAB2_LIB.BASEBOARD_FAB2(SCH_1):FM_PVPP_CPU0_EN
  C7B9     1      A  CAP         I185
  C7F8     1      A  CAP         I140
  R7B9     1      A  RES         I307
  R7F9     1      A  RES         I220
  R7F14    1      A  RES         I136
  U8D7   P15  PR14C  LCMXO2_A_256BGA  I59

FM_PVPP_CPU1_EN   @BASEBOARD_FAB2_LIB.BASEBOARD_FAB2(SCH_1):FM_PVPP_CPU1_EN
  C4B5     1      A  CAP         I129
  C4G7     1      A  CAP         I183
  R4B1     1      A  RES         I220
  R4G4     1      A  RES         I275
  R4G5     1      A  RES         I182
  U8D7   P16  PR13D  LCMXO2_A_256BGA  I59

FM_PVPP_PVDDQ_CPU0_EN_ABC   @BASEBOARD_FAB2_LIB.BASEBOARD_FAB2(SCH_1):FM_PVPP_PVDDQ_CPU0_EN_ABC
  EU7F1   40     EN  NCP3232L_SM  I193
  R7F9     2      B  RES         I220

FM_PVPP_PVDDQ_CPU0_EN_DEF   @BASEBOARD_FAB2_LIB.BASEBOARD_FAB2(SCH_1):FM_PVPP_PVDDQ_CPU0_EN_DEF
  EU7B1   40     EN  NCP3232L_SM  I214
  R7B9     2      B  RES         I307

FM_PVPP_PVDDQ_CPU1_EN_GHJ   @BASEBOARD_FAB2_LIB.BASEBOARD_FAB2(SCH_1):FM_PVPP_PVDDQ_CPU1_EN_GHJ
  EU4G1   40     EN  NCP3232L_SM  I225
  R4G4     2      B  RES         I275

FM_PVPP_PVDDQ_CPU1_EN_KLM   @BASEBOARD_FAB2_LIB.BASEBOARD_FAB2(SCH_1):FM_PVPP_PVDDQ_CPU1_EN_KLM
  EU4A3   40     EN  NCP3232L_SM  I184
  R4B1     2      B  RES         I220

FM_PVTT_ABC_EN_R   @BASEBOARD_FAB2_LIB.BASEBOARD_FAB2(SCH_1):FM_PVTT_ABC_EN_R
  C4G23    1      A  CAP         I39
  EU4G3    7     EN  MIC5166_DFN   I1
  R4G23    2      B  RES         I38
  R6U15    2      B  RES         I37

FM_PVTT_DEF_EN_R   @BASEBOARD_FAB2_LIB.BASEBOARD_FAB2(SCH_1):FM_PVTT_DEF_EN_R
  C4A2     1      A  CAP         I40
  EU4A1    7     EN  MIC5166_DFN  I31
  R4A2     2      B  RES         I38
  R6L4     2      B  RES         I37

FM_PVTT_GHJ_EN_R   @BASEBOARD_FAB2_LIB.BASEBOARD_FAB2(SCH_1):FM_PVTT_GHJ_EN_R
  C4G12    1      A  CAP         I36
  EU4G2    7     EN  MIC5166_DFN  I24
  R4G16    2      B  RES         I35
  R6U3     2      B  RES         I34

FM_PVTT_KLM_EN_R   @BASEBOARD_FAB2_LIB.BASEBOARD_FAB2(SCH_1):FM_PVTT_KLM_EN_R
  C4A6     1      A  CAP         I39
  EU4A2    7     EN  MIC5166_DFN  I31
  R4A3     2      B  RES         I38
  R6L5     2      B  RES         I37

FM_PWRBRK_N     @BASEBOARD_FAB2_LIB.BASEBOARD_FAB2(SCH_1):FM_PWRBRK_N
  Q7E8     3    DRN  FET_N       I119
  R7E21    2      B  RES         I343
  R7E22    1      A  RES         I341

FM_PWRBRK_SLOT_N   @BASEBOARD_FAB2_LIB.BASEBOARD_FAB2(SCH_1):FM_PWRBRK_SLOT_N
  J8G1    20   IO20  SCONN200_H68296001_SM  I258
  R2U50    2      B  RES         I215
  R7E22    2      B  RES         I341

FM_PWR_BTN_N    @BASEBOARD_FAB2_LIB.BASEBOARD_FAB2(SCH_1):FM_PWR_BTN_N
  R1L26    2      B  RES         I13
  U7C1   BH20  GPP_B9_SRCCLKREQ4_N  LBG_CORE_QAT_EXT_D  I115
  U8D7    G6   PL3D  LCMXO2_A_256BGA  I179
  U9F4   B17  GPIOD2_SD2DAT0  AST1250_BGA  I100

FM_PWR_BTN_R_N   @BASEBOARD_FAB2_LIB.BASEBOARD_FAB2(SCH_1):FM_PWR_BTN_R_N
  R1L26    1      A  RES         I13
  U9A4     4   Y<0>  TTL2G14     I10

FM_PWR_LED      @BASEBOARD_FAB2_LIB.BASEBOARD_FAB2(SCH_1):FM_PWR_LED
  Q9A2     5  GATE<0>  FET_N_DUAL_SMLF  I180
  Q9A2     6  DRAIN<0>  FET_N_DUAL_SMLF  I175
  R9A18    2      B  RES         I183

FM_PWR_LED_A    @BASEBOARD_FAB2_LIB.BASEBOARD_FAB2(SCH_1):FM_PWR_LED_A
  DS9A5    1      A  LED_A1LF    I179
  R9A20    1      A  RES         I178

FM_PWR_LED_K    @BASEBOARD_FAB2_LIB.BASEBOARD_FAB2(SCH_1):FM_PWR_LED_K
  DS9A5    2      C  LED_A1LF    I179
  Q9A2     3  DRAIN<0>  FET_N_DUAL_SMLF  I180

FM_PWR_LED_N    @BASEBOARD_FAB2_LIB.BASEBOARD_FAB2(SCH_1):FM_PWR_LED_N
  Q9A2     2  GATE<0>  FET_N_DUAL_SMLF  I175
  R9A21    2      B  RES         I186
  U7C1   BK46  GPP_D1  LBG_CORE_QAT_EXT_D  I115

FM_QAT_EN_N     @BASEBOARD_FAB2_LIB.BASEBOARD_FAB2(SCH_1):FM_QAT_EN_N
  R2N23    2      B  RES         I112
  R2N24    1      A  RES         I113
  U7C1   BR9  GPP_B3_CPU_GP2  LBG_CORE_QAT_EXT_D  I115

FM_RED_LED_ANODE   @BASEBOARD_FAB2_LIB.BASEBOARD_FAB2(SCH_1):FM_RED_LED_ANODE
  DS9F1    1      A  LED_A1      I71
  R9F28    2      B  RES         I72

FM_RED_LED_CATHODE   @BASEBOARD_FAB2_LIB.BASEBOARD_FAB2(SCH_1):FM_RED_LED_CATHODE
  DS9F1    2      C  LED_A1      I71
  Q9F1     3  DRAIN<0>  FET_N_DUAL_SMLF  I79

FM_ROMA<0>      @BASEBOARD_FAB2_LIB.BASEBOARD_FAB2(SCH_1):FM_ROMA<0>
  J9G1     3    IO3  CONN12_C73564003  I128
  R9E15    1      A  RES         I114
  U9F4   R20  ROMA<0>  AST1250_BGA   I1

FM_ROMA<1>      @BASEBOARD_FAB2_LIB.BASEBOARD_FAB2(SCH_1):FM_ROMA<1>
  R9F40    1      A  RES         I65
  U9F4   R21  ROMA<1>  AST1250_BGA   I1

FM_ROMA<2>      @BASEBOARD_FAB2_LIB.BASEBOARD_FAB2(SCH_1):FM_ROMA<2>
  R9F39    1      A  RES         I64
  U9F4   R22  ROMA2_GPIOZ0_VPOB0  AST1250_BGA   I1

FM_ROMA<3>      @BASEBOARD_FAB2_LIB.BASEBOARD_FAB2(SCH_1):FM_ROMA<3>
  R9F19    1      A  RES         I63
  U9F4   P18  ROMA3_GPIOZ1_VPOB1  AST1250_BGA   I1

FM_ROMA<4>      @BASEBOARD_FAB2_LIB.BASEBOARD_FAB2(SCH_1):FM_ROMA<4>
  R9F18    1      A  RES         I62
  U9F4   P19  ROMA4_GPIOZ2_VPOB2  AST1250_BGA   I1

FM_ROMA<5>      @BASEBOARD_FAB2_LIB.BASEBOARD_FAB2(SCH_1):FM_ROMA<5>
  R1T16    1      A  RES         I61
  U9F4   P20  ROMA5_GPIOZ3_VPOB3  AST1250_BGA   I1

FM_ROMA<6>      @BASEBOARD_FAB2_LIB.BASEBOARD_FAB2(SCH_1):FM_ROMA<6>
  R9F10    1      A  RES         I60
  U9F4   P21  ROMA6_GPIOZ4_VPOB4  AST1250_BGA   I1

FM_ROMA<7>      @BASEBOARD_FAB2_LIB.BASEBOARD_FAB2(SCH_1):FM_ROMA<7>
  R9F38    1      A  RES         I59
  U9F4   P22  ROMA7_GPIOZ5_VPOB5  AST1250_BGA   I1

FM_ROMA<8>      @BASEBOARD_FAB2_LIB.BASEBOARD_FAB2(SCH_1):FM_ROMA<8>
  R9F15    1      A  RES         I111
  U9F4   M19  ROMA8_GPIOZ6_VPOB6  AST1250_BGA   I1

FM_ROMA<9>      @BASEBOARD_FAB2_LIB.BASEBOARD_FAB2(SCH_1):FM_ROMA<9>
  R1T19    1      A  RES         I57
  U9F4   M20  ROMA9_GPIOZ7_VPOB7  AST1250_BGA   I1

FM_ROMA<10>     @BASEBOARD_FAB2_LIB.BASEBOARD_FAB2(SCH_1):FM_ROMA<10>
  R9F16    1      A  RES         I56
  U9F4   M21  ROMA10_GPIOAA0_VPOG0  AST1250_BGA   I1

FM_ROMA<11>     @BASEBOARD_FAB2_LIB.BASEBOARD_FAB2(SCH_1):FM_ROMA<11>
  R9F37    1      A  RES         I55
  U9F4   M22  ROMA11_GPIOAA1_VPOG1  AST1250_BGA   I1

FM_ROMA<12>     @BASEBOARD_FAB2_LIB.BASEBOARD_FAB2(SCH_1):FM_ROMA<12>
  R1T14    1      A  RES         I54
  U9F4   L18  ROMA12_GPIOAA2_VPOG2  AST1250_BGA   I1

FM_ROMA<13>     @BASEBOARD_FAB2_LIB.BASEBOARD_FAB2(SCH_1):FM_ROMA<13>
  R1T21    1      A  RES         I53
  U9F4   L19  ROMA13_GPIOAA3_VPOG3  AST1250_BGA   I1

FM_ROMA<14>     @BASEBOARD_FAB2_LIB.BASEBOARD_FAB2(SCH_1):FM_ROMA<14>
  R9F9     1      A  RES         I52
  U9F4   L20  ROMA14_GPIOAA4_VPOG4  AST1250_BGA   I1

FM_ROMA<15>     @BASEBOARD_FAB2_LIB.BASEBOARD_FAB2(SCH_1):FM_ROMA<15>
  R9F35    1      A  RES         I51
  U9F4   L21  ROMA15_GPIOAA5_VPOG5  AST1250_BGA   I1

FM_ROMA<16>     @BASEBOARD_FAB2_LIB.BASEBOARD_FAB2(SCH_1):FM_ROMA<16>
  R1T22    1      A  RES         I50
  U9F4   T18  ROMA16_GPIOAA6_VPOG6  AST1250_BGA   I1

FM_ROMA<17>     @BASEBOARD_FAB2_LIB.BASEBOARD_FAB2(SCH_1):FM_ROMA<17>
  R1T20    1      A  RES         I49
  U9F4   N18  ROMA17_GPIOAA7_VPOG7  AST1250_BGA   I1

FM_ROMA<18>     @BASEBOARD_FAB2_LIB.BASEBOARD_FAB2(SCH_1):FM_ROMA<18>
  R1T18    1      A  RES         I48
  U9F4   N19  ROMA18_GPIOAB0_VPOR0  AST1250_BGA   I1

FM_ROMA<19>     @BASEBOARD_FAB2_LIB.BASEBOARD_FAB2(SCH_1):FM_ROMA<19>
  R9F14    1      A  RES         I47
  U9F4   M18  ROMA19_GPIOAB1_VPOR1  AST1250_BGA   I1

FM_ROMA<20>     @BASEBOARD_FAB2_LIB.BASEBOARD_FAB2(SCH_1):FM_ROMA<20>
  R9F17    1      A  RES         I46
  U9F4   N22  ROMA20_GPIOAB2_VPOR2  AST1250_BGA   I1

FM_ROMA<21>     @BASEBOARD_FAB2_LIB.BASEBOARD_FAB2(SCH_1):FM_ROMA<21>
  R1T17    1      A  RES         I112
  U9F4   N20  ROMA21_GPIOAB3_VPOR3  AST1250_BGA   I1

FM_ROMA<22>     @BASEBOARD_FAB2_LIB.BASEBOARD_FAB2(SCH_1):FM_ROMA<22>
  R9F36    1      A  RES         I44
  U9F4   L22  ROMA22_GPIOS6_VPOR4  AST1250_BGA   I1

FM_ROMA<23>     @BASEBOARD_FAB2_LIB.BASEBOARD_FAB2(SCH_1):FM_ROMA<23>
  R1T13    1      A  RES         I43
  U9F4   K18  ROMA23_GPIOS7_VPOR5  AST1250_BGA   I1

FM_SINT_PRSNT_N   @BASEBOARD_FAB2_LIB.BASEBOARD_FAB2(SCH_1):FM_SINT_PRSNT_N
  R7C5     2      B  RES         I297
  U7C1   C18  RSVD<11>  LBG_CORE_QAT_EXT_D  I34
  U8D7   B14  PT24A  LCMXO2_A_256BGA  I59

FM_SLPS3_N      @BASEBOARD_FAB2_LIB.BASEBOARD_FAB2(SCH_1):FM_SLPS3_N
  U7C1   D14  GPD4_SLP_S3_N  LBG_CORE_QAT_EXT_D  I73
  U8D7    G1   PL6A  LCMXO2_A_256BGA  I179
  U9F4   D13  GPIOG2_SGPSI0  AST1250_BGA  I347

FM_SLPS4_N      @BASEBOARD_FAB2_LIB.BASEBOARD_FAB2(SCH_1):FM_SLPS4_N
  U7C1   B16  GPD5_SLP_S4_N  LBG_CORE_QAT_EXT_D  I73
  U8D7   C12  PT23A  LCMXO2_A_256BGA  I59
  U9F4   C13  GPIOG3_SGPSI1  AST1250_BGA  I347

FM_SLP_SUS_N    @BASEBOARD_FAB2_LIB.BASEBOARD_FAB2(SCH_1):FM_SLP_SUS_N
  U7C1    P7  SLP_SUS_N  LBG_CORE_QAT_EXT_D  I73
  U8D7    E9  PT17D  LCMXO2_A_256BGA  I59

FM_SLT_CFG0     @BASEBOARD_FAB2_LIB.BASEBOARD_FAB2(SCH_1):FM_SLT_CFG0
  J8G1    19   IO19  SCONN200_H68296001_SM  I258
  R8C7     2      B  RES         I327
  U7C1   CA32  GPP_C15  LBG_CORE_QAT_EXT_D  I115

FM_SLT_CFG1     @BASEBOARD_FAB2_LIB.BASEBOARD_FAB2(SCH_1):FM_SLT_CFG1
  J8G1    18   IO18  SCONN200_H68296001_SM  I258
  R8C1     2      B  RES         I326
  U7C1   BW37  GPP_C16  LBG_CORE_QAT_EXT_D  I115

FM_SLT_CFG2_R   @BASEBOARD_FAB2_LIB.BASEBOARD_FAB2(SCH_1):FM_SLT_CFG2_R
  R2U48    2      B  RES         I213
  R2U50    1      A  RES         I215
  U7C1   BY31  GPP_C17  LBG_CORE_QAT_EXT_D  I115

FM_SOL_UART_CH_SEL   @BASEBOARD_FAB2_LIB.BASEBOARD_FAB2(SCH_1):FM_SOL_UART_CH_SEL
  Q1L1     3      C  NPN_SM       I9
  R1L5     2      B  RES         I10
  U7C1   BG7  GPP_G21_SSATA_DEVSLP1  LBG_CORE_QAT_EXT_D  I147
  U8D7   L10  PB18D  LCMXO2_A_256BGA  I179
  U9F4   R18  ROMOE_N_GPIOS4  AST1250_BGA   I1

FM_SPEAKER_PCH_N   @BASEBOARD_FAB2_LIB.BASEBOARD_FAB2(SCH_1):FM_SPEAKER_PCH_N
  DS9A3    1      C  LED_1NCLF   I67
  Q9A3     3    DRN  FET_N       I49

FM_SSATA_PCIE_M2_SEL   @BASEBOARD_FAB2_LIB.BASEBOARD_FAB2(SCH_1):FM_SSATA_PCIE_M2_SEL
  R2P14    2      B  RES         I115
  U7C1   BH4  GPP_H23_SSATAXPCIE5_SSATAGP5  LBG_CORE_QAT_EXT_D  I147

FM_SYS_THROTTLE_LVC3   @BASEBOARD_FAB2_LIB.BASEBOARD_FAB2(SCH_1):FM_SYS_THROTTLE_LVC3
  Q2U1     2  GATE<0>  FET_N_DUAL_SMLF  I28
  Q2U1     5  GATE<0>  FET_N_DUAL_SMLF  I113
  Q4B2     2  GATE<0>  FET_N_DUAL_SMLF  I32
  Q4B2     5  GATE<0>  FET_N_DUAL_SMLF  I33
  Q7E3     2  GATE<0>  FET_N_DUAL_SMLF  I52
  Q7E3     5  GATE<0>  FET_N_DUAL_SMLF  I51
  Q7E4     3    DRN  FET_N       I104
  Q7E8     1   GATE  FET_N       I119
  R7E7     2      B  RES         I106

FM_THERMTRIP_DLY   @BASEBOARD_FAB2_LIB.BASEBOARD_FAB2(SCH_1):FM_THERMTRIP_DLY
  R7D18    1      A  RES         I11
  U8D7   L15  PR12A  LCMXO2_A_256BGA  I59

FM_THERMTRIP_DLY_R   @BASEBOARD_FAB2_LIB.BASEBOARD_FAB2(SCH_1):FM_THERMTRIP_DLY_R
  Q7D1     1   GATE  FET_N       I10
  R7D18    2      B  RES         I11

FM_THROTTLE_N   @BASEBOARD_FAB2_LIB.BASEBOARD_FAB2(SCH_1):FM_THROTTLE_N
  R1R8     2      B  RES         I51
  R7E9     1      A  RES         I108
  R8B31    2      B  RES         I307
  U7C1   AY15  GPP_G7_FANTACH7_FANTACH7IE  LBG_CORE_QAT_EXT_D  I147
  U7C1   CA39  GPP_C20  LBG_CORE_QAT_EXT_D  I115
  U9F4   V21  GPIOR4_ROMA24_VPOR6  AST1250_BGA   I1

FM_THROTTLE_R1_N   @BASEBOARD_FAB2_LIB.BASEBOARD_FAB2(SCH_1):FM_THROTTLE_R1_N
  R1R8     1      A  RES         I51
  U1R1     4      Y  TTL1G07_A_SOP  I46

FM_THROTTLE_R_N   @BASEBOARD_FAB2_LIB.BASEBOARD_FAB2(SCH_1):FM_THROTTLE_R_N
  Q7E4     1   GATE  FET_N       I104
  R7E9     2      B  RES         I108

FM_TPM_PRES_N   @BASEBOARD_FAB2_LIB.BASEBOARD_FAB2(SCH_1):FM_TPM_PRES_N
  J8E1     8    IO8  SCONN11_H67026001_SM  I87
  R8E3     2      B  RES         I355
  U7C1   AE4  GPP_A22  LBG_CORE_QAT_EXT_D  I115

FM_UARTSW_LSB_N   @BASEBOARD_FAB2_LIB.BASEBOARD_FAB2(SCH_1):FM_UARTSW_LSB_N
  DS9A4    2      C  LED_A1LF    I130
  U7C1   AT4  GPP_H0_SRCCLKREQ6_N  LBG_CORE_QAT_EXT_D  I147
  U8D7    R9  PB18A  LCMXO2_A_256BGA  I179
  U9F1     6     S1  FSA3357_SM  I75
  U9F2     6     S1  FSA3357_SM  I74
  U9F4   AA3  GPION6_PWM6_VPIG6  AST1250_BGA   I1

FM_UARTSW_LSB_R_N   @BASEBOARD_FAB2_LIB.BASEBOARD_FAB2(SCH_1):FM_UARTSW_LSB_R_N
  DS9A4    1      A  LED_A1LF    I130
  R1L43    1      A  RES         I131

FM_UARTSW_MSB_N   @BASEBOARD_FAB2_LIB.BASEBOARD_FAB2(SCH_1):FM_UARTSW_MSB_N
  DS9A7    2      C  LED_A1LF    I134
  U7C1   BA13  GPP_G23_SSATAXPCIE0_SSATAGP0  LBG_CORE_QAT_EXT_D  I147
  U8D7   P11  PB21B  LCMXO2_A_256BGA  I179
  U9F1     5     S2  FSA3357_SM  I75
  U9F2     5     S2  FSA3357_SM  I74
  U9F4   AB2  GPION7_PWM7_VPIG7  AST1250_BGA   I1

FM_UARTSW_MSB_R_N   @BASEBOARD_FAB2_LIB.BASEBOARD_FAB2(SCH_1):FM_UARTSW_MSB_R_N
  DS9A7    1      A  LED_A1LF    I134
  R1L44    1      A  RES         I136

FM_UART_ALERT_N   @BASEBOARD_FAB2_LIB.BASEBOARD_FAB2(SCH_1):FM_UART_ALERT_N
  EU9F3   20  IRQ_N  PI7C9X1172_QFN   I1
  R9F55    2      B  RES         I30
  U7C1   BK13  GPP_B15  LBG_CORE_QAT_EXT_D  I115
  U8D7    P2  PL14D  LCMXO2_A_256BGA  I179

FM_UART_PRES_N   @BASEBOARD_FAB2_LIB.BASEBOARD_FAB2(SCH_1):FM_UART_PRES_N
  J9G1     9    IO9  CONN12_C73564003  I128
  R7C13    2      B  RES         I67
  U7C1    T2  GPP_A16_CLKOUT_LPC2  LBG_CORE_QAT_EXT_D  I115

FM_UART_SEL_N   @BASEBOARD_FAB2_LIB.BASEBOARD_FAB2(SCH_1):FM_UART_SEL_N
  Q1L1     1      B  NPN_SM       I9
  R1L4     2      B  RES          I7

FM_UART_SWITCH_N   @BASEBOARD_FAB2_LIB.BASEBOARD_FAB2(SCH_1):FM_UART_SWITCH_N
  J9A2    12   IO12  CONN14_H54902001_PIP  I171
  R1L4     1      A  RES          I7
  R1L6     1      A  RES          I6
  R9A5     2      B  RES         I136

FM_USB_P0_EN_BOOT_BIOS_STRAP_N   @BASEBOARD_FAB2_LIB.BASEBOARD_FAB2(SCH_1):FM_USB_P0_EN_BOOT_BIOS_STRAP_N
  R1M25    1      A  RES         I111
  R2N14    2      B  RES         I83
  U1M3     4   EN_N  TPS2061_SM  I100
  U7C1   BR17  GPP_B22  LBG_CORE_QAT_EXT_D  I115

FM_UV_ADR_TRIGGER_EN   @BASEBOARD_FAB2_LIB.BASEBOARD_FAB2(SCH_1):FM_UV_ADR_TRIGGER_EN
  R2U30    2      B  RES         I76
  U7C1   BL15  GPP_B18  LBG_CORE_QAT_EXT_D  I115
  U8D7   H12   PR5D  LCMXO2_A_256BGA  I59
  U9F4    D5  GPIOA7_TIMER8_MDIO2  AST1250_BGA   I1

FM_UV_ADR_TRIGGER_N   @BASEBOARD_FAB2_LIB.BASEBOARD_FAB2(SCH_1):FM_UV_ADR_TRIGGER_N
  CR9P2    1      C  DIODE_SMLF  I213
  R9P6     2      B  RES         I149
  U8D7   G15   PR5A  LCMXO2_A_256BGA  I59
  U9P1     6   OUTA  TPS3700_SM  I163

FM_WBG_PRSNT_N   @BASEBOARD_FAB2_LIB.BASEBOARD_FAB2(SCH_1):FM_WBG_PRSNT_N
  R7C8     2      B  RES         I296
  U7C1    D8  RSVD<10>  LBG_CORE_QAT_EXT_D  I34
  U8D7   G11   PR5C  LCMXO2_A_256BGA  I59

FM_XRC_PRESENT_N   @BASEBOARD_FAB2_LIB.BASEBOARD_FAB2(SCH_1):FM_XRC_PRESENT_N
  J1C1    G5   IOG5  CONN76_H22707001_THMT1  I18
  R8B23    2      B  RES         I280
  U7C1   BW48  GPP_D17  LBG_CORE_QAT_EXT_D  I115
  U9F4   AB4  GPIOO6_TACH6_VPIR4  AST1250_BGA   I1

FM_XRC_READY_N   @BASEBOARD_FAB2_LIB.BASEBOARD_FAB2(SCH_1):FM_XRC_READY_N
  J1C1    H5   IOH5  CONN76_H22707001_THMT1  I18
  R1C31    1      A  RES         I110
  R8B30    2      B  RES         I282
  U7C1   CA41  GPP_D18  LBG_CORE_QAT_EXT_D  I115
  U9F4    V7  GPIOO7_TACH7_VPIR5  AST1250_BGA   I1

FP_ID_LED_P5V_STBY_N   @BASEBOARD_FAB2_LIB.BASEBOARD_FAB2(SCH_1):FP_ID_LED_P5V_STBY_N
  DS9A1    1      C  LED_1NC     I50
  U1L2     4      Y  TTL1G86_SOTLF  I57

FP_ID_LED_XOR_R   @BASEBOARD_FAB2_LIB.BASEBOARD_FAB2(SCH_1):FP_ID_LED_XOR_R
  DS9A1    2      A  LED_1NC     I50
  R1L8     2      B  RES         I58

FP_LED_HDD_ACTIVITY_AND_N   @BASEBOARD_FAB2_LIB.BASEBOARD_FAB2(SCH_1):FP_LED_HDD_ACTIVITY_AND_N
  DS9A2    1      C  LED_1NCLF   I42
  U1M1     4   Y<0>  TTL1G08     I70

FP_LED_HDD_ACTIVITY_AND_R_N   @BASEBOARD_FAB2_LIB.BASEBOARD_FAB2(SCH_1):FP_LED_HDD_ACTIVITY_AND_R_N
  DS9A2    2      A  LED_1NCLF   I42
  R1L21    2      B  RES         I43

FP_NMI_BTN      @BASEBOARD_FAB2_LIB.BASEBOARD_FAB2(SCH_1):FP_NMI_BTN
  U2R1     1   A<0>  TTL2G14     I357
  U2R1     4   Y<0>  TTL2G14     I356

FP_NMI_BTN_N    @BASEBOARD_FAB2_LIB.BASEBOARD_FAB2(SCH_1):FP_NMI_BTN_N
  R2R10    2      B  RES         I358
  R8F24    2      B  RES         I316
  U7C1   BN11  GPP_B8_SRCCLKREQ3_N  LBG_CORE_QAT_EXT_D  I115
  U9F4   A18  GPIOD0_SD2CLK  AST1250_BGA  I100

FP_NMI_BTN_OUT_N   @BASEBOARD_FAB2_LIB.BASEBOARD_FAB2(SCH_1):FP_NMI_BTN_OUT_N
  C2R12    1      A  CAP_A       I353
  R2R9     2      B  RES         I352
  U2R1     3   A<0>  TTL2G14     I356

FP_NMI_BTN_OUT_R_N   @BASEBOARD_FAB2_LIB.BASEBOARD_FAB2(SCH_1):FP_NMI_BTN_OUT_R_N
  R2R9     1      A  RES         I352
  R8E32    2      B  RES         I385
  S8E1     2      B  SWITCH_D90553001_SMLF  I351

FP_NMI_BTN_R_N   @BASEBOARD_FAB2_LIB.BASEBOARD_FAB2(SCH_1):FP_NMI_BTN_R_N
  R2R10    1      A  RES         I358
  U2R1     6   Y<0>  TTL2G14     I357

FP_PWR_BTN_BUF1_N   @BASEBOARD_FAB2_LIB.BASEBOARD_FAB2(SCH_1):FP_PWR_BTN_BUF1_N
  U9A4     3   A<0>  TTL2G14     I10
  U9A4     6   Y<0>  TTL2G14      I9

FP_PWR_BTN_R1_N   @BASEBOARD_FAB2_LIB.BASEBOARD_FAB2(SCH_1):FP_PWR_BTN_R1_N
  C1L18    1      A  CAP_A       I11
  R1L31    2      B  RES          I4
  U9A4     1   A<0>  TTL2G14      I9

FP_PWR_BTN_R_N   @BASEBOARD_FAB2_LIB.BASEBOARD_FAB2(SCH_1):FP_PWR_BTN_R_N
  R1L27    2      B  RES          I5
  R1L31    1      A  RES          I4
  S9A2     1    IO1  SW_H67881001_SM  I84
  S9A2     2    IO2  SW_H67881001_SM  I84

FP_PWR_ID_LED_N   @BASEBOARD_FAB2_LIB.BASEBOARD_FAB2(SCH_1):FP_PWR_ID_LED_N
  R8D14    2      B  RES         I301
  U1L2     2      B  TTL1G86_SOTLF  I57
  U7C1   BD3  GPP_H19_SSATAXPCIE1_SSATAGP1  LBG_CORE_QAT_EXT_D  I147
  U9F4    H3  GPIOQ5_SDA14  AST1250_BGA  I100

FP_RST_BTN_BUF1_N   @BASEBOARD_FAB2_LIB.BASEBOARD_FAB2(SCH_1):FP_RST_BTN_BUF1_N
  U9A3     3   A<0>  TTL2G14     I15
  U9A3     6   Y<0>  TTL2G14     I18

FP_RST_BTN_R_N   @BASEBOARD_FAB2_LIB.BASEBOARD_FAB2(SCH_1):FP_RST_BTN_R_N
  C1L10    1      A  CAP_A       I19
  R1L22    2      B  RES         I22
  U9A3     1   A<0>  TTL2G14     I18

GND             @BASEBOARD_FAB2_LIB.BASEBOARD_FAB2(SCH_1):GND
  C1A1     2      B  CAP         I68
  C1A2     2      B  CAP_A       I53
  C1A4     2      B  CAP         I79
  C1A5     2      B  CAP_A       I178
  C1A6     2      B  CAP_0402    I77
  C1A9     2      B  CAP_0402    I79
  C1A10    2      B  CAP_A       I51
  C1A11    2      B  CAP_A       I73
  C1A12    2      B  CAP          I6
  C1A13    2      B  CAP_0402    I72
  C1A16    2      B  CAP         I85
  C1A17    2      B  CAP_A       I182
  C1A19    2      B  CAP_0402    I48
  C1A20    2      B  CAP_A       I78
  C1B2     2      B  CAP_A       I44
  C1B3     2      B  CAP_A       I41
  C1B4     2      B  CAP         I80
  C1B5     2      B  CAP_A       I27
  C1B6     2      B  CAP_A       I25
  C1B7     2      B  CAP         I82
  C1B8     2      B  CAP         I59
  C1B9     2      B  CAP_A       I176
  C1B10    2      B  CAPP        I175
  C1B11    2      B  CAP         I36
  C1B14    2      B  CAPP        I84
  C1B15    2      B  CAP_A       I68
  C1B16    2      B  CAP_A       I30
  C1B17    2      B  CAP_A       I128
  C1B18    2      B  CAP         I61
  C1B19    2      B  CAP_A       I64
  C1B20    2      B  CAP_0402    I50
  C1B21    2      B  CAP_0402    I54
  C1C1     2      B  CAPP        I35
  C1C2     2      B  CAPP        I38
  C1C3     2      B  CAP_A       I23
  C1C4     2      B  CAP_0402    I22
  C1C5     2      B  CAP_0402    I26
  C1C7     2      B  CAP_A       I41
  C1C8     2      B  CAP         I73
  C1C9     2      B  CAP_A       I42
  C1C10    2      B  CAP         I69
  C1C11    2      B  CAP         I71
  C1C13    2      B  CAP_A       I29
  C1C14    2      B  CAP_A       I31
  C1C15    2      B  CAP_0402    I28
  C1C17    2      B  CAP_A       I27
  C1C18    2      B  CAP_A       I21
  C1C19    2      B  CAP_A        I8
  C1C23    2      B  CAP         I114
  C1C25    2      B  CAP_A       I17
  C1C26    2      B  CAP_0402    I16
  C1D3     2      B  CAP_A       I22
  C1D5     2      B  CAP_A       I47
  C1D6     2      B  CAP_0402    I46
  C1D7     2      B  CAP_0402    I50
  C1D12    2      B  CAP_0402    I52
  C1D13    2      B  CAP_A       I51
  C1D14    2      B  CAP_A        I9
  C1D15    2      B  CAP_A       I39
  C1D16    2      B  CAP_0402    I38
  C1D17    2      B  CAP_0402    I43
  C1D23    2      B  CAP_0402    I45
  C1D24    2      B  CAP_A       I42
  C1D28    2      B  CAP_A       I44
  C1D32    2      B  CAP_0402    I18
  C1D33    2      B  CAP_0402    I22
  C1D34    2      B  CAP_A       I41
  C1D35    2      B  CAP_0402    I42
  C1E2     2      B  CAP         I155
  C1E3     2      B  CAP_A       I18
  C1E6     2      B  CAP_A       I29
  C1E7     2      B  CAP_0402    I28
  C1E8     2      B  CAP_0402    I32
  C1E9     2      B  CAP_A       I58
  C1E12    2      B  CAP         I32
  C1E13    2      B  CAP_0402    I34
  C1E14    2      B  CAP_A       I33
  C1E15    2      B  CAP         I35
  C1E16    2      B  CAP_A       I39
  C1E17    2      B  CAP_A       I38
  C1E18    2      B  CAPP        I37
  C1E20    2      B  CAP_A        I4
  C1E21    2      B  CAP          I3
  C1E22    2      B  CAP_A       I113
  C1E23    2      B  CAP_A       I37
  C1E24    2      B  CAP_0402    I40
  C1E25    2      B  CAP_0402    I36
  C1F7     2      B  CAPP        I85
  C1F9     2      B  CAP_A       I46
  C1F19    2      B  CAP_A        I8
  C1F21    2      B  CAP_A       I73
  C1F22    2      B  CAP_A       I181
  C1F27    2      B  CAP_0402    I48
  C1F28    2      B  CAP_A       I78
  C1G2     2      B  CAP         I194
  C1G4     2      B  CAP_A       I53
  C1G5     2      B  CAP_0402    I54
  C1G6     2      B  CAP_0402    I50
  C1G7     2      B  CAP         I195
  C1G8     2      B  CAP_A       I26
  C1G10    2      B  CAP_A        I3
  C1G12    2      B  CAP         I193
  C1G13    2      B  CAP_0402    I79
  C1G14    2      B  CAP_A       I51
  C1G15    2      B  CAP         I192
  C1G17    2      B  CAP          I6
  C1G18    2      B  CAP_A       I42
  C1G19    2      B  CAP_A       I180
  C1G20    2      B  CAP         I68
  C1G21    2      B  CAP         I80
  C1G22    2      B  CAP_A       I44
  C1G23    2      B  CAP_A       I41
  C1G24    2      B  CAP         I36
  C1G25    2      B  CAP_A       I27
  C1G26    2      B  CAP         I59
  C1G27    2      B  CAP_A       I25
  C1G28    2      B  CAP_0402    I77
  C1G29    2      B  CAP_0402    I72
  C1L1     2      B  CAP_0402    I136
  C1L4     2      B  CAP_A       I64
  C1L5     2      B  CAP_A       I30
  C1L8     2      B  CAP_A       I14
  C1L9     2      B  CAP_A       I38
  C1L10    2      B  CAP_A       I19
  C1L11    2      B  CAP_A       I87
  C1L16    2      B  CAP_A       I81
  C1L17    2      B  CAP_A       I37
  C1L18    2      B  CAP_A       I11
  C1L19    2      B  CAP_0402    I140
  C1L20    2      B  CAP_A       I267
  C1M3     2      B  CAP_A       I20
  C1M5     2      B  CAPP        I103
  C1M20    2      B  CAP_A       I270
  C1M21    2      B  CAP_A       I334
  C1M22    2      B  CAP_A        I8
  C1M23    2      B  CAP_A        I7
  C1M24    2      B  CAP_A       I10
  C1M25    2      B  CAP_A       I335
  C1M26    2      B  CAP          I6
  C1M27    2      B  CAP          I3
  C1M28    2      B  CAP_A       I119
  C1M29    2      B  CAP_A       I147
  C1M30    2      B  CAP_A       I131
  C1M31    2      B  CAP_A       I116
  C1M32    2      B  CAP_A       I117
  C1M33    2      B  CAP_A       I248
  C1M34    2      B  CAP_A       I265
  C1M35    2      B  CAP_A       I266
  C1M36    2      B  CAP_A       I42
  C1M37    2      B  CAP_A       I47
  C1M38    2      B  CAP_A       I108
  C1R13    2      B  CAP         I142
  C1R14    2      B  CAP_A       I145
  C1R15    2      B  CAP_A       I160
  C1R16    2      B  CAP         I161
  C1R17    2      B  CAP         I153
  C1R18    2      B  CAP_A       I157
  C1R19    2      B  CAP_A       I151
  C1R20    2      B  CAP_A       I143
  C1R21    2      B  CAP_A       I146
  C1R22    2      B  CAP         I136
  C1R23    2      B  CAPP        I101
  C1R24    2      B  CAP_A       I159
  C1R25    2      B  CAP_A        I3
  C1R26    2      B  CAP_A       I149
  C1R27    2      B  CAP_A       I30
  C1R28    2      B  CAP_A       I49
  C1R29    2      B  CAP_A       I150
  C1R30    2      B  CAP         I135
  C1R31    2      B  CAP_A       I152
  C1T3     2      B  CAP_A       I144
  C1T4     2      B  CAP         I134
  C1T5     2      B  CAP_A       I158
  C1T7     2      B  CAP         I22
  C1T8     2      B  CAP_A       I44
  C1T9     2      B  CAP         I75
  C1T10    2      B  CAP_A       I70
  C1T11    2      B  CAP_A       I97
  C1T12    2      B  CAP_A        I8
  C1T13    2      B  CAP         I74
  C1T14    2      B  CAP_A       I49
  C1T15    2      B  CAP         I12
  C1T16    2      B  CAP         I150
  C1T17    2      B  CAP_A       I151
  C1T18    2      B  CAP_A       I152
  C1T19    2      B  CAP_A       I121
  C1T20    2      B  CAP         I119
  C1T21    2      B  CAP_A       I28
  C1T22    2      B  CAP_A       I43
  C1T23    2      B  CAP_A       I147
  C1T24    2      B  CAP_A       I81
  C1T25    2      B  CAP_A       I42
  C1T26    2      B  CAP_A       I46
  C1T27    2      B  CAP_A       I82
  C1T28    2      B  CAP_A       I77
  C1T29    2      B  CAP_A        I5
  C1T30    2      B  CAP_A        I6
  C1T31    2      B  CAP_A       I92
  C1T32    2      B  CAP_A       I89
  C1T33    2      B  CAP_A       I80
  C1T34    2      B  CAP_A       I80
  C1T35    2      B  CAP_A       I93
  C1T36    2      B  CAP_A       I83
  C1T37    2      B  CAP_A       I336
  C1T38    2      B  CAP_A       I22
  C1T40    2      B  CAP_A       I76
  C1T41    2      B  CAP_A       I63
  C1T42    2      B  CAP         I85
  C1T43    2      B  CAP_A       I20
  C1T44    2      B  CAP         I25
  C1T45    2      B  CAP_A       I21
  C1T46    2      B  CAP_A       I91
  C1T47    2      B  CAP_A       I24
  C1T48    2      B  CAP_A       I58
  C1T49    2      B  CAP_A       I94
  C1T50    2      B  CAP_A       I41
  C1T51    2      B  CAP_A       I62
  C1T52    2      B  CAP_A        I1
  C1T53    2      B  CAP_A       I82
  C1T54    2      B  CAP_A       I83
  C1T55    2      B  CAP_A       I90
  C1T56    2      B  CAP_A       I184
  C1U1     2      B  CAP         I84
  C1U2     2      B  CAP         I26
  C1U3     2      B  CAP_A        I4
  C1U4     2      B  CAP_A       I18
  C1U5     2      B  CAP_A       I17
  C1U6     2      B  CAP_A       I78
  C1U7     2      B  CAP_A       I79
  C1U8     2      B  CAP_A       I19
  C1U9     2      B  CAP_A       I23
  C1U10    2      B  CAP_A       I86
  C1U11    2      B  CAP_A       I25
  C1U12    2      B  CAP         I88
  C1U13    2      B  CAP_A       I79
  C1U14    2      B  CAP_A       I84
  C1U15    2      B  CAP_A       I78
  C1U16    2      B  CAP_A       I81
  C1U17    2      B  CAP         I142
  C1U18    2      B  CAP_A       I141
  C1U19    2      B  CAP_0402    I18
  C1U20    2      B  CAP         I67
  C1U21    2      B  CAP         I56
  C1U22    2      B  CAP_A       I27
  C2A1     2      B  CAP_A       I210
  C2A2     2      B  CAP_A       I209
  C2A3     2      B  CAP_A       I230
  C2A4     2      B  CAP_A       I234
  C2A5     2      B  CAP_A       I199
  C2A6     2      B  CAP_A       I219
  C2A7     2      B  CAP_A       I218
  C2A8     2      B  CAP         I82
  C2A9     2      B  CAP_A       I215
  C2A10    2      B  CAP_A       I214
  C2A11    2      B  CAP_A       I213
  C2A12    2      B  CAP_A       I211
  C2A13    2      B  CAP_A       I212
  C2A14    2      B  CAP_A       I220
  C2A15    2      B  CAP_A       I221
  C2A16    2      B  CAP         I89
  C2B1     2      B  CAP_A       I200
  C2B2     2      B  CAP_A       I204
  C2D1     2      B  CAP_A       I116
  C2D2     2      B  CAP_A       I201
  C2D3     2      B  CAP_A       I202
  C2D4     2      B  CAP         I187
  C2D5     2      B  CAP         I188
  C2D6     2      B  CAP         I190
  C2D7     2      B  CAP         I186
  C2D8     2      B  CAP         I33
  C2D9     2      B  CAP         I43
  C2D10    2      B  CAP         I37
  C2D11    2      B  CAP         I42
  C2D12    2      B  CAP_A       I59
  C2D13    2      B  CAP_A       I73
  C2D14    2      B  CAP_A       I76
  C2D15    2      B  CAP_A       I159
  C2D16    2      B  CAP_A       I124
  C2D17    2      B  CAP_A       I114
  C2D18    2      B  CAP_A       I197
  C2D19    2      B  CAP_A       I75
  C2D20    2      B  CAP_A       I79
  C2D21    2      B  CAP_A       I65
  C2D22    2      B  CAP_A       I61
  C2D23    2      B  CAP_A       I112
  C2D24    2      B  CAP_A       I80
  C2D25    2      B  CAP_A       I82
  C2D26    2      B  CAP_A       I108
  C2D27    2      B  CAP_A       I66
  C2D28    2      B  CAP_A       I198
  C2D29    2      B  CAP_A       I199
  C2D30    2      B  CAP_A       I83
  C2D31    2      B  CAP_A       I63
  C2D32    2      B  CAP_A       I90
  C2D33    2      B  CAP_A       I85
  C2D34    2      B  CAP_A       I122
  C2D35    2      B  CAP_A       I161
  C2D36    2      B  CAP_A       I70
  C2D37    2      B  CAP_A       I119
  C2D38    2      B  CAP_A       I160
  C2D39    2      B  CAP_A       I165
  C2D40    2      B  CAP_A       I10
  C2D41    2      B  CAP         I180
  C2D42    2      B  CAP         I183
  C2D43    2      B  CAP         I179
  C2D44    2      B  CAP         I181
  C2D45    2      B  CAP_A       I123
  C2D46    2      B  CAP_A       I204
  C2D47    2      B  CAP_A       I203
  C2F1     2      B  CAP_A       I201
  C2F2     2      B  CAP_A       I47
  C2G1     2      B  CAP_A       I219
  C2G2     2      B  CAP_A       I217
  C2G3     2      B  CAP_A       I216
  C2G4     2      B  CAP_A       I215
  C2G5     2      B  CAP_A       I214
  C2G6     2      B  CAP_A       I213
  C2G7     2      B  CAP         I92
  C2G8     2      B  CAP_A       I197
  C2G9     2      B  CAP_A       I218
  C2G10    2      B  CAP_A       I223
  C2G11    2      B  CAP_A       I221
  C2G12    2      B  CAP_A       I220
  C2G13    2      B  CAP_A       I210
  C2G14    2      B  CAP_A       I209
  C2G15    2      B  CAP_A       I200
  C2G16    2      B  CAP         I110
  C2L8     2      B  CAP_A       I151
  C2L11    2      B  CAP_A       I169
  C2L25    2      B  CAPP        I79
  C2L32    2      B  CAP         I79
  C2L45    2      B  CAP         I12
  C2L46    2      B  CAPP        I77
  C2M1     2      B  CAP_A       I43
  C2M2     2      B  CAP_A       I45
  C2M5     2      B  CAP         I43
  C2M6     2      B  CAP_A       I76
  C2M7     2      B  CAP_A       I44
  C2M8     2      B  CAP_A       I74
  C2M9     2      B  CAP_A       I50
  C2M10    2      B  CAP         I49
  C2M11    2      B  CAP         I35
  C2M12    2      B  CAP_A       I52
  C2M13    2      B  CAP_A       I48
  C2M16    2      B  CAP_A       I37
  C2M17    2      B  CAP         I34
  C2M18    2      B  CAP_A       I29
  C2M19    2      B  CAP_A       I31
  C2M20    2      B  CAP_A       I39
  C2M21    2      B  CAP_A       I28
  C2M22    2      B  CAP_A       I27
  C2M25    2      B  CAP_A       I78
  C2N2     2      B  CAP_A       I41
  C2N3     2      B  CAP_A       I27
  C2N4     2      B  CAP_A       I28
  C2N5     2      B  CAP_A       I65
  C2N6     2      B  CAP         I64
  C2N7     2      B  CAP_A       I43
  C2N8     2      B  CAP_A       I47
  C2N9     2      B  CAP_A       I26
  C2N10    2      B  CAP_A       I50
  C2N11    2      B  CAP_A       I30
  C2N12    2      B  CAP_A       I29
  C2N13    2      B  CAP_A       I40
  C2N14    2      B  CAP         I25
  C2N15    2      B  CAP_A       I47
  C2N16    2      B  CAP_A       I52
  C2N17    2      B  CAP         I28
  C2N18    2      B  CAP_A       I29
  C2N19    2      B  CAP_A        I7
  C2N20    2      B  CAP_A       I12
  C2N21    2      B  CAP         I15
  C2N22    2      B  CAP          I9
  C2N23    2      B  CAP         I24
  C2N24    2      B  CAP          I8
  C2N25    2      B  CAP_A       I34
  C2N26    2      B  CAP_A        I4
  C2P1     2      B  CAP_A        I8
  C2P2     2      B  CAP_A        I9
  C2P3     2      B  CAP_A       I22
  C2P4     2      B  CAP_A       I16
  C2P5     2      B  CAP_A        I3
  C2P6     2      B  CAP_A       I18
  C2P7     2      B  CAP_A       I20
  C2P8     2      B  CAP_A        I1
  C2P9     2      B  CAP_A       I117
  C2P10    2      B  CAP         I41
  C2P11    2      B  CAP_A       I21
  C2P12    2      B  CAP_A       I23
  C2P13    2      B  CAP_A       I57
  C2P14    2      B  CAP_A       I56
  C2P15    2      B  CAP_A       I55
  C2P16    2      B  CAP_A       I53
  C2R1     2      B  CAP_A        I8
  C2R2     2      B  CAP_A       I28
  C2R3     2      B  CAP_A       I19
  C2R4     2      B  CAP_A       I21
  C2R5     2      B  CAP_A       I15
  C2R6     2      B  CAP         I224
  C2R12    2      B  CAP_A       I353
  C2R15    2      B  CAP_A        I2
  C2R16    2      B  CAP_A       I40
  C2R17    2      B  CAP_A       I25
  C2R18    2      B  CAP_A        I3
  C2T1     2      B  CAP_A       I94
  C2T2     2      B  CAP_A       I131
  C2T3     2      B  CAP_A       I370
  C2T4     2      B  CAP_A       I132
  C2T5     2      B  CAP_A       I135
  C2T6     2      B  CAP         I160
  C2T7     2      B  CAP         I158
  C2T8     2      B  CAP_A       I135
  C2T9     2      B  CAP         I174
  C2T12    2      B  CAP_A       I132
  C2T15    2      B  CAP_A       I127
  C2T16    2      B  CAP_A       I126
  C2T17    2      B  CAP_A       I112
  C2T18    2      B  CAP_A       I104
  C2T19    2      B  CAP_A       I106
  C2T21    2      B  CAP_A       I124
  C2T22    2      B  CAP         I113
  C2T24    2      B  CAP_A       I129
  C2T25    2      B  CAP_A       I111
  C2T26    2      B  CAP_A       I123
  C2T27    2      B  CAP_A       I90
  C2T28    2      B  CAP_A       I116
  C2T29    2      B  CAP_A       I120
  C2T30    2      B  CAP_A       I110
  C2T31    2      B  CAP_A       I89
  C2T32    2      B  CAP_A       I95
  C2T33    2      B  CAP_A       I72
  C2T34    2      B  CAP_A       I109
  C2T35    2      B  CAP_A       I273
  C2T36    2      B  CAP_A       I43
  C2T37    2      B  CAP_A       I99
  C2T38    2      B  CAP_A       I97
  C2U1     2      B  CAP         I44
  C2U2     2      B  CAP         I47
  C2U19    2      B  CAP_A       I46
  C2U20    2      B  CAP_A        I1
  C2U21    2      B  CAP_A        I5
  C2U22    2      B  CAP_A       I318
  C2U23    2      B  CAP_A       I315
  C2U24    2      B  CAP_A        I2
  C2U25    2      B  CAP_A        I7
  C2U26    2      B  CAP_A       I102
  C2U27    2      B  CAP_A       I90
  C2U28    2      B  CAP_A       I93
  C3A1     2      B  CAP_A       I217
  C3A2     2      B  CAP_A       I216
  C3A3     2      B  CAP         I97
  C3A4     2      B  CAP         I93
  C3A5     2      B  CAP_A       I222
  C3A6     2      B  CAP_A       I223
  C3A7     2      B  CAP         I95
  C3A8     2      B  CAP         I86
  C3B1     2      B  CAP         I94
  C3B2     2      B  CAP         I84
  C3B3     2      B  CAPP        I167
  C3B4     2      B  CAP_A       I47
  C3B5     2      B  CAP_A       I53
  C3B6     2      B  CAPP        I100
  C3C1     2      B  CAP_A       I38
  C3C2     2      B  CAP_A       I31
  C3D1     2      B  CAP_A       I111
  C3D2     2      B  CAP_A       I69
  C3D3     2      B  CAP         I25
  C3D4     2      B  CAP_A        I5
  C3D5     2      B  CAP_A        I3
  C3D6     2      B  CAP_A       I170
  C3D7     2      B  CAP_A       I164
  C3D8     2      B  CAP_A       I18
  C3D9     2      B  CAP_A       I15
  C3D10    2      B  CAP_A       I196
  C3D11    2      B  CAP_A        I7
  C3D12    2      B  CAP_A        I4
  C3D13    2      B  CAP_A        I8
  C3D14    2      B  CAP_A       I171
  C3D15    2      B  CAP_A       I174
  C3D16    2      B  CAP_A       I176
  C3D17    2      B  CAP_A       I166
  C3D18    2      B  CAP_A       I169
  C3D19    2      B  CAP_A       I208
  C3D20    2      B  CAP_A       I207
  C3D21    2      B  CAP_A        I1
  C3D22    2      B  CAP         I10
  C3D23    2      B  CAP_A       I172
  C3D24    2      B  CAP_A       I175
  C3D25    2      B  CAP_A       I205
  C3E1     2      B  CAP_A       I108
  C3F1     2      B  CAP_A       I140
  C3F2     2      B  CAP_A       I34
  C3F3     2      B  CAP         I116
  C3F4     2      B  CAP         I117
  C3G1     2      B  CAP_A       I212
  C3G2     2      B  CAP_A       I211
  C3G3     2      B  CAP         I118
  C3G4     2      B  CAP         I133
  C3G5     2      B  CAP_A       I208
  C3G6     2      B  CAP_A       I207
  C3G7     2      B  CAP         I132
  C3G8     2      B  CAP         I135
  C3L1     2      B  CAP_A       I17
  C3L2     2      B  CAP         I45
  C3L4     2      B  CAP         I46
  C3L6     2      B  CAPP        I75
  C3L7     2      B  CAP         I31
  C3L8     2      B  CAP         I26
  C3L9     2      B  CAP         I29
  C3L10    2      B  CAP         I32
  C3L11    2      B  CAP         I24
  C3L12    2      B  CAP         I23
  C3L13    2      B  CAP         I47
  C3L14    2      B  CAPP        I76
  C3L15    2      B  CAP         I84
  C3L16    2      B  CAP         I81
  C3L17    2      B  CAP         I80
  C3L18    2      B  CAPP        I71
  C3L19    2      B  CAPP        I76
  C3L20    2      B  CAPP        I73
  C3L21    2      B  CAPP        I74
  C3L22    2      B  CAP_A       I54
  C3L23    2      B  CAP_A       I52
  C3L24    2      B  CAP_A       I56
  C3L25    2      B  CAP_A        I1
  C3L26    2      B  CAP_A        I3
  C3L27    2      B  CAP_A        I4
  C3L29    2      B  CAP_A       I38
  C3L31    2      B  CAP_A       I77
  C3M6     2      B  CAP_A        I6
  C3M7     2      B  CAP_A        I2
  C3M8     2      B  CAP         I259
  C3M9     2      B  CAP_0402    I207
  C3M15    2      B  CAP         I260
  C3M16    2      B  CAP         I261
  C3M17    2      B  CAP         I86
  C3M18    2      B  CAP         I85
  C3M19    2      B  CAP_A       I87
  C3M20    2      B  CAP_A       I84
  C3M21    2      B  CAP_A        I9
  C3M22    2      B  CAP_A       I18
  C3M23    2      B  CAP         I82
  C3M24    2      B  CAP         I81
  C3M27    2      B  CAP_A       I83
  C3M29    2      B  CAP_A       I80
  C3M30    2      B  CAP_A       I27
  C3M31    2      B  CAP_A       I57
  C3M38    2      B  CAP_A       I32
  C3M39    2      B  CAP_A       I44
  C3M42    2      B  CAP_A       I45
  C3M43    2      B  CAP_A       I42
  C3M46    2      B  CAP_A       I99
  C3N1     2      B  CAP_A       I34
  C3N2     2      B  CAP_A       I43
  C3N3     2      B  CAP_A       I32
  C3N4     2      B  CAP_A       I46
  C3N5     2      B  CAP_A       I48
  C3N6     2      B  CAP_A       I44
  C3N7     2      B  CAP_A       I35
  C3N10    2      B  CAP_A       I13
  C3N11    2      B  CAP_A       I19
  C3N12    2      B  CAP_A       I12
  C3N14    2      B  CAPP        I101
  C3N15    2      B  CAP_A       I49
  C3N16    2      B  CAP_A       I36
  C3N17    2      B  CAP_A       I45
  C3N18    2      B  CAP_A       I42
  C3N19    2      B  CAP_A       I31
  C3N20    2      B  CAP_A       I51
  C3N21    2      B  CAP_A       I49
  C3N22    2      B  CAP_A       I53
  C3N23    2      B  CAP_A       I42
  C3N24    2      B  CAP_A       I16
  C3N25    2      B  CAP_A       I50
  C3N26    2      B  CAPP        I17
  C3N27    2      B  CAP_A        I8
  C3N28    2      B  CAP_A       I17
  C3N29    2      B  CAP_A       I16
  C3N30    2      B  CAP_A        I9
  C3N31    2      B  CAP_A       I20
  C3N32    2      B  CAP_A       I20
  C3N33    2      B  CAP         I41
  C3N34    2      B  CAP         I43
  C3N35    2      B  CAPP        I18
  C3N36    2      B  CAP         I40
  C3N38    2      B  CAPP        I16
  C3N40    2      B  CAP_A       I86
  C3P2     2      B  CAP         I33
  C3P3     2      B  CAP_A       I20
  C3P4     2      B  CAP_A       I11
  C3P5     2      B  CAP_A       I13
  C3P6     2      B  CAP         I71
  C3P7     2      B  CAP_A       I22
  C3P42    2      B  CAP_A       I73
  C3P43    2      B  CAP_A        I6
  C3P44    2      B  CAP_A       I23
  C3P45    2      B  CAP_0402    I60
  C3P46    2      B  CAP_A       I72
  C3P47    2      B  CAP_A       I12
  C3P48    2      B  CAP_A       I25
  C3P49    2      B  CAP_A       I37
  C3P50    2      B  CAP_0402    I84
  C3P51    2      B  CAP_A       I11
  C3P52    2      B  CAP_A       I17
  C3R1     2      B  CAP_A        I4
  C3R2     2      B  CAP_A       I10
  C3R3     2      B  CAP_A        I7
  C3R4     2      B  CAPP        I31
  C3T1     2      B  CAP_A       I149
  C3T2     2      B  CAP_A       I150
  C3T3     2      B  CAPP        I113
  C3T4     2      B  CAP_A       I138
  C3T5     2      B  CAP_A       I136
  C3T6     2      B  CAPP        I98
  C3T7     2      B  CAP         I184
  C3T8     2      B  CAP         I210
  C3T9     2      B  CAP         I186
  C3T10    2      B  CAP_0402    I161
  C3T12    2      B  CAP         I215
  C3T13    2      B  CAPP        I104
  C3T14    2      B  CAP         I211
  C3T15    2      B  CAPP        I106
  C3U1     2      B  CAPP        I76
  C3U2     2      B  CAP         I45
  C3U3     2      B  CAP         I46
  C3U4     2      B  CAP         I47
  C3U5     2      B  CAPP        I77
  C3U6     2      B  CAP         I84
  C3U7     2      B  CAP         I81
  C3U8     2      B  CAPP        I78
  C3U9     2      B  CAP         I80
  C3U10    2      B  CAP_A       I360
  C4A1     2      B  CAP         I16
  C4A2     2      B  CAP         I40
  C4A3     2      B  CAP         I16
  C4A4     2      B  CAP         I62
  C4A5     2      B  CAP_A       I179
  C4A6     2      B  CAP         I39
  C4A7     2      B  CAP         I46
  C4A8     2      B  CAP_0402    I28
  C4A9     2      B  CAP_0402    I21
  C4A10    2      B  CAP_0402    I28
  C4A11    2      B  CAP         I46
  C4A12    2      B  CAP         I12
  C4A13    2      B  CAP         I18
  C4A14    2      B  CAP_0402    I21
  C4A15    2      B  CAP         I25
  C4A17    2      B  CAP         I67
  C4A18    2      B  CAP_A        I3
  C4A19    2      B  CAP         I205
  C4A20    2      B  CAP_A       I199
  C4B1     2      B  CAP         I130
  C4B2     2      B  CAP         I180
  C4B3     2      B  CAP         I177
  C4B8     2      B  CAP         I139
  C4B11    2      B  CAP         I59
  C4B12    2      B  CAP_A       I179
  C4B13    2      B  CAPP        I83
  C4B14    2      B  CAPP        I97
  C4C1     2      B  CAPP        I29
  C4C2     2      B  CAP_A       I51
  C4C3     2      B  CAP_A       I75
  C4C4     2      B  CAP_A       I18
  C4C5     2      B  CAP_0402    I16
  C4C6     2      B  CAP_0402    I20
  C4C9     2      B  CAP_0402    I32
  C4C10    2      B  CAP_A       I31
  C4C11    2      B  CAP_A       I43
  C4C12    2      B  CAPP        I67
  C4C14    2      B  CAP_A       I19
  C4C18    2      B  CAP_0402    I36
  C4C19    2      B  CAP_A       I35
  C4D2     2      B  CAPP        I48
  C4D4     2      B  CAP_A       I69
  C4D5     2      B  CAP_0402    I48
  C4D6     2      B  CAP_A       I49
  C4D7     2      B  CAP_0402    I51
  C4D10    2      B  CAP_0402    I53
  C4D11    2      B  CAP_A       I52
  C4D12    2      B  CAP_A        I9
  C4D13    2      B  CAP_0402    I40
  C4D14    2      B  CAP_A       I41
  C4D15    2      B  CAP_A       I37
  C4D16    2      B  CAP_0402    I45
  C4D17    2      B  CAP         I66
  C4D18    2      B  CAP         I68
  C4D19    2      B  CAP_A       I39
  C4D20    2      B  CAP         I60
  C4D22    2      B  CAP_A       I28
  C4D23    2      B  CAP_A       I19
  C4D24    2      B  CAP_A       I18
  C4D25    2      B  CAP_A       I30
  C4D26    2      B  CAP_A       I32
  C4D27    2      B  CAP_A       I30
  C4D30    2      B  CAP_0402    I47
  C4D31    2      B  CAP_A        I9
  C4D32    2      B  CAP_A       I11
  C4D33    2      B  CAP         I73
  C4D34    2      B  CAP_A       I68
  C4D35    2      B  CAP_A       I46
  C4D36    2      B  CAP_A       I17
  C4D38    2      B  CAP_A       I35
  C4D40    2      B  CAP         I33
  C4D42    2      B  CAP         I125
  C4D46    2      B  CAP_0402    I34
  C4D47    2      B  CAP_0402    I18
  C4D48    2      B  CAP_0402    I47
  C4D49    2      B  CAP_A       I46
  C4E3     2      B  CAP_A       I61
  C4E5     2      B  CAP_0402    I18
  C4E6     2      B  CAP_A       I19
  C4E7     2      B  CAPP        I20
  C4E8     2      B  CAP         I29
  C4E9     2      B  CAP          I8
  C4E10    2      B  CAP_0402    I34
  C4E11    2      B  CAP_A       I27
  C4E13    2      B  CAP_A       I77
  C4E14    2      B  CAP         I31
  C4E15    2      B  CAP_0402    I79
  C4E16    2      B  CAPP        I50
  C4E19    2      B  CAP_0402    I36
  C4E20    2      B  CAP_A       I35
  C4E22    2      B  CAP_0402    I76
  C4E23    2      B  CAP_0402    I73
  C4E24    2      B  CAPP        I61
  C4E25    2      B  CAP_A       I25
  C4E26    2      B  CAP_0402    I45
  C4E27    2      B  CAP_0402    I24
  C4E28    2      B  CAP_A       I74
  C4F1     2      B  CAP_A       I68
  C4F2     2      B  CAP_A       I141
  C4F3     2      B  CAP_A       I70
  C4F4     2      B  CAPP        I112
  C4F5     2      B  CAPP        I96
  C4F6     2      B  CAPP        I82
  C4F7     2      B  CAPP        I217
  C4F9     2      B  CAP_A        I7
  C4F10    2      B  CAP_A       I272
  C4F11    2      B  CAPP        I256
  C4G1     2      B  CAP_A       I43
  C4G2     2      B  CAP         I253
  C4G3     2      B  CAP_A       I179
  C4G4     2      B  CAP_0402    I196
  C4G5     2      B  CAP         I189
  C4G9     2      B  CAP         I201
  C4G12    2      B  CAP         I36
  C4G13    2      B  CAP         I15
  C4G14    2      B  CAP         I15
  C4G15    2      B  CAP_0402    I24
  C4G16    2      B  CAP_0402    I34
  C4G17    2      B  CAP_A       I51
  C4G18    2      B  CAP_0402    I27
  C4G19    2      B  CAP_A       I188
  C4G20    2      B  CAP         I17
  C4G21    2      B  CAP_0402    I21
  C4G22    2      B  CAP_A       I27
  C4G23    2      B  CAP         I39
  C4G24    2      B  CAP         I20
  C4G25    2      B  CAP_A       I41
  C4L1     2      B  CAP         I129
  C4L2     2      B  CAP         I102
  C4L3     2      B  CAP         I106
  C4L4     2      B  CAP         I108
  C4L5     2      B  CAPP        I78
  C4M1     2      B  CAPP        I267
  C4M2     2      B  CAP_A       I222
  C4M3     2      B  CAP         I111
  C4M4     2      B  CAP         I125
  C4M5     2      B  CAP_A       I196
  C4M6     2      B  CAPP        I102
  C4M7     2      B  CAPP        I105
  C4P1     2      B  CAP         I10
  C4P2     2      B  CAP         I163
  C4P3     2      B  CAP          I8
  C4P4     2      B  CAP         I14
  C4P5     2      B  CAP         I172
  C4P6     2      B  CAP_A       I164
  C4P7     2      B  CAP          I9
  C4P8     2      B  CAP_A       I178
  C4P9     2      B  CAP         I12
  C4P10    2      B  CAP         I17
  C4R1     2      B  CAPP        I29
  C4R2     2      B  CAP_A       I246
  C4T1     2      B  CAP_A       I16
  C4T2     2      B  CAP_A        I9
  C4T3     2      B  CAPP        I217
  C4T4     2      B  CAP         I91
  C4T5     2      B  CAP         I125
  C4T6     2      B  CAP         I124
  C4U1     2      B  CAP         I130
  C4U2     2      B  CAP         I129
  C4U3     2      B  CAP         I148
  C4U4     2      B  CAP         I146
  C5A1     2      B  CAP_A       I219
  C5A2     2      B  CAP_A       I214
  C5A3     2      B  CAP_A       I210
  C5A4     2      B  CAP_A       I206
  C5A5     2      B  CAP_A       I193
  C5A6     2      B  CAP_A       I212
  C5A7     2      B  CAP_A       I211
  C5A8     2      B  CAP_A       I209
  C5A9     2      B  CAP_A       I208
  C5A10    2      B  CAP         I110
  C5A11    2      B  CAP_A       I221
  C5A12    2      B  CAP_A       I216
  C5A13    2      B  CAP_A       I215
  C5A14    2      B  CAP_A       I213
  C5A15    2      B  CAP_A       I217
  C5A16    2      B  CAP_A       I207
  C5A17    2      B  CAP_A       I205
  C5A18    2      B  CAP_A       I204
  C5A19    2      B  CAP_A       I203
  C5A20    2      B  CAP         I92
  C5B1     2      B  CAP_A       I194
  C5B2     2      B  CAP_A       I197
  C5D1     2      B  CAP_A       I126
  C5D2     2      B  CAP_A       I136
  C5D3     2      B  CAP_A       I130
  C5D4     2      B  CAP_A       I127
  C5D5     2      B  CAP_A       I125
  C5D6     2      B  CAP         I182
  C5D7     2      B  CAP         I183
  C5D8     2      B  CAP         I184
  C5D9     2      B  CAP         I180
  C5D10    2      B  CAP         I108
  C5D11    2      B  CAP         I93
  C5D12    2      B  CAP         I94
  C5D13    2      B  CAP         I91
  C5D14    2      B  CAP_A       I117
  C5D15    2      B  CAP_A       I132
  C5D16    2      B  CAP_A       I123
  C5D17    2      B  CAP_A       I118
  C5D18    2      B  CAP_A       I134
  C5D19    2      B  CAP_A       I128
  C5D20    2      B  CAP_A       I173
  C5D21    2      B  CAP_A       I88
  C5D22    2      B  CAP_A       I153
  C5D23    2      B  CAP_A       I98
  C5D24    2      B  CAP_A       I138
  C5D25    2      B  CAP_A       I155
  C5D26    2      B  CAP_A       I154
  C5D27    2      B  CAP_A       I109
  C5D28    2      B  CAP_A       I100
  C5D29    2      B  CAP_A       I102
  C5D30    2      B  CAP_A       I111
  C5D31    2      B  CAP_A       I106
  C5D32    2      B  CAP_A       I103
  C5D33    2      B  CAP_A       I174
  C5D34    2      B  CAP_A       I175
  C5D35    2      B  CAP_A       I176
  C5D36    2      B  CAP_A       I151
  C5D37    2      B  CAP_A       I70
  C5D38    2      B  CAP_A       I69
  C5D39    2      B  CAP_A       I140
  C5D40    2      B  CAP_A       I115
  C5D41    2      B  CAP_A       I114
  C5D42    2      B  CAP_A       I135
  C5D43    2      B  CAP_A       I131
  C5D44    2      B  CAP_A       I142
  C5D45    2      B  CAP_A       I156
  C5D46    2      B  CAP_A       I107
  C5D47    2      B  CAP_A       I104
  C5D48    2      B  CAP_A       I90
  C5D49    2      B  CAP_A       I152
  C5D50    2      B  CAP_A       I89
  C5D51    2      B  CAP_A       I83
  C5D52    2      B  CAP_A       I180
  C5D53    2      B  CAP_A       I179
  C5D54    2      B  CAP         I190
  C5D55    2      B  CAP         I189
  C5D56    2      B  CAP         I188
  C5D57    2      B  CAP         I186
  C5D58    2      B  CAP_A       I120
  C5D59    2      B  CAP_A       I129
  C5D60    2      B  CAP_A       I112
  C5D61    2      B  CAP_A       I113
  C5F1     2      B  CAP_A       I206
  C5F2     2      B  CAP_A       I205
  C5G1     2      B  CAP_A       I231
  C5G2     2      B  CAP_A       I245
  C5G3     2      B  CAP_A       I217
  C5G4     2      B  CAP_A       I241
  C5G5     2      B  CAP_A       I235
  C5G6     2      B  CAP_A       I237
  C5G7     2      B  CAP_A       I234
  C5G8     2      B  CAP_A       I230
  C5G9     2      B  CAP         I92
  C5G10    2      B  CAP_A       I207
  C5G11    2      B  CAP_A       I250
  C5G12    2      B  CAP_A       I246
  C5G13    2      B  CAP_A       I240
  C5G14    2      B  CAP_A       I223
  C5G15    2      B  CAP_A       I220
  C5G16    2      B  CAP_A       I221
  C5G17    2      B  CAP_A       I226
  C5G18    2      B  CAP_A       I227
  C5G19    2      B  CAP_A       I213
  C5G20    2      B  CAP         I110
  C5G21    2      B  CAP         I11
  C5G22    2      B  CAP         I15
  C5G41    2      B  CAP_A       I53
  C5G42    2      B  CAP_A       I54
  C5G43    2      B  CAP_A       I56
  C5G44    2      B  CAP_A       I55
  C5G45    2      B  CAP_A       I60
  C5G46    2      B  CAP_A       I59
  C5G47    2      B  CAP_A       I58
  C5G48    2      B  CAP_A       I57
  C5G49    2      B  CAP_A       I61
  C5G50    2      B  CAP_A       I70
  C5G51    2      B  CAP_A       I69
  C5G52    2      B  CAP_A       I68
  C5G53    2      B  CAP_A       I67
  C5G54    2      B  CAP_A       I62
  C5G55    2      B  CAP_A       I66
  C5G56    2      B  CAP_A       I65
  C5G57    2      B  CAP_A       I64
  C5G58    2      B  CAP_A       I63
  C5G59    2      B  CAP_A       I79
  C5G60    2      B  CAP_A       I78
  C5G61    2      B  CAP_A       I77
  C5G62    2      B  CAP_A       I76
  C5G63    2      B  CAP_A       I75
  C5G64    2      B  CAP_A       I74
  C5G65    2      B  CAP_A       I73
  C5G66    2      B  CAP_A       I72
  C5G67    2      B  CAP_A       I71
  C5G68    2      B  CAP_A       I88
  C5G69    2      B  CAP_A       I87
  C5G70    2      B  CAP_A       I86
  C5G71    2      B  CAP_A       I85
  C5G72    2      B  CAP_A       I84
  C5G73    2      B  CAP_A       I83
  C5G74    2      B  CAP_A       I82
  C5G75    2      B  CAP_A       I81
  C5G76    2      B  CAP_A       I80
  C5G77    2      B  CAP         I37
  C5G78    2      B  CAP         I41
  C5G79    2      B  CAP_A       I53
  C5G80    2      B  CAP_A       I61
  C5G81    2      B  CAP_A       I60
  C5G82    2      B  CAP_A       I59
  C5G83    2      B  CAP_A       I58
  C5G84    2      B  CAP_A       I57
  C5G85    2      B  CAP_A       I56
  C5G86    2      B  CAP_A       I55
  C5G87    2      B  CAP_A       I54
  C5G88    2      B  CAP_A       I70
  C5G89    2      B  CAP_A       I69
  C5G90    2      B  CAP_A       I68
  C5G91    2      B  CAP_A       I67
  C5G92    2      B  CAP_A       I66
  C5G93    2      B  CAP_A       I65
  C5G94    2      B  CAP_A       I64
  C5G95    2      B  CAP_A       I63
  C5G96    2      B  CAP_A       I62
  C5G97    2      B  CAP_A       I79
  C5G98    2      B  CAP_A       I78
  C5G99    2      B  CAP_A       I77
  C5G100    2      B  CAP_A       I76
  C5G101    2      B  CAP_A       I75
  C5G102    2      B  CAP_A       I74
  C5G103    2      B  CAP_A       I71
  C5G104    2      B  CAP_A       I72
  C5G105    2      B  CAP_A       I73
  C5G106    2      B  CAP_A       I88
  C5G107    2      B  CAP_A       I87
  C5G108    2      B  CAP_A       I86
  C5G109    2      B  CAP_A       I85
  C5G110    2      B  CAP_A       I84
  C5G111    2      B  CAP_A       I83
  C5G112    2      B  CAP_A       I82
  C5G113    2      B  CAP_A       I81
  C5G114    2      B  CAP_A       I80
  C5G115    2      B  CAP         I39
  C5G116    2      B  CAP         I43
  C5G117    2      B  CAP         I12
  C5G118    2      B  CAP         I13
  C5L1     2      B  CAP         I91
  C5L2     2      B  CAP         I90
  C5L3     2      B  CAP         I89
  C5L4     2      B  CAP_A       I47
  C5L5     2      B  CAP_A       I49
  C5L6     2      B  CAP_A       I237
  C5L7     2      B  CAP_A       I236
  C5L8     2      B  CAP_A       I234
  C5L9     2      B  CAP_A       I233
  C5L10    2      B  CAP_A       I232
  C5L11    2      B  CAP_A       I231
  C5L12    2      B  CAP_A       I230
  C5L13    2      B  CAP_A       I229
  C5L14    2      B  CAP         I83
  C5L15    2      B  CAP_A       I192
  C5M1     2      B  CAP_A       I223
  C5M2     2      B  CAP_A       I224
  C5M3     2      B  CAP_A       I199
  C5M4     2      B  CAP_A       I225
  C5M5     2      B  CAP_A       I226
  C5M6     2      B  CAP_A       I227
  C5M7     2      B  CAP_A       I228
  C5M8     2      B  CAP         I82
  C5M9     2      B  CAP_A       I195
  C5M10    2      B  CAP_A       I198
  C5M11    2      B  CAP_A       I200
  C5M12    2      B  CAP         I88
  C5M13    2      B  CAP_A       I48
  C5P1     2      B  CAP         I179
  C5P2     2      B  CAP         I177
  C5P3     2      B  CAP         I189
  C5P4     2      B  CAP         I27
  C5P5     2      B  CAP         I42
  C5P6     2      B  CAP         I38
  C5P7     2      B  CAP         I25
  C5P8     2      B  CAP         I19
  C5P9     2      B  CAP         I18
  C5P10    2      B  CAP          I6
  C5P11    2      B  CAP          I4
  C5P12    2      B  CAP         I183
  C5P13    2      B  CAP         I186
  C5P14    2      B  CAP         I41
  C5P15    2      B  CAP         I187
  C5P16    2      B  CAP         I188
  C5P17    2      B  CAP         I190
  C5P18    2      B  CAP          I2
  C5P19    2      B  CAP         I13
  C5P20    2      B  CAP         I185
  C5P21    2      B  CAP         I184
  C5P22    2      B  CAP         I55
  C5P23    2      B  CAP         I28
  C5P24    2      B  CAP         I33
  C5P25    2      B  CAP         I37
  C5P26    2      B  CAP         I56
  C5P27    2      B  CAP         I44
  C5P28    2      B  CAP          I3
  C5P29    2      B  CAP         I149
  C5P30    2      B  CAP         I148
  C5P31    2      B  CAP         I162
  C5P32    2      B  CAP         I53
  C5P33    2      B  CAP         I50
  C5P34    2      B  CAP         I54
  C5P35    2      B  CAP         I51
  C5P36    2      B  CAP         I65
  C5P37    2      B  CAP         I63
  C5P38    2      B  CAP         I193
  C5P39    2      B  CAP         I184
  C5P40    2      B  CAP         I57
  C5P41    2      B  CAP         I40
  C5P42    2      B  CAP         I59
  C5P43    2      B  CAP         I60
  C5P44    2      B  CAP         I61
  C5T1     2      B  CAP_A       I212
  C5T2     2      B  CAP_A       I208
  C5T3     2      B  CAP_A       I51
  C5T4     2      B  CAP_A       I211
  C5T5     2      B  CAP_A       I216
  C5T6     2      B  CAP_A       I218
  C5T7     2      B  CAP_A       I219
  C5T8     2      B  CAP_A       I222
  C5T9     2      B  CAP_A       I224
  C5T10    2      B  CAP_A       I225
  C5T11    2      B  CAP_A       I228
  C5T12    2      B  CAP_A       I229
  C5T13    2      B  CAP_A       I210
  C5U1     2      B  CAP         I88
  C5U2     2      B  CAP_A       I247
  C5U3     2      B  CAP_A       I244
  C5U4     2      B  CAP_A       I243
  C5U5     2      B  CAP_A       I239
  C5U6     2      B  CAP_A       I238
  C5U7     2      B  CAP_A       I236
  C5U8     2      B  CAP_A       I233
  C5U9     2      B  CAP_A       I232
  C5U10    2      B  CAP         I83
  C5U11    2      B  CAP_A       I209
  C5U12    2      B  CAP_A       I50
  C5U13    2      B  CAP         I82
  C5U14    2      B  CAP         I89
  C5U15    2      B  CAP         I90
  C5U16    2      B  CAP_A       I52
  C6A1     2      B  CAP         I87
  C6A2     2      B  CAP         I105
  C6A3     2      B  CAP         I104
  C6A4     2      B  CAP         I68
  C6A5     2      B  CAPP        I77
  C6A6     2      B  CAP         I110
  C6A7     2      B  CAP         I109
  C6B1     2      B  CAP         I128
  C6B2     2      B  CAP         I126
  C6B3     2      B  CAP         I236
  C6B7     2      B  CAPP        I229
  C6D1     2      B  CAP         I19
  C6D2     2      B  CAP_A       I77
  C6D3     2      B  CAP_A       I80
  C6D4     2      B  CAP_A       I74
  C6D5     2      B  CAP_A       I75
  C6D6     2      B  CAP_A       I81
  C6D7     2      B  CAP_A       I72
  C6D8     2      B  CAP_A       I68
  C6D9     2      B  CAP_A       I145
  C6D10    2      B  CAP_A       I147
  C6F1     2      B  CAP_A       I25
  C6F2     2      B  CAP_A        I2
  C6F3     2      B  CAP_A        I7
  C6F4     2      B  CAPP        I180
  C6F5     2      B  CAP         I149
  C6F6     2      B  CAP         I122
  C6G1     2      B  CAP         I126
  C6G2     2      B  CAP         I128
  C6G3     2      B  CAP          I6
  C6G4     2      B  CAP         I131
  C6G5     2      B  CAP         I145
  C6L1     2      B  CAP_A       I178
  C6L2     2      B  CAP_A       I67
  C6L3     2      B  CAP         I24
  C6L4     2      B  CAP         I26
  C6L5     2      B  CAP         I26
  C6L6     2      B  CAP_A       I175
  C6L7     2      B  CAP_A       I59
  C6L8     2      B  CAPP        I210
  C6L10    2      B  CAP         I202
  C6L11    2      B  CAP_0402    I152
  C6M1     2      B  CAP_A       I177
  C6M2     2      B  CAP_A       I33
  C6M3     2      B  CAP         I203
  C6M5     2      B  CAP         I204
  C6M6     2      B  CAP_A       I250
  C6N1     2      B  CAPP        I12
  C6N2     2      B  CAP         I33
  C6N3     2      B  CAP         I34
  C6N4     2      B  CAPP        I14
  C6N5     2      B  CAPP        I109
  C6N6     2      B  CAP         I35
  C6N7     2      B  CAP_A        I5
  C6N8     2      B  CAP         I51
  C6N9     2      B  CAPP        I34
  C6N10    2      B  CAP         I37
  C6N11    2      B  CAP         I42
  C6P3     2      B  CAP_A       I25
  C6P4     2      B  CAP_A       I11
  C6P5     2      B  CAP_A       I14
  C6P6     2      B  CAP_A       I12
  C6P7     2      B  CAP         I59
  C6P8     2      B  CAPP        I32
  C6P9     2      B  CAP_A       I79
  C6P10    2      B  CAP_A       I13
  C6P11    2      B  CAP_A       I16
  C6P12    2      B  CAP_A       I15
  C6P13    2      B  CAP         I38
  C6P14    2      B  CAPP        I29
  C6P15    2      B  CAP         I58
  C6P16    2      B  CAP_A       I62
  C6P17    2      B  CAP         I38
  C6P18    2      B  CAPP        I30
  C6P19    2      B  CAP         I54
  C6P20    2      B  CAP         I57
  C6P21    2      B  CAP_A       I66
  C6P22    2      B  CAP         I49
  C6P23    2      B  CAPP        I28
  C6P24    2      B  CAP          I1
  C6R2     2      B  CAP_A       I70
  C6R3     2      B  CAPP        I16
  C6R4     2      B  CAP         I48
  C6R5     2      B  CAPP        I24
  C6R6     2      B  CAP          I2
  C6R7     2      B  CAP_A        I9
  C6R8     2      B  CAP         I83
  C6R9     2      B  CAPP        I18
  C6R10    2      B  CAP         I81
  C6R11    2      B  CAP         I37
  C6R12    2      B  CAPP        I21
  C6R13    2      B  CAP         I42
  C6R14    2      B  CAP         I80
  C6R16    2      B  CAPP        I62
  C6T1     2      B  CAP_A        I2
  C6T2     2      B  CAP         I54
  C6U2     2      B  CAP         I223
  C6U3     2      B  CAP         I221
  C6U4     2      B  CAP         I248
  C6U5     2      B  CAP_A       I242
  C6U7     2      B  CAP         I254
  C6U8     2      B  CAP         I255
  C6U9     2      B  CAP_A        I5
  C6U10    2      B  CAP         I65
  C6U11    2      B  CAP         I46
  C6U12    2      B  CAP         I49
  C6U13    2      B  CAP         I29
  C6U14    2      B  CAP         I25
  C6U15    2      B  CAP         I26
  C6U16    2      B  CAP         I22
  C6U17    2      B  CAP_A       I176
  C6U18    2      B  CAP         I52
  C7A5     2      B  CAP_A       I51
  C7A6     2      B  CAP_0402    I19
  C7A7     2      B  CAP_0402    I22
  C7A8     2      B  CAP_0402    I16
  C7A9     2      B  CAP_0402    I33
  C7A10    2      B  CAP_0402    I36
  C7A11    2      B  CAP_0402    I48
  C7A13    2      B  CAP         I63
  C7A14    2      B  CAP         I65
  C7A16    2      B  CAP_0402    I50
  C7A17    2      B  CAP_0402    I54
  C7A18    2      B  CAP_A       I53
  C7A19    2      B  CAPP        I175
  C7A20    2      B  CAP_A       I78
  C7A21    2      B  CAP_0402    I79
  C7A24    2      B  CAP_0402    I77
  C7A25    2      B  CAP_0402    I72
  C7A26    2      B  CAP_A       I73
  C7A27    2      B  CAPP        I75
  C7A29    2      B  CAP         I39
  C7A30    2      B  CAP          I9
  C7A31    2      B  CAP         I40
  C7A32    2      B  CAP         I38
  C7A33    2      B  CAP         I23
  C7A35    2      B  CAP         I55
  C7A36    2      B  CAP_A       I11
  C7A37    2      B  CAP_A       I29
  C7A38    2      B  CAP_A       I31
  C7A39    2      B  CAP_A       I20
  C7A40    2      B  CAP_A       I35
  C7A41    2      B  CAP_0402    I39
  C7A42    2      B  CAP         I46
  C7B1     2      B  CAP_A       I22
  C7B2     2      B  CAP_A       I23
  C7B3     2      B  CAP         I26
  C7B4     2      B  CAP         I24
  C7B5     2      B  CAP         I262
  C7B6     2      B  CAP_A       I252
  C7B7     2      B  CAP         I238
  C7B8     2      B  CAP         I202
  C7B12    2      B  CAP         I209
  C7B15    2      B  CAP_A        I1
  C7B16    2      B  CAP_A        I3
  C7B17    2      B  CAP_A       I18
  C7B18    2      B  CAP_A       I12
  C7B19    2      B  CAP_A        I2
  C7B20    2      B  CAP_A        I6
  C7B21    2      B  CAP_A        I4
  C7B22    2      B  CAP_A       I10
  C7B23    2      B  CAP_A        I7
  C7B24    2      B  CAP_A       I11
  C7C4     2      B  CAP         I50
  C7C5     2      B  CAP         I47
  C7C6     2      B  CAP_A       I23
  C7C7     2      B  CAP         I54
  C7C8     2      B  CAP         I51
  C7C9     2      B  CAP_A        I7
  C7C10    2      B  CAP_A       I77
  C7C11    2      B  CAP_A       I38
  C7C12    2      B  CAP_0402    I39
  C7C13    2      B  CAP         I56
  C7C15    2      B  CAP         I46
  C7C17    2      B  CAP_0402    I36
  C7C18    2      B  CAP_0402    I33
  C7C19    2      B  CAP_A       I14
  C7C20    2      B  CAP_A       I34
  C7D1     2      B  CAP_A       I136
  C7D2     2      B  CAP          I2
  C7D3     2      B  CAP_A       I38
  C7D4     2      B  CAP_0402    I79
  C7D5     2      B  CAP_A       I52
  C7E1     2      B  CAP_A       I23
  C7E2     2      B  CAP_A       I32
  C7E3     2      B  CAP_A       I92
  C7E4     2      B  CAP_A       I115
  C7E5     2      B  CAP_A       I52
  C7E6     2      B  CAP         I53
  C7E8     2      B  CAP         I50
  C7E9     2      B  CAP_A       I49
  C7E10    2      B  CAP         I14
  C7E11    2      B  CAP         I39
  C7E12    2      B  CAP         I47
  C7E13    2      B  CAP         I45
  C7E14    2      B  CAP_0402    I30
  C7F1     2      B  CAP_A       I131
  C7F2     2      B  CAP_A       I130
  C7F5     2      B  CAP         I209
  C7F6     2      B  CAP_A       I205
  C7F7     2      B  CAP         I151
  C7F11    2      B  CAP         I142
  C7F14    2      B  CAP         I305
  C7F15    2      B  CAP_A       I327
  C7F16    2      B  CAP_A       I325
  C7F17    2      B  CAP_A       I311
  C7F18    2      B  CAP_A       I309
  C7G1     2      B  CAP         I339
  C7G2     2      B  CAPP        I175
  C7G3     2      B  CAP         I320
  C7G27    2      B  CAP         I68
  C7G28    2      B  CAPP        I75
  C7G29    2      B  CAP_A       I51
  C7G30    2      B  CAP_0402    I79
  C7G33    2      B  CAP_0402    I50
  C7G34    2      B  CAP_0402    I54
  C7G35    2      B  CAP_A       I53
  C7G36    2      B  CAP_A       I78
  C7G37    2      B  CAP_0402    I48
  C7G40    2      B  CAP_0402    I77
  C7G41    2      B  CAP_0402    I72
  C7G42    2      B  CAP_A       I73
  C7L1     2      B  CAP         I92
  C7L2     2      B  CAP         I88
  C7L3     2      B  CAP         I87
  C7L4     2      B  CAP_A       I238
  C7L5     2      B  CAP_A       I225
  C7L6     2      B  CAP         I90
  C7L7     2      B  CAP         I89
  C7M1     2      B  CAP_A       I231
  C7M2     2      B  CAP_A       I232
  C7M3     2      B  CAP         I92
  C7M4     2      B  CAP         I91
  C7M5     2      B  CAP_A       I202
  C7M6     2      B  CAPP        I108
  C7P1     2      B  CAP         I105
  C7P2     2      B  CAP         I100
  C7P3     2      B  CAP         I52
  C7P4     2      B  CAP         I195
  C7P5     2      B  CAP         I182
  C7P6     2      B  CAP         I23
  C7P7     2      B  CAP         I27
  C7P8     2      B  CAP         I184
  C7P9     2      B  CAP         I181
  C7P10    2      B  CAP         I26
  C7P11    2      B  CAP         I183
  C7P12    2      B  CAP_A       I179
  C7P13    2      B  CAP         I25
  C7P14    2      B  CAP         I49
  C7P15    2      B  CAP         I45
  C7P16    2      B  CAP_A       I206
  C7P17    2      B  CAP         I29
  C7P18    2      B  CAP         I51
  C7P19    2      B  CAP         I215
  C7P20    2      B  CAP         I218
  C7R1     2      B  CAP_A       I65
  C7T1     2      B  CAP         I90
  C7T2     2      B  CAP         I112
  C7T3     2      B  CAP         I113
  C7T4     2      B  CAP_A       I235
  C7T5     2      B  CAP_A       I234
  C7U1     2      B  CAP_A       I237
  C7U2     2      B  CAP_A       I238
  C7U3     2      B  CAP         I136
  C7U4     2      B  CAP         I109
  C7U5     2      B  CAP         I111
  C7U6     2      B  CAP         I115
  C7U7     2      B  CAP         I91
  C8A3     2      B  CAP         I167
  C8A4     2      B  CAP         I31
  C8A6     2      B  CAP         I29
  C8A7     2      B  CAP_A       I143
  C8A8     2      B  CAP_A       I145
  C8A9     2      B  CAP         I218
  C8A10    2      B  CAP         I55
  C8A11    2      B  CAP          I5
  C8A12    2      B  CAP         I77
  C8A13    2      B  CAP         I37
  C8A14    2      B  CAP         I13
  C8A15    2      B  CAPP        I78
  C8B1     2      B  CAP_A       I41
  C8B2     2      B  CAP_A       I30
  C8B3     2      B  CAP_A       I32
  C8B4     2      B  CAP_A       I39
  C8B5     2      B  CAP_A       I37
  C8B6     2      B  CAP         I40
  C8B7     2      B  CAP_A       I41
  C8B8     2      B  CAP_A       I26
  C8B9     2      B  CAP_A       I14
  C8B10    2      B  CAP_A        I8
  C8B11    2      B  CAP_A       I15
  C8B12    2      B  CAP         I38
  C8B13    2      B  CAP_A       I20
  C8B14    2      B  CAP_A       I16
  C8B15    2      B  CAP         I24
  C8B16    2      B  CAP         I22
  C8C1     2      B  CAP         I79
  C8C2     2      B  CAP         I77
  C8C3     2      B  CAP         I19
  C8C4     2      B  CAP         I20
  C8C5     2      B  CAP         I21
  C8C6     2      B  CAP         I22
  C8D1     2      B  CAP_A       I376
  C8D2     2      B  CAP_A       I33
  C8D3     2      B  CAP         I42
  C8D4     2      B  CAP_A       I105
  C8E1     2      B  CAP_A       I253
  C8E2     2      B  CAP_A       I40
  C8E3     2      B  CAP_A       I94
  C8E4     2      B  CAPP         I8
  C8E5     2      B  CAP_A       I20
  C8E7     2      B  CAP          I3
  C8E8     2      B  CAP_A       I128
  C8E9     2      B  CAP          I2
  C8E10    2      B  CAP         I137
  C8E11    2      B  CAP         I135
  C8E14    2      B  CAP_0402    I139
  C8E18    2      B  CAP_A       I14
  C8E19    2      B  CAP_A       I28
  C8F2     2      B  CAP         I116
  C8F4     2      B  CAP_A       I30
  C8F5     2      B  CAP_A       I28
  C8F8     2      B  CAPP        I155
  C8F9     2      B  CAP_A       I161
  C8F10    2      B  CAP         I159
  C8F14    2      B  CAPP        I154
  C8F16    2      B  CAP_A       I275
  C8F17    2      B  CAP_A       I24
  C8F18    2      B  CAP         I49
  C8F19    2      B  CAP         I53
  C8L1     2      B  CAP         I110
  C8L2     2      B  CAP         I83
  C8L3     2      B  CAP_A       I48
  C8L4     2      B  CAP_A       I49
  C8L5     2      B  CAP_A       I241
  C8L6     2      B  CAP_A       I240
  C8L7     2      B  CAP_A       I239
  C8L8     2      B  CAP_A       I237
  C8L9     2      B  CAP_A       I236
  C8L10    2      B  CAP_A       I229
  C8L11    2      B  CAP         I88
  C8L12    2      B  CAP_A       I201
  C8M1     2      B  CAP_A       I243
  C8M2     2      B  CAP_A       I206
  C8M3     2      B  CAP_A       I227
  C8M4     2      B  CAP_A       I233
  C8M5     2      B  CAP_A       I228
  C8M6     2      B  CAP_A       I235
  C8M7     2      B  CAP         I90
  C8M8     2      B  CAP_A       I198
  C8M9     2      B  CAP_A       I205
  C8M10    2      B  CAP_A       I203
  C8M11    2      B  CAP         I91
  C8M12    2      B  CAP_A       I47
  C8P1     2      B  CAP         I185
  C8P2     2      B  CAP         I183
  C8P3     2      B  CAP         I101
  C8P4     2      B  CAP         I88
  C8P5     2      B  CAP         I58
  C8P6     2      B  CAP         I55
  C8P7     2      B  CAP         I50
  C8P8     2      B  CAP         I213
  C8P9     2      B  CAP         I214
  C8P10    2      B  CAP         I127
  C8P11    2      B  CAP         I139
  C8P12    2      B  CAP         I107
  C8P13    2      B  CAP         I132
  C8P14    2      B  CAP         I211
  C8P15    2      B  CAP         I212
  C8P16    2      B  CAP         I129
  C8P17    2      B  CAP         I133
  C8P18    2      B  CAP         I92
  C8P19    2      B  CAP         I103
  C8P20    2      B  CAP         I89
  C8P21    2      B  CAP         I135
  C8P22    2      B  CAP         I28
  C8P23    2      B  CAP         I48
  C8P24    2      B  CAP         I217
  C8P25    2      B  CAP         I136
  C8P26    2      B  CAP         I118
  C8P27    2      B  CAP         I141
  C8P28    2      B  CAP         I137
  C8P29    2      B  CAP         I125
  C8P30    2      B  CAP         I184
  C8P31    2      B  CAP         I178
  C8P32    2      B  CAP         I216
  C8P33    2      B  CAP         I131
  C8P34    2      B  CAP         I106
  C8T1     2      B  CAP_A       I202
  C8T2     2      B  CAP_A       I198
  C8T3     2      B  CAP_A       I48
  C8T4     2      B  CAP_A       I196
  C8T5     2      B  CAP_A       I233
  C8T6     2      B  CAP_A       I231
  C8T7     2      B  CAP_A       I230
  C8T8     2      B  CAP_A       I229
  C8T9     2      B  CAP_A       I227
  C8T10    2      B  CAP_A       I226
  C8T11    2      B  CAP_A       I204
  C8U1     2      B  CAP         I82
  C8U2     2      B  CAP_A       I239
  C8U3     2      B  CAP_A       I236
  C8U4     2      B  CAP_A       I225
  C8U5     2      B  CAP_A       I228
  C8U6     2      B  CAP_A       I232
  C8U7     2      B  CAP_A       I241
  C8U8     2      B  CAP         I83
  C8U9     2      B  CAP_A       I203
  C8U10    2      B  CAP_A       I49
  C8U11    2      B  CAP         I89
  C8U12    2      B  CAP         I88
  C8U13    2      B  CAP_A       I199
  C9A1     2      B  CAP_A       I127
  C9A2     2      B  CAP_A       I10
  C9A3     2      B  CAP_A       I40
  C9A4     2      B  CAP_A       I59
  C9A5     2      B  CAP_A       I12
  C9A6     2      B  CAP_A       I25
  C9B1     2      B  CAP         I39
  C9B2     2      B  CAP         I36
  C9B7     2      B  CAP_A       I39
  C9B8     2      B  CAPP        I113
  C9B9     2      B  CAP_A       I347
  C9B10    2      B  CAP_A       I345
  C9E1     2      B  CAP_A       I163
  C9E6     2      B  CAP         I155
  C9E8     2      B  CAP         I111
  C9E9     2      B  CAP         I112
  C9E10    2      B  CAP         I23
  C9E11    2      B  CAP_0402    I39
  C9E12    2      B  CAP_A       I241
  C9F1     2      B  CAP         I134
  C9F2     2      B  CAP         I140
  C9F3     2      B  CAP          I7
  C9F4     2      B  CAP         I30
  C9F5     2      B  CAP_A       I71
  C9F6     2      B  CAP         I30
  C9F8     2      B  CAP         I19
  C9F9     2      B  CAP          I5
  C9F10    2      B  CAP          I4
  C9F11    2      B  CAP_A       I90
  C9F12    2      B  CAP_A       I106
  C9F13    2      B  CAP          I7
  C9F14    2      B  CAP_A       I105
  C9F15    2      B  CAP_A       I160
  C9F18    2      B  CAP         I104
  C9F19    2      B  CAP_A        I7
  C9F20    2      B  CAP         I20
  C9F21    2      B  CAP         I21
  C9F22    2      B  CAP         I60
  C9F23    2      B  CAP_A       I258
  C9G1     2      B  CAP         I58
  C9G2     2      B  CAP         I36
  C9G3     2      B  CAP         I59
  C9G4     2      B  CAP_A       I46
  C9G5     2      B  CAP_0402    I48
  C9G6     2      B  CAP_A       I47
  C9G7     2      B  CAP_A       I33
  C9G10    1      A  CAP_A       I79
  C9G14    2      B  CAP         I146
  C9G15    2      B  CAP         I139
  C9G17    2      B  CAP         I80
  C9G18    2      B  CAP         I153
  C9G19    2      B  CAP_A       I61
  C9G20    2      B  CAP         I86
  C9G21    2      B  CAP         I68
  C9G22    2      B  CAP         I108
  C9L1     2      B  CAP_A       I177
  C9L2     2      B  CAPP        I78
  C9L3     2      B  CAP_A       I46
  C9L4     2      B  CAPP        I77
  C9L5     2      B  CAP         I80
  C9L6     2      B  CAP         I47
  C9L7     2      B  CAP_A       I181
  C9L8     2      B  CAP_A       I30
  C9L9     2      B  CAPP        I75
  C9L10    2      B  CAP         I46
  C9L11    2      B  CAP         I45
  C9L12    2      B  CAPP        I76
  C9L13    2      B  CAP         I81
  C9L14    2      B  CAP         I84
  C9M1     2      B  CAP_A        I4
  C9M2     2      B  CAP_A       I15
  C9M3     2      B  CAPP        I99
  C9M4     2      B  CAP         I27
  C9M5     2      B  CAP_A       I26
  C9M6     2      B  CAP_A       I67
  C9M7     2      B  CAP_A       I12
  C9M8     2      B  CAP_A       I10
  C9M9     2      B  CAP_A       I76
  C9M10    2      B  CAP         I74
  C9M11    2      B  CAP_A       I92
  C9N11    2      B  CAPP        I12
  C9N13    2      B  CAP         I35
  C9N19    2      B  CAP         I36
  C9N20    2      B  CAPP        I14
  C9N21    2      B  CAP         I38
  C9N22    2      B  CAP_A       I44
  C9N24    2      B  CAPP        I24
  C9N25    2      B  CAP          I8
  C9N26    2      B  CAP          I7
  C9N27    2      B  CAP          I5
  C9P1     2      B  CAP         I59
  C9P2     2      B  CAP         I60
  C9P3     2      B  CAP_A       I59
  C9P4     2      B  CAP         I53
  C9P5     2      B  CAPP        I14
  C9P7     2      B  CAP         I54
  C9P8     2      B  CAPP        I12
  C9P9     2      B  CAP         I55
  C9P10    2      B  CAP_A       I66
  C9P11    2      B  CAP_A       I201
  C9P18    2      B  CAPP        I30
  C9P20    2      B  CAP_A       I55
  C9P22    2      B  CAP         I50
  C9P23    2      B  CAPP        I28
  C9P24    2      B  CAP         I58
  C9P25    2      B  CAP         I51
  C9P26    2      B  CAP         I54
  C9R2     2      B  CAP_A       I67
  C9R3     2      B  CAPP        I26
  C9R5     2      B  CAP         I31
  C9R6     2      B  CAP_A       I37
  C9R7     2      B  CAP         I43
  C9R8     2      B  CAP_A        I8
  C9R9     2      B  CAPP        I25
  C9R10    2      B  CAP         I44
  C9R11    2      B  CAP         I48
  C9R12    2      B  CAP_A       I36
  C9R13    2      B  CAP_A       I42
  C9R14    2      B  CAP_A       I41
  C9T1     2      B  CAP_A       I137
  C9T3     2      B  CAPP        I111
  C9T4     2      B  CAP         I47
  C9T5     2      B  CAPP        I75
  C9T6     2      B  CAP         I81
  C9T7     2      B  CAP_A        I2
  C9T8     2      B  CAP         I70
  C9T9     2      B  CAP         I84
  C9U2     2      B  CAPP        I76
  C9U3     2      B  CAP         I80
  C9U4     2      B  CAP         I46
  C9U5     2      B  CAPP        I78
  C9U6     2      B  CAP         I45
  C9U7     2      B  CAP_A       I178
  C9U8     2      B  CAP         I76
  C9U9     2      B  CAPP        I77
  C9U10    2      B  CAP_A       I178
  C9U11    2      B  CAP         I73
  C9U12    2      B  CAP_A       I92
  CR1F5    2      A  DIODE_SM    I220
  CR1M1    3  GND<0>  DIODEAC_DUAL_ARRAY_SM9  I52
  CR1M2    3  GND<0>  DIODEAC_DUAL_ARRAY_SM9  I98
  CTI1     2      B  CAP_A       I70
  CTI2     2      B  CAP         I78
  CTI4     2      B  CAP         I85
  CTI6     2      B  CAP_A       I81
  CTI7     2      B  CAP_A       I109
  CTI8     2      B  CAP         I114
  CTI10    2      B  CAP         I119
  CTI12    2      B  CAP_A       I122
  CTI13    2      B  CAP_A       I62
  CTI15    2      B  CAP         I67
  CTI16    2      B  CAP_A       I80
  CTI17    2      B  CAP         I82
  CTI19    2      B  CAP         I90
  CTI21    2      B  CAP_A       I87
  CTI22    2      B  CAP         I74
  CTI24    2      B  CAP_A       I71
  CTI25    2      B  CAP_A       I81
  CTI26    2      B  CAP         I82
  CTI28    2      B  CAP         I122
  CTI30    2      B  CAP_A       I117
  CTI31    2      B  CAP_A       I124
  CTI32    2      B  CAP         I130
  CTI34    2      B  CAP         I88
  CTI36    2      B  CAP_A       I85
  CTI37    2      B  CAP         I99
  CTI39    2      B  CAP_A       I96
  CTI40    2      B  CAP_A       I93
  CTI42    2      B  CAP         I108
  CTI43    2      B  CAP         I124
  CTI45    2      B  CAP_A       I116
  CTI46    2      B  CAP_A       I113
  CTI48    2      B  CAP         I119
  CTI49    2      B  CAP         I118
  CTI51    2      B  CAP_A       I108
  CTI52    2      B  CAP_A       I111
  CTI54    2      B  CAP         I121
  CTI55    2      B  CAP         I60
  CTI57    2      B  CAP_A       I55
  CTI58    2      B  CAP         I65
  CTI60    2      B  CAP_A       I69
  CTI61    2      B  CAP         I134
  CTI63    2      B  CAP_A       I137
  CTI64    2      B  CAP         I136
  CTI66    2      B  CAP_A       I127
  CTI67    2      B  CAP_A       I124
  CTI69    2      B  CAP         I134
  CTI70    2      B  CAP_A       I106
  CTI71    2      B  CAP         I109
  DS9A6    2      C  LED_A1LF    I31
  EU1A1    2   LGND  IR354XX_SM  I102
  EU1A1    5  PGND<0>  IR354XX_SM  I102
  EU1A1    7  PGND<1>  IR354XX_SM  I102
  EU1A1   40  PGND<2>  IR354XX_SM  I102
  EU1A2    2   LGND  IR354XX_SM  I101
  EU1A2    5  PGND<0>  IR354XX_SM  I101
  EU1A2    7  PGND<1>  IR354XX_SM  I101
  EU1A2   40  PGND<2>  IR354XX_SM  I101
  EU1B1   27    GND  PXM1310B_QFN  I90
  EU1B1   32  BISEN1  PXM1310B_QFN  I90
  EU1B1   41  THPAD  PXM1310B_QFN  I90
  EU1C1    2   LGND  IR354XX_SM  I51
  EU1C1    5  PGND<0>  IR354XX_SM  I51
  EU1C1    7  PGND<1>  IR354XX_SM  I51
  EU1C1   40  PGND<2>  IR354XX_SM  I51
  EU1C2   49  THPAD  PXE1610B_QFN  I130
  EU1C3    2   LGND  IR354XX_SM  I56
  EU1C3    5  PGND<0>  IR354XX_SM  I56
  EU1C3    7  PGND<1>  IR354XX_SM  I56
  EU1C3   40  PGND<2>  IR354XX_SM  I56
  EU1D1    2   LGND  IR354XX_SM  I71
  EU1D1    5  PGND<0>  IR354XX_SM  I71
  EU1D1    7  PGND<1>  IR354XX_SM  I71
  EU1D1   40  PGND<2>  IR354XX_SM  I71
  EU1D2   23   PGND  ADM1278_SM  I10
  EU1D3    2   LGND  IR354XX_SM  I27
  EU1D3    5  PGND<0>  IR354XX_SM  I27
  EU1D3    7  PGND<1>  IR354XX_SM  I27
  EU1D3   40  PGND<2>  IR354XX_SM  I27
  EU1D4    2   LGND  IR354XX_SM  I24
  EU1D4    5  PGND<0>  IR354XX_SM  I24
  EU1D4    7  PGND<1>  IR354XX_SM  I24
  EU1D4   40  PGND<2>  IR354XX_SM  I24
  EU1E2    2   LGND  IR354XX_SM  I20
  EU1E2    5  PGND<0>  IR354XX_SM  I20
  EU1E2    7  PGND<1>  IR354XX_SM  I20
  EU1E2   40  PGND<2>  IR354XX_SM  I20
  EU1F1    2   LGND  IR354XX_SM  I111
  EU1F1    5  PGND<0>  IR354XX_SM  I111
  EU1F1    7  PGND<1>  IR354XX_SM  I111
  EU1F1   40  PGND<2>  IR354XX_SM  I111
  EU1G1    2   LGND  IR354XX_SM  I110
  EU1G1    5  PGND<0>  IR354XX_SM  I110
  EU1G1    7  PGND<1>  IR354XX_SM  I110
  EU1G1   40  PGND<2>  IR354XX_SM  I110
  EU1G2   27    GND  PXM1310B_QFN  I90
  EU1G2   32  BISEN1  PXM1310B_QFN  I90
  EU1G2   41  THPAD  PXM1310B_QFN  I90
  EU2T1    4    GND  SLG55021_SM   I1
  EU2T1    9  THPAD  SLG55021_SM   I1
  EU3P1   23  GND<1>  PXE1110B_QFN  I93
  EU3P1   26  BISEN1  PXE1110B_QFN  I93
  EU3P1   27  GND<0>  PXE1110B_QFN  I93
  EU3P1   41  THPAD  PXE1110B_QFN  I93
  EU4A1    3   AGND  MIC5166_DFN  I31
  EU4A1    8   PGND  MIC5166_DFN  I31
  EU4A1   11  THPAD  MIC5166_DFN  I31
  EU4A2    3   AGND  MIC5166_DFN  I31
  EU4A2    8   PGND  MIC5166_DFN  I31
  EU4A2   11  THPAD  MIC5166_DFN  I31
  EU4A3   16  PGND<0>  NCP3232L_SM  I184
  EU4A3   17  PGND<1>  NCP3232L_SM  I184
  EU4A3   18  PGND<2>  NCP3232L_SM  I184
  EU4A3   19  PGND<3>  NCP3232L_SM  I184
  EU4A3   20  PGND<4>  NCP3232L_SM  I184
  EU4A3   21  PGND<5>  NCP3232L_SM  I184
  EU4A3   22  PGND<6>  NCP3232L_SM  I184
  EU4A3   23  PGND<7>  NCP3232L_SM  I184
  EU4A3   24  PGND<8>  NCP3232L_SM  I184
  EU4A3   25  PGND<9>  NCP3232L_SM  I184
  EU4A3   26  PGND<10>  NCP3232L_SM  I184
  EU4A3   27  PGND<11>  NCP3232L_SM  I184
  EU4A3   28  PGND<12>  NCP3232L_SM  I184
  EU4A3   37  PGND<13>  NCP3232L_SM  I184
  EU4A3   41    GND  NCP3232L_SM  I184
  EU4C1    2   LGND  IR354XX_SM  I46
  EU4C1    5  PGND<0>  IR354XX_SM  I46
  EU4C1    7  PGND<1>  IR354XX_SM  I46
  EU4C1   40  PGND<2>  IR354XX_SM  I46
  EU4C2    2   LGND  IR354XX_SM  I71
  EU4C2    5  PGND<0>  IR354XX_SM  I71
  EU4C2    7  PGND<1>  IR354XX_SM  I71
  EU4C2   40  PGND<2>  IR354XX_SM  I71
  EU4D1    2   LGND  IR354XX_SM  I71
  EU4D1    5  PGND<0>  IR354XX_SM  I71
  EU4D1    7  PGND<1>  IR354XX_SM  I71
  EU4D1   40  PGND<2>  IR354XX_SM  I71
  EU4D2    2   GNDA  NB3W1200L_LCC   I1
  EU4D2    7  GND<0>  NB3W1200L_LCC   I1
  EU4D2   23  GND<1>  NB3W1200L_LCC   I1
  EU4D2   33  GND<2>  NB3W1200L_LCC   I1
  EU4D2   41  GND<3>  NB3W1200L_LCC   I1
  EU4D2   48  GND<4>  NB3W1200L_LCC   I1
  EU4D2   58  GND<5>  NB3W1200L_LCC   I1
  EU4D2   65  THPAD  NB3W1200L_LCC   I1
  EU4D3    2   LGND  IR354XX_SM  I70
  EU4D3    5  PGND<0>  IR354XX_SM  I70
  EU4D3    7  PGND<1>  IR354XX_SM  I70
  EU4D3   40  PGND<2>  IR354XX_SM  I70
  EU4D4   49  THPAD  PXE1610B_QFN  I155
  EU4D5   23  GND<1>  PXE1110B_QFN  I96
  EU4D5   26  BISEN1  PXE1110B_QFN  I96
  EU4D5   27  GND<0>  PXE1110B_QFN  I96
  EU4D5   41  THPAD  PXE1110B_QFN  I96
  EU4D6    2   LGND  IR354XX_SM  I64
  EU4D6    5  PGND<0>  IR354XX_SM  I64
  EU4D6    7  PGND<1>  IR354XX_SM  I64
  EU4D6   40  PGND<2>  IR354XX_SM  I64
  EU4E1    2   LGND  IR354XX_SM  I63
  EU4E1    5  PGND<0>  IR354XX_SM  I63
  EU4E1    7  PGND<1>  IR354XX_SM  I63
  EU4E1   40  PGND<2>  IR354XX_SM  I63
  EU4E2    2   LGND  IR354XX_SM  I126
  EU4E2    5  PGND<0>  IR354XX_SM  I126
  EU4E2    7  PGND<1>  IR354XX_SM  I126
  EU4E2   40  PGND<2>  IR354XX_SM  I126
  EU4G1   16  PGND<0>  NCP3232L_SM  I225
  EU4G1   17  PGND<1>  NCP3232L_SM  I225
  EU4G1   18  PGND<2>  NCP3232L_SM  I225
  EU4G1   19  PGND<3>  NCP3232L_SM  I225
  EU4G1   20  PGND<4>  NCP3232L_SM  I225
  EU4G1   21  PGND<5>  NCP3232L_SM  I225
  EU4G1   22  PGND<6>  NCP3232L_SM  I225
  EU4G1   23  PGND<7>  NCP3232L_SM  I225
  EU4G1   24  PGND<8>  NCP3232L_SM  I225
  EU4G1   25  PGND<9>  NCP3232L_SM  I225
  EU4G1   26  PGND<10>  NCP3232L_SM  I225
  EU4G1   27  PGND<11>  NCP3232L_SM  I225
  EU4G1   28  PGND<12>  NCP3232L_SM  I225
  EU4G1   37  PGND<13>  NCP3232L_SM  I225
  EU4G1   41    GND  NCP3232L_SM  I225
  EU4G2    3   AGND  MIC5166_DFN  I24
  EU4G2    8   PGND  MIC5166_DFN  I24
  EU4G2   11  THPAD  MIC5166_DFN  I24
  EU4G3    3   AGND  MIC5166_DFN   I1
  EU4G3    8   PGND  MIC5166_DFN   I1
  EU4G3   11  THPAD  MIC5166_DFN   I1
  EU7A1    2   LGND  IR354XX_SM  I106
  EU7A1    5  PGND<0>  IR354XX_SM  I106
  EU7A1    7  PGND<1>  IR354XX_SM  I106
  EU7A1   40  PGND<2>  IR354XX_SM  I106
  EU7A2    2   LGND  IR354XX_SM  I117
  EU7A2    5  PGND<0>  IR354XX_SM  I117
  EU7A2    7  PGND<1>  IR354XX_SM  I117
  EU7A2   40  PGND<2>  IR354XX_SM  I117
  EU7A3    2   LGND  IR354XX_SM  I116
  EU7A3    5  PGND<0>  IR354XX_SM  I116
  EU7A3    7  PGND<1>  IR354XX_SM  I116
  EU7A3   40  PGND<2>  IR354XX_SM  I116
  EU7A4    2   LGND  IR354XX_SM  I107
  EU7A4    5  PGND<0>  IR354XX_SM  I107
  EU7A4    7  PGND<1>  IR354XX_SM  I107
  EU7A4   40  PGND<2>  IR354XX_SM  I107
  EU7A5   27    GND  PXM1310B_QFN  I75
  EU7A5   32  BISEN1  PXM1310B_QFN  I75
  EU7A5   41  THPAD  PXM1310B_QFN  I75
  EU7B1   16  PGND<0>  NCP3232L_SM  I214
  EU7B1   17  PGND<1>  NCP3232L_SM  I214
  EU7B1   18  PGND<2>  NCP3232L_SM  I214
  EU7B1   19  PGND<3>  NCP3232L_SM  I214
  EU7B1   20  PGND<4>  NCP3232L_SM  I214
  EU7B1   21  PGND<5>  NCP3232L_SM  I214
  EU7B1   22  PGND<6>  NCP3232L_SM  I214
  EU7B1   23  PGND<7>  NCP3232L_SM  I214
  EU7B1   24  PGND<8>  NCP3232L_SM  I214
  EU7B1   25  PGND<9>  NCP3232L_SM  I214
  EU7B1   26  PGND<10>  NCP3232L_SM  I214
  EU7B1   27  PGND<11>  NCP3232L_SM  I214
  EU7B1   28  PGND<12>  NCP3232L_SM  I214
  EU7B1   37  PGND<13>  NCP3232L_SM  I214
  EU7B1   41    GND  NCP3232L_SM  I214
  EU7C1    2   LGND  IR354XX_SM  I101
  EU7C1    5  PGND<0>  IR354XX_SM  I101
  EU7C1    7  PGND<1>  IR354XX_SM  I101
  EU7C1   40  PGND<2>  IR354XX_SM  I101
  EU7E1    4    GND  SLG55021_SM  I19
  EU7E1    9  THPAD  SLG55021_SM  I19
  EU7E2    2  GND<0>  TPS54821_LCC  I83
  EU7E2    3  GND<1>  TPS54821_LCC  I83
  EU7E2   15  THPAD  TPS54821_LCC  I83
  EU7F1   16  PGND<0>  NCP3232L_SM  I193
  EU7F1   17  PGND<1>  NCP3232L_SM  I193
  EU7F1   18  PGND<2>  NCP3232L_SM  I193
  EU7F1   19  PGND<3>  NCP3232L_SM  I193
  EU7F1   20  PGND<4>  NCP3232L_SM  I193
  EU7F1   21  PGND<5>  NCP3232L_SM  I193
  EU7F1   22  PGND<6>  NCP3232L_SM  I193
  EU7F1   23  PGND<7>  NCP3232L_SM  I193
  EU7F1   24  PGND<8>  NCP3232L_SM  I193
  EU7F1   25  PGND<9>  NCP3232L_SM  I193
  EU7F1   26  PGND<10>  NCP3232L_SM  I193
  EU7F1   27  PGND<11>  NCP3232L_SM  I193
  EU7F1   28  PGND<12>  NCP3232L_SM  I193
  EU7F1   37  PGND<13>  NCP3232L_SM  I193
  EU7F1   41    GND  NCP3232L_SM  I193
  EU7G1   27    GND  PXM1310B_QFN  I358
  EU7G1   32  BISEN1  PXM1310B_QFN  I358
  EU7G1   41  THPAD  PXM1310B_QFN  I358
  EU7G2    2   LGND  IR354XX_SM  I102
  EU7G2    5  PGND<0>  IR354XX_SM  I102
  EU7G2    7  PGND<1>  IR354XX_SM  I102
  EU7G2   40  PGND<2>  IR354XX_SM  I102
  EU7G3    2   LGND  IR354XX_SM  I103
  EU7G3    5  PGND<0>  IR354XX_SM  I103
  EU7G3    7  PGND<1>  IR354XX_SM  I103
  EU7G3   40  PGND<2>  IR354XX_SM  I103
  EU8A1   23  GND<1>  PXE1110B_QFN  I229
  EU8A1   27  GND<0>  PXE1110B_QFN  I229
  EU8A1   41  THPAD  PXE1110B_QFN  I229
  EU8A2   11    GND  RT9059_DFN  I86
  EU8B1    4    GND  SLG55021_SM  I13
  EU8B1    9  THPAD  SLG55021_SM  I13
  EU8E1    3   PGND  CSD87384M_SM  I170
  EU8F2    1  GND<0>  ICS9FGP204_MLFP  I34
  EU8F2   10  GNDCPU  ICS9FGP204_MLFP  I34
  EU8F2   14  GND32K  ICS9FGP204_MLFP  I34
  EU8F2   18  GNDREF  ICS9FGP204_MLFP  I34
  EU8F2   21  GND33  ICS9FGP204_MLFP  I34
  EU8F2   27  GNDRMII<0>  ICS9FGP204_MLFP  I34
  EU8F2   30  GNDRMII<1>  ICS9FGP204_MLFP  I34
  EU8F2   35  GND_RGMII  ICS9FGP204_MLFP  I34
  EU8F2   41  GND<1>  ICS9FGP204_MLFP  I34
  EU9E1   65    GND  SPRINGVILLE_SM1  I72
  EU9F1   11    GND  RT9059_DFN  I40
  EU9F2   11    GND  RT9059_DFN  I70
  EU9F3   12    GND  PI7C9X1172_QFN   I1
  EU9F3   16  CTSB_N  PI7C9X1172_QFN   I1
  EU9F3   25  CTSA_N  PI7C9X1172_QFN   I1
  EU9F3   33  THPAD  PI7C9X1172_QFN   I1
  EU9G1    4    GND  ADC128D818_SM  I52
  EU9M1    4    GND  SLG55021_SM  I69
  EU9M1    9  THPAD  SLG55021_SM  I69
  J1A1     2  VSS<93>  SCONN288_H44441004_PIP  I185
  J1A1     4  VSS<92>  SCONN288_H44441004_PIP  I185
  J1A1     6  VSS<91>  SCONN288_H44441004_PIP  I185
  J1A1     9  VSS<90>  SCONN288_H44441004_PIP  I185
  J1A1    11  VSS<89>  SCONN288_H44441004_PIP  I185
  J1A1    13  VSS<88>  SCONN288_H44441004_PIP  I185
  J1A1    15  VSS<87>  SCONN288_H44441004_PIP  I185
  J1A1    17  VSS<86>  SCONN288_H44441004_PIP  I185
  J1A1    20  VSS<85>  SCONN288_H44441004_PIP  I185
  J1A1    22  VSS<84>  SCONN288_H44441004_PIP  I185
  J1A1    24  VSS<83>  SCONN288_H44441004_PIP  I185
  J1A1    26  VSS<82>  SCONN288_H44441004_PIP  I185
  J1A1    28  VSS<81>  SCONN288_H44441004_PIP  I185
  J1A1    31  VSS<80>  SCONN288_H44441004_PIP  I185
  J1A1    33  VSS<79>  SCONN288_H44441004_PIP  I185
  J1A1    35  VSS<78>  SCONN288_H44441004_PIP  I185
  J1A1    37  VSS<77>  SCONN288_H44441004_PIP  I185
  J1A1    39  VSS<76>  SCONN288_H44441004_PIP  I185
  J1A1    42  VSS<75>  SCONN288_H44441004_PIP  I185
  J1A1    44  VSS<74>  SCONN288_H44441004_PIP  I185
  J1A1    46  VSS<73>  SCONN288_H44441004_PIP  I185
  J1A1    48  VSS<72>  SCONN288_H44441004_PIP  I185
  J1A1    50  VSS<71>  SCONN288_H44441004_PIP  I185
  J1A1    53  VSS<70>  SCONN288_H44441004_PIP  I185
  J1A1    55  VSS<69>  SCONN288_H44441004_PIP  I185
  J1A1    57  VSS<68>  SCONN288_H44441004_PIP  I185
  J1A1    94  VSS<67>  SCONN288_H44441004_PIP  I185
  J1A1    96  VSS<66>  SCONN288_H44441004_PIP  I185
  J1A1    98  VSS<65>  SCONN288_H44441004_PIP  I185
  J1A1   101  VSS<64>  SCONN288_H44441004_PIP  I185
  J1A1   103  VSS<63>  SCONN288_H44441004_PIP  I185
  J1A1   105  VSS<62>  SCONN288_H44441004_PIP  I185
  J1A1   107  VSS<61>  SCONN288_H44441004_PIP  I185
  J1A1   109  VSS<60>  SCONN288_H44441004_PIP  I185
  J1A1   112  VSS<59>  SCONN288_H44441004_PIP  I185
  J1A1   114  VSS<58>  SCONN288_H44441004_PIP  I185
  J1A1   116  VSS<57>  SCONN288_H44441004_PIP  I185
  J1A1   118  VSS<56>  SCONN288_H44441004_PIP  I185
  J1A1   120  VSS<55>  SCONN288_H44441004_PIP  I185
  J1A1   123  VSS<54>  SCONN288_H44441004_PIP  I185
  J1A1   125  VSS<53>  SCONN288_H44441004_PIP  I185
  J1A1   127  VSS<52>  SCONN288_H44441004_PIP  I185
  J1A1   129  VSS<51>  SCONN288_H44441004_PIP  I185
  J1A1   131  VSS<50>  SCONN288_H44441004_PIP  I185
  J1A1   134  VSS<49>  SCONN288_H44441004_PIP  I185
  J1A1   136  VSS<48>  SCONN288_H44441004_PIP  I185
  J1A1   138  VSS<47>  SCONN288_H44441004_PIP  I185
  J1A1   139  SA<0>  SCONN288_H44441004_PIP  I186
  J1A1   140  SA<1>  SCONN288_H44441004_PIP  I186
  J1A1   147  VSS<46>  SCONN288_H44441004_PIP  I185
  J1A1   149  VSS<45>  SCONN288_H44441004_PIP  I185
  J1A1   151  VSS<44>  SCONN288_H44441004_PIP  I185
  J1A1   154  VSS<43>  SCONN288_H44441004_PIP  I185
  J1A1   156  VSS<42>  SCONN288_H44441004_PIP  I185
  J1A1   158  VSS<41>  SCONN288_H44441004_PIP  I185
  J1A1   160  VSS<40>  SCONN288_H44441004_PIP  I185
  J1A1   162  VSS<39>  SCONN288_H44441004_PIP  I185
  J1A1   165  VSS<38>  SCONN288_H44441004_PIP  I185
  J1A1   167  VSS<37>  SCONN288_H44441004_PIP  I185
  J1A1   169  VSS<36>  SCONN288_H44441004_PIP  I185
  J1A1   171  VSS<35>  SCONN288_H44441004_PIP  I185
  J1A1   173  VSS<34>  SCONN288_H44441004_PIP  I185
  J1A1   176  VSS<33>  SCONN288_H44441004_PIP  I185
  J1A1   178  VSS<32>  SCONN288_H44441004_PIP  I185
  J1A1   180  VSS<31>  SCONN288_H44441004_PIP  I185
  J1A1   182  VSS<30>  SCONN288_H44441004_PIP  I185
  J1A1   184  VSS<29>  SCONN288_H44441004_PIP  I185
  J1A1   187  VSS<28>  SCONN288_H44441004_PIP  I185
  J1A1   189  VSS<27>  SCONN288_H44441004_PIP  I185
  J1A1   191  VSS<26>  SCONN288_H44441004_PIP  I185
  J1A1   193  VSS<25>  SCONN288_H44441004_PIP  I185
  J1A1   195  VSS<24>  SCONN288_H44441004_PIP  I185
  J1A1   198  VSS<23>  SCONN288_H44441004_PIP  I185
  J1A1   200  VSS<22>  SCONN288_H44441004_PIP  I185
  J1A1   202  VSS<21>  SCONN288_H44441004_PIP  I185
  J1A1   239  VSS<20>  SCONN288_H44441004_PIP  I185
  J1A1   241  VSS<19>  SCONN288_H44441004_PIP  I185
  J1A1   243  VSS<18>  SCONN288_H44441004_PIP  I185
  J1A1   246  VSS<17>  SCONN288_H44441004_PIP  I185
  J1A1   248  VSS<16>  SCONN288_H44441004_PIP  I185
  J1A1   250  VSS<15>  SCONN288_H44441004_PIP  I185
  J1A1   252  VSS<14>  SCONN288_H44441004_PIP  I185
  J1A1   254  VSS<13>  SCONN288_H44441004_PIP  I185
  J1A1   257  VSS<12>  SCONN288_H44441004_PIP  I185
  J1A1   259  VSS<11>  SCONN288_H44441004_PIP  I185
  J1A1   261  VSS<10>  SCONN288_H44441004_PIP  I185
  J1A1   263  VSS<9>  SCONN288_H44441004_PIP  I185
  J1A1   265  VSS<8>  SCONN288_H44441004_PIP  I185
  J1A1   268  VSS<7>  SCONN288_H44441004_PIP  I185
  J1A1   270  VSS<6>  SCONN288_H44441004_PIP  I185
  J1A1   272  VSS<5>  SCONN288_H44441004_PIP  I185
  J1A1   274  VSS<4>  SCONN288_H44441004_PIP  I185
  J1A1   276  VSS<3>  SCONN288_H44441004_PIP  I185
  J1A1   279  VSS<2>  SCONN288_H44441004_PIP  I185
  J1A1   281  VSS<1>  SCONN288_H44441004_PIP  I185
  J1A1   283  VSS<0>  SCONN288_H44441004_PIP  I185
  J1A2     2  VSS<93>  SCONN288_H44441004_PIP  I43
  J1A2     4  VSS<92>  SCONN288_H44441004_PIP  I43
  J1A2     6  VSS<91>  SCONN288_H44441004_PIP  I43
  J1A2     9  VSS<90>  SCONN288_H44441004_PIP  I43
  J1A2    11  VSS<89>  SCONN288_H44441004_PIP  I43
  J1A2    13  VSS<88>  SCONN288_H44441004_PIP  I43
  J1A2    15  VSS<87>  SCONN288_H44441004_PIP  I43
  J1A2    17  VSS<86>  SCONN288_H44441004_PIP  I43
  J1A2    20  VSS<85>  SCONN288_H44441004_PIP  I43
  J1A2    22  VSS<84>  SCONN288_H44441004_PIP  I43
  J1A2    24  VSS<83>  SCONN288_H44441004_PIP  I43
  J1A2    26  VSS<82>  SCONN288_H44441004_PIP  I43
  J1A2    28  VSS<81>  SCONN288_H44441004_PIP  I43
  J1A2    31  VSS<80>  SCONN288_H44441004_PIP  I43
  J1A2    33  VSS<79>  SCONN288_H44441004_PIP  I43
  J1A2    35  VSS<78>  SCONN288_H44441004_PIP  I43
  J1A2    37  VSS<77>  SCONN288_H44441004_PIP  I43
  J1A2    39  VSS<76>  SCONN288_H44441004_PIP  I43
  J1A2    42  VSS<75>  SCONN288_H44441004_PIP  I43
  J1A2    44  VSS<74>  SCONN288_H44441004_PIP  I43
  J1A2    46  VSS<73>  SCONN288_H44441004_PIP  I43
  J1A2    48  VSS<72>  SCONN288_H44441004_PIP  I43
  J1A2    50  VSS<71>  SCONN288_H44441004_PIP  I43
  J1A2    53  VSS<70>  SCONN288_H44441004_PIP  I43
  J1A2    55  VSS<69>  SCONN288_H44441004_PIP  I43
  J1A2    57  VSS<68>  SCONN288_H44441004_PIP  I43
  J1A2    94  VSS<67>  SCONN288_H44441004_PIP  I43
  J1A2    96  VSS<66>  SCONN288_H44441004_PIP  I43
  J1A2    98  VSS<65>  SCONN288_H44441004_PIP  I43
  J1A2   101  VSS<64>  SCONN288_H44441004_PIP  I43
  J1A2   103  VSS<63>  SCONN288_H44441004_PIP  I43
  J1A2   105  VSS<62>  SCONN288_H44441004_PIP  I43
  J1A2   107  VSS<61>  SCONN288_H44441004_PIP  I43
  J1A2   109  VSS<60>  SCONN288_H44441004_PIP  I43
  J1A2   112  VSS<59>  SCONN288_H44441004_PIP  I43
  J1A2   114  VSS<58>  SCONN288_H44441004_PIP  I43
  J1A2   116  VSS<57>  SCONN288_H44441004_PIP  I43
  J1A2   118  VSS<56>  SCONN288_H44441004_PIP  I43
  J1A2   120  VSS<55>  SCONN288_H44441004_PIP  I43
  J1A2   123  VSS<54>  SCONN288_H44441004_PIP  I43
  J1A2   125  VSS<53>  SCONN288_H44441004_PIP  I43
  J1A2   127  VSS<52>  SCONN288_H44441004_PIP  I43
  J1A2   129  VSS<51>  SCONN288_H44441004_PIP  I43
  J1A2   131  VSS<50>  SCONN288_H44441004_PIP  I43
  J1A2   134  VSS<49>  SCONN288_H44441004_PIP  I43
  J1A2   136  VSS<48>  SCONN288_H44441004_PIP  I43
  J1A2   138  VSS<47>  SCONN288_H44441004_PIP  I43
  J1A2   139  SA<0>  SCONN288_H44441004_PIP  I111
  J1A2   147  VSS<46>  SCONN288_H44441004_PIP  I43
  J1A2   149  VSS<45>  SCONN288_H44441004_PIP  I43
  J1A2   151  VSS<44>  SCONN288_H44441004_PIP  I43
  J1A2   154  VSS<43>  SCONN288_H44441004_PIP  I43
  J1A2   156  VSS<42>  SCONN288_H44441004_PIP  I43
  J1A2   158  VSS<41>  SCONN288_H44441004_PIP  I43
  J1A2   160  VSS<40>  SCONN288_H44441004_PIP  I43
  J1A2   162  VSS<39>  SCONN288_H44441004_PIP  I43
  J1A2   165  VSS<38>  SCONN288_H44441004_PIP  I43
  J1A2   167  VSS<37>  SCONN288_H44441004_PIP  I43
  J1A2   169  VSS<36>  SCONN288_H44441004_PIP  I43
  J1A2   171  VSS<35>  SCONN288_H44441004_PIP  I43
  J1A2   173  VSS<34>  SCONN288_H44441004_PIP  I43
  J1A2   176  VSS<33>  SCONN288_H44441004_PIP  I43
  J1A2   178  VSS<32>  SCONN288_H44441004_PIP  I43
  J1A2   180  VSS<31>  SCONN288_H44441004_PIP  I43
  J1A2   182  VSS<30>  SCONN288_H44441004_PIP  I43
  J1A2   184  VSS<29>  SCONN288_H44441004_PIP  I43
  J1A2   187  VSS<28>  SCONN288_H44441004_PIP  I43
  J1A2   189  VSS<27>  SCONN288_H44441004_PIP  I43
  J1A2   191  VSS<26>  SCONN288_H44441004_PIP  I43
  J1A2   193  VSS<25>  SCONN288_H44441004_PIP  I43
  J1A2   195  VSS<24>  SCONN288_H44441004_PIP  I43
  J1A2   198  VSS<23>  SCONN288_H44441004_PIP  I43
  J1A2   200  VSS<22>  SCONN288_H44441004_PIP  I43
  J1A2   202  VSS<21>  SCONN288_H44441004_PIP  I43
  J1A2   238  SA<2>  SCONN288_H44441004_PIP  I111
  J1A2   239  VSS<20>  SCONN288_H44441004_PIP  I43
  J1A2   241  VSS<19>  SCONN288_H44441004_PIP  I43
  J1A2   243  VSS<18>  SCONN288_H44441004_PIP  I43
  J1A2   246  VSS<17>  SCONN288_H44441004_PIP  I43
  J1A2   248  VSS<16>  SCONN288_H44441004_PIP  I43
  J1A2   250  VSS<15>  SCONN288_H44441004_PIP  I43
  J1A2   252  VSS<14>  SCONN288_H44441004_PIP  I43
  J1A2   254  VSS<13>  SCONN288_H44441004_PIP  I43
  J1A2   257  VSS<12>  SCONN288_H44441004_PIP  I43
  J1A2   259  VSS<11>  SCONN288_H44441004_PIP  I43
  J1A2   261  VSS<10>  SCONN288_H44441004_PIP  I43
  J1A2   263  VSS<9>  SCONN288_H44441004_PIP  I43
  J1A2   265  VSS<8>  SCONN288_H44441004_PIP  I43
  J1A2   268  VSS<7>  SCONN288_H44441004_PIP  I43
  J1A2   270  VSS<6>  SCONN288_H44441004_PIP  I43
  J1A2   272  VSS<5>  SCONN288_H44441004_PIP  I43
  J1A2   274  VSS<4>  SCONN288_H44441004_PIP  I43
  J1A2   276  VSS<3>  SCONN288_H44441004_PIP  I43
  J1A2   279  VSS<2>  SCONN288_H44441004_PIP  I43
  J1A2   281  VSS<1>  SCONN288_H44441004_PIP  I43
  J1A2   283  VSS<0>  SCONN288_H44441004_PIP  I43
  J1B1     2  VSS<93>  SCONN288_H44441004_PIP  I43
  J1B1     4  VSS<92>  SCONN288_H44441004_PIP  I43
  J1B1     6  VSS<91>  SCONN288_H44441004_PIP  I43
  J1B1     9  VSS<90>  SCONN288_H44441004_PIP  I43
  J1B1    11  VSS<89>  SCONN288_H44441004_PIP  I43
  J1B1    13  VSS<88>  SCONN288_H44441004_PIP  I43
  J1B1    15  VSS<87>  SCONN288_H44441004_PIP  I43
  J1B1    17  VSS<86>  SCONN288_H44441004_PIP  I43
  J1B1    20  VSS<85>  SCONN288_H44441004_PIP  I43
  J1B1    22  VSS<84>  SCONN288_H44441004_PIP  I43
  J1B1    24  VSS<83>  SCONN288_H44441004_PIP  I43
  J1B1    26  VSS<82>  SCONN288_H44441004_PIP  I43
  J1B1    28  VSS<81>  SCONN288_H44441004_PIP  I43
  J1B1    31  VSS<80>  SCONN288_H44441004_PIP  I43
  J1B1    33  VSS<79>  SCONN288_H44441004_PIP  I43
  J1B1    35  VSS<78>  SCONN288_H44441004_PIP  I43
  J1B1    37  VSS<77>  SCONN288_H44441004_PIP  I43
  J1B1    39  VSS<76>  SCONN288_H44441004_PIP  I43
  J1B1    42  VSS<75>  SCONN288_H44441004_PIP  I43
  J1B1    44  VSS<74>  SCONN288_H44441004_PIP  I43
  J1B1    46  VSS<73>  SCONN288_H44441004_PIP  I43
  J1B1    48  VSS<72>  SCONN288_H44441004_PIP  I43
  J1B1    50  VSS<71>  SCONN288_H44441004_PIP  I43
  J1B1    53  VSS<70>  SCONN288_H44441004_PIP  I43
  J1B1    55  VSS<69>  SCONN288_H44441004_PIP  I43
  J1B1    57  VSS<68>  SCONN288_H44441004_PIP  I43
  J1B1    94  VSS<67>  SCONN288_H44441004_PIP  I43
  J1B1    96  VSS<66>  SCONN288_H44441004_PIP  I43
  J1B1    98  VSS<65>  SCONN288_H44441004_PIP  I43
  J1B1   101  VSS<64>  SCONN288_H44441004_PIP  I43
  J1B1   103  VSS<63>  SCONN288_H44441004_PIP  I43
  J1B1   105  VSS<62>  SCONN288_H44441004_PIP  I43
  J1B1   107  VSS<61>  SCONN288_H44441004_PIP  I43
  J1B1   109  VSS<60>  SCONN288_H44441004_PIP  I43
  J1B1   112  VSS<59>  SCONN288_H44441004_PIP  I43
  J1B1   114  VSS<58>  SCONN288_H44441004_PIP  I43
  J1B1   116  VSS<57>  SCONN288_H44441004_PIP  I43
  J1B1   118  VSS<56>  SCONN288_H44441004_PIP  I43
  J1B1   120  VSS<55>  SCONN288_H44441004_PIP  I43
  J1B1   123  VSS<54>  SCONN288_H44441004_PIP  I43
  J1B1   125  VSS<53>  SCONN288_H44441004_PIP  I43
  J1B1   127  VSS<52>  SCONN288_H44441004_PIP  I43
  J1B1   129  VSS<51>  SCONN288_H44441004_PIP  I43
  J1B1   131  VSS<50>  SCONN288_H44441004_PIP  I43
  J1B1   134  VSS<49>  SCONN288_H44441004_PIP  I43
  J1B1   136  VSS<48>  SCONN288_H44441004_PIP  I43
  J1B1   138  VSS<47>  SCONN288_H44441004_PIP  I43
  J1B1   139  SA<0>  SCONN288_H44441004_PIP  I111
  J1B1   140  SA<1>  SCONN288_H44441004_PIP  I111
  J1B1   147  VSS<46>  SCONN288_H44441004_PIP  I43
  J1B1   149  VSS<45>  SCONN288_H44441004_PIP  I43
  J1B1   151  VSS<44>  SCONN288_H44441004_PIP  I43
  J1B1   154  VSS<43>  SCONN288_H44441004_PIP  I43
  J1B1   156  VSS<42>  SCONN288_H44441004_PIP  I43
  J1B1   158  VSS<41>  SCONN288_H44441004_PIP  I43
  J1B1   160  VSS<40>  SCONN288_H44441004_PIP  I43
  J1B1   162  VSS<39>  SCONN288_H44441004_PIP  I43
  J1B1   165  VSS<38>  SCONN288_H44441004_PIP  I43
  J1B1   167  VSS<37>  SCONN288_H44441004_PIP  I43
  J1B1   169  VSS<36>  SCONN288_H44441004_PIP  I43
  J1B1   171  VSS<35>  SCONN288_H44441004_PIP  I43
  J1B1   173  VSS<34>  SCONN288_H44441004_PIP  I43
  J1B1   176  VSS<33>  SCONN288_H44441004_PIP  I43
  J1B1   178  VSS<32>  SCONN288_H44441004_PIP  I43
  J1B1   180  VSS<31>  SCONN288_H44441004_PIP  I43
  J1B1   182  VSS<30>  SCONN288_H44441004_PIP  I43
  J1B1   184  VSS<29>  SCONN288_H44441004_PIP  I43
  J1B1   187  VSS<28>  SCONN288_H44441004_PIP  I43
  J1B1   189  VSS<27>  SCONN288_H44441004_PIP  I43
  J1B1   191  VSS<26>  SCONN288_H44441004_PIP  I43
  J1B1   193  VSS<25>  SCONN288_H44441004_PIP  I43
  J1B1   195  VSS<24>  SCONN288_H44441004_PIP  I43
  J1B1   198  VSS<23>  SCONN288_H44441004_PIP  I43
  J1B1   200  VSS<22>  SCONN288_H44441004_PIP  I43
  J1B1   202  VSS<21>  SCONN288_H44441004_PIP  I43
  J1B1   238  SA<2>  SCONN288_H44441004_PIP  I111
  J1B1   239  VSS<20>  SCONN288_H44441004_PIP  I43
  J1B1   241  VSS<19>  SCONN288_H44441004_PIP  I43
  J1B1   243  VSS<18>  SCONN288_H44441004_PIP  I43
  J1B1   246  VSS<17>  SCONN288_H44441004_PIP  I43
  J1B1   248  VSS<16>  SCONN288_H44441004_PIP  I43
  J1B1   250  VSS<15>  SCONN288_H44441004_PIP  I43
  J1B1   252  VSS<14>  SCONN288_H44441004_PIP  I43
  J1B1   254  VSS<13>  SCONN288_H44441004_PIP  I43
  J1B1   257  VSS<12>  SCONN288_H44441004_PIP  I43
  J1B1   259  VSS<11>  SCONN288_H44441004_PIP  I43
  J1B1   261  VSS<10>  SCONN288_H44441004_PIP  I43
  J1B1   263  VSS<9>  SCONN288_H44441004_PIP  I43
  J1B1   265  VSS<8>  SCONN288_H44441004_PIP  I43
  J1B1   268  VSS<7>  SCONN288_H44441004_PIP  I43
  J1B1   270  VSS<6>  SCONN288_H44441004_PIP  I43
  J1B1   272  VSS<5>  SCONN288_H44441004_PIP  I43
  J1B1   274  VSS<4>  SCONN288_H44441004_PIP  I43
  J1B1   276  VSS<3>  SCONN288_H44441004_PIP  I43
  J1B1   279  VSS<2>  SCONN288_H44441004_PIP  I43
  J1B1   281  VSS<1>  SCONN288_H44441004_PIP  I43
  J1B1   283  VSS<0>  SCONN288_H44441004_PIP  I43
  J1B2     1    IO1  CONN6_C74770005  I32
  J1C1    A2  GNDA2  CONN76_H22707001_THMT1  I18
  J1C1    A4  GNDA4  CONN76_H22707001_THMT1  I18
  J1C1    A6  GNDA6  CONN76_H22707001_THMT1  I18
  J1C1    A8  GNDA8  CONN76_H22707001_THMT1  I18
  J1C1    C1  GNDC1  CONN76_H22707001_THMT1  I18
  J1C1    C3  GNDC3  CONN76_H22707001_THMT1  I18
  J1C1    C5  GNDC5  CONN76_H22707001_THMT1  I18
  J1C1    C7  GNDC7  CONN76_H22707001_THMT1  I18
  J1C1    D2  GNDD2  CONN76_H22707001_THMT1  I18
  J1C1    D4  GNDD4  CONN76_H22707001_THMT1  I18
  J1C1    D6  GNDD6  CONN76_H22707001_THMT1  I18
  J1C1    D8  GNDD8  CONN76_H22707001_THMT1  I18
  J1C1    F1  GNDF1  CONN76_H22707001_THMT1  I18
  J1C1    F3  GNDF3  CONN76_H22707001_THMT1  I18
  J1C1    F5  GNDF5  CONN76_H22707001_THMT1  I18
  J1C1    F7  GNDF7  CONN76_H22707001_THMT1  I18
  J1C1    G2  GNDG2  CONN76_H22707001_THMT1  I18
  J1C1    G4  GNDG4  CONN76_H22707001_THMT1  I18
  J1C1    G6  GNDG6  CONN76_H22707001_THMT1  I18
  J1C1    G8  GNDG8  CONN76_H22707001_THMT1  I18
  J1C1    I1  GNDI1  CONN76_H22707001_THMT1  I18
  J1C1    I3  GNDI3  CONN76_H22707001_THMT1  I18
  J1C1    I5  GNDI5  CONN76_H22707001_THMT1  I18
  J1C1    I7  GNDI7  CONN76_H22707001_THMT1  I18
  J1C1    J2  GNDJ2  CONN76_H22707001_THMT1  I18
  J1C1    J4  GNDJ4  CONN76_H22707001_THMT1  I18
  J1C1    J6  GNDJ6  CONN76_H22707001_THMT1  I18
  J1C1    J8  GNDJ8  CONN76_H22707001_THMT1  I18
  J1D1    C1     C1  CONN12_G98257001_THMT  I78
  J1D1    C2     C2  CONN12_G98257001_THMT  I78
  J1D1    C3     C3  CONN12_G98257001_THMT  I78
  J1D1    D1     D1  CONN12_G98257001_THMT  I78
  J1D1    D2     D2  CONN12_G98257001_THMT  I78
  J1D1    D3     D3  CONN12_G98257001_THMT  I78
  J1E1    C1     C1  CONN12_G98257001_THMT  I29
  J1E1    C2     C2  CONN12_G98257001_THMT  I29
  J1E1    C3     C3  CONN12_G98257001_THMT  I29
  J1E1    D1     D1  CONN12_G98257001_THMT  I29
  J1E1    D2     D2  CONN12_G98257001_THMT  I29
  J1E1    D3     D3  CONN12_G98257001_THMT  I29
  J1F1    A2  GNDA2  CONN76_H22707001_THMT1  I111
  J1F1    A8  GNDA8  CONN76_H22707001_THMT1  I111
  J1F1    C1  GNDC1  CONN76_H22707001_THMT1  I111
  J1F1    C3  GNDC3  CONN76_H22707001_THMT1  I111
  J1F1    C5  GNDC5  CONN76_H22707001_THMT1  I111
  J1F1    C7  GNDC7  CONN76_H22707001_THMT1  I111
  J1F1    D2  GNDD2  CONN76_H22707001_THMT1  I111
  J1F1    D6  GNDD6  CONN76_H22707001_THMT1  I111
  J1F1    D8  GNDD8  CONN76_H22707001_THMT1  I111
  J1F1    F1  GNDF1  CONN76_H22707001_THMT1  I111
  J1F1    F3  GNDF3  CONN76_H22707001_THMT1  I111
  J1F1    F7  GNDF7  CONN76_H22707001_THMT1  I111
  J1F1    G2  GNDG2  CONN76_H22707001_THMT1  I111
  J1F1    G4  GNDG4  CONN76_H22707001_THMT1  I111
  J1F1    G6  GNDG6  CONN76_H22707001_THMT1  I111
  J1F1    G8  GNDG8  CONN76_H22707001_THMT1  I111
  J1F1    I1  GNDI1  CONN76_H22707001_THMT1  I111
  J1F1    I7  GNDI7  CONN76_H22707001_THMT1  I111
  J1F1    J2  GNDJ2  CONN76_H22707001_THMT1  I111
  J1F1    J4  GNDJ4  CONN76_H22707001_THMT1  I111
  J1F1    J6  GNDJ6  CONN76_H22707001_THMT1  I111
  J1F1    J8  GNDJ8  CONN76_H22707001_THMT1  I111
  J1F2     1    IO1  CONN6_C74770005   I1
  J1F3     8    IO8  CONN8_H62179001_PIP  I189
  J1G1     2  VSS<93>  SCONN288_H44441004_PIP  I43
  J1G1     4  VSS<92>  SCONN288_H44441004_PIP  I43
  J1G1     6  VSS<91>  SCONN288_H44441004_PIP  I43
  J1G1     9  VSS<90>  SCONN288_H44441004_PIP  I43
  J1G1    11  VSS<89>  SCONN288_H44441004_PIP  I43
  J1G1    13  VSS<88>  SCONN288_H44441004_PIP  I43
  J1G1    15  VSS<87>  SCONN288_H44441004_PIP  I43
  J1G1    17  VSS<86>  SCONN288_H44441004_PIP  I43
  J1G1    20  VSS<85>  SCONN288_H44441004_PIP  I43
  J1G1    22  VSS<84>  SCONN288_H44441004_PIP  I43
  J1G1    24  VSS<83>  SCONN288_H44441004_PIP  I43
  J1G1    26  VSS<82>  SCONN288_H44441004_PIP  I43
  J1G1    28  VSS<81>  SCONN288_H44441004_PIP  I43
  J1G1    31  VSS<80>  SCONN288_H44441004_PIP  I43
  J1G1    33  VSS<79>  SCONN288_H44441004_PIP  I43
  J1G1    35  VSS<78>  SCONN288_H44441004_PIP  I43
  J1G1    37  VSS<77>  SCONN288_H44441004_PIP  I43
  J1G1    39  VSS<76>  SCONN288_H44441004_PIP  I43
  J1G1    42  VSS<75>  SCONN288_H44441004_PIP  I43
  J1G1    44  VSS<74>  SCONN288_H44441004_PIP  I43
  J1G1    46  VSS<73>  SCONN288_H44441004_PIP  I43
  J1G1    48  VSS<72>  SCONN288_H44441004_PIP  I43
  J1G1    50  VSS<71>  SCONN288_H44441004_PIP  I43
  J1G1    53  VSS<70>  SCONN288_H44441004_PIP  I43
  J1G1    55  VSS<69>  SCONN288_H44441004_PIP  I43
  J1G1    57  VSS<68>  SCONN288_H44441004_PIP  I43
  J1G1    94  VSS<67>  SCONN288_H44441004_PIP  I43
  J1G1    96  VSS<66>  SCONN288_H44441004_PIP  I43
  J1G1    98  VSS<65>  SCONN288_H44441004_PIP  I43
  J1G1   101  VSS<64>  SCONN288_H44441004_PIP  I43
  J1G1   103  VSS<63>  SCONN288_H44441004_PIP  I43
  J1G1   105  VSS<62>  SCONN288_H44441004_PIP  I43
  J1G1   107  VSS<61>  SCONN288_H44441004_PIP  I43
  J1G1   109  VSS<60>  SCONN288_H44441004_PIP  I43
  J1G1   112  VSS<59>  SCONN288_H44441004_PIP  I43
  J1G1   114  VSS<58>  SCONN288_H44441004_PIP  I43
  J1G1   116  VSS<57>  SCONN288_H44441004_PIP  I43
  J1G1   118  VSS<56>  SCONN288_H44441004_PIP  I43
  J1G1   120  VSS<55>  SCONN288_H44441004_PIP  I43
  J1G1   123  VSS<54>  SCONN288_H44441004_PIP  I43
  J1G1   125  VSS<53>  SCONN288_H44441004_PIP  I43
  J1G1   127  VSS<52>  SCONN288_H44441004_PIP  I43
  J1G1   129  VSS<51>  SCONN288_H44441004_PIP  I43
  J1G1   131  VSS<50>  SCONN288_H44441004_PIP  I43
  J1G1   134  VSS<49>  SCONN288_H44441004_PIP  I43
  J1G1   136  VSS<48>  SCONN288_H44441004_PIP  I43
  J1G1   138  VSS<47>  SCONN288_H44441004_PIP  I43
  J1G1   139  SA<0>  SCONN288_H44441004_PIP  I111
  J1G1   140  SA<1>  SCONN288_H44441004_PIP  I111
  J1G1   147  VSS<46>  SCONN288_H44441004_PIP  I43
  J1G1   149  VSS<45>  SCONN288_H44441004_PIP  I43
  J1G1   151  VSS<44>  SCONN288_H44441004_PIP  I43
  J1G1   154  VSS<43>  SCONN288_H44441004_PIP  I43
  J1G1   156  VSS<42>  SCONN288_H44441004_PIP  I43
  J1G1   158  VSS<41>  SCONN288_H44441004_PIP  I43
  J1G1   160  VSS<40>  SCONN288_H44441004_PIP  I43
  J1G1   162  VSS<39>  SCONN288_H44441004_PIP  I43
  J1G1   165  VSS<38>  SCONN288_H44441004_PIP  I43
  J1G1   167  VSS<37>  SCONN288_H44441004_PIP  I43
  J1G1   169  VSS<36>  SCONN288_H44441004_PIP  I43
  J1G1   171  VSS<35>  SCONN288_H44441004_PIP  I43
  J1G1   173  VSS<34>  SCONN288_H44441004_PIP  I43
  J1G1   176  VSS<33>  SCONN288_H44441004_PIP  I43
  J1G1   178  VSS<32>  SCONN288_H44441004_PIP  I43
  J1G1   180  VSS<31>  SCONN288_H44441004_PIP  I43
  J1G1   182  VSS<30>  SCONN288_H44441004_PIP  I43
  J1G1   184  VSS<29>  SCONN288_H44441004_PIP  I43
  J1G1   187  VSS<28>  SCONN288_H44441004_PIP  I43
  J1G1   189  VSS<27>  SCONN288_H44441004_PIP  I43
  J1G1   191  VSS<26>  SCONN288_H44441004_PIP  I43
  J1G1   193  VSS<25>  SCONN288_H44441004_PIP  I43
  J1G1   195  VSS<24>  SCONN288_H44441004_PIP  I43
  J1G1   198  VSS<23>  SCONN288_H44441004_PIP  I43
  J1G1   200  VSS<22>  SCONN288_H44441004_PIP  I43
  J1G1   202  VSS<21>  SCONN288_H44441004_PIP  I43
  J1G1   238  SA<2>  SCONN288_H44441004_PIP  I111
  J1G1   239  VSS<20>  SCONN288_H44441004_PIP  I43
  J1G1   241  VSS<19>  SCONN288_H44441004_PIP  I43
  J1G1   243  VSS<18>  SCONN288_H44441004_PIP  I43
  J1G1   246  VSS<17>  SCONN288_H44441004_PIP  I43
  J1G1   248  VSS<16>  SCONN288_H44441004_PIP  I43
  J1G1   250  VSS<15>  SCONN288_H44441004_PIP  I43
  J1G1   252  VSS<14>  SCONN288_H44441004_PIP  I43
  J1G1   254  VSS<13>  SCONN288_H44441004_PIP  I43
  J1G1   257  VSS<12>  SCONN288_H44441004_PIP  I43
  J1G1   259  VSS<11>  SCONN288_H44441004_PIP  I43
  J1G1   261  VSS<10>  SCONN288_H44441004_PIP  I43
  J1G1   263  VSS<9>  SCONN288_H44441004_PIP  I43
  J1G1   265  VSS<8>  SCONN288_H44441004_PIP  I43
  J1G1   268  VSS<7>  SCONN288_H44441004_PIP  I43
  J1G1   270  VSS<6>  SCONN288_H44441004_PIP  I43
  J1G1   272  VSS<5>  SCONN288_H44441004_PIP  I43
  J1G1   274  VSS<4>  SCONN288_H44441004_PIP  I43
  J1G1   276  VSS<3>  SCONN288_H44441004_PIP  I43
  J1G1   279  VSS<2>  SCONN288_H44441004_PIP  I43
  J1G1   281  VSS<1>  SCONN288_H44441004_PIP  I43
  J1G1   283  VSS<0>  SCONN288_H44441004_PIP  I43
  J1G2     2  VSS<93>  SCONN288_H44441004_PIP  I43
  J1G2     4  VSS<92>  SCONN288_H44441004_PIP  I43
  J1G2     6  VSS<91>  SCONN288_H44441004_PIP  I43
  J1G2     9  VSS<90>  SCONN288_H44441004_PIP  I43
  J1G2    11  VSS<89>  SCONN288_H44441004_PIP  I43
  J1G2    13  VSS<88>  SCONN288_H44441004_PIP  I43
  J1G2    15  VSS<87>  SCONN288_H44441004_PIP  I43
  J1G2    17  VSS<86>  SCONN288_H44441004_PIP  I43
  J1G2    20  VSS<85>  SCONN288_H44441004_PIP  I43
  J1G2    22  VSS<84>  SCONN288_H44441004_PIP  I43
  J1G2    24  VSS<83>  SCONN288_H44441004_PIP  I43
  J1G2    26  VSS<82>  SCONN288_H44441004_PIP  I43
  J1G2    28  VSS<81>  SCONN288_H44441004_PIP  I43
  J1G2    31  VSS<80>  SCONN288_H44441004_PIP  I43
  J1G2    33  VSS<79>  SCONN288_H44441004_PIP  I43
  J1G2    35  VSS<78>  SCONN288_H44441004_PIP  I43
  J1G2    37  VSS<77>  SCONN288_H44441004_PIP  I43
  J1G2    39  VSS<76>  SCONN288_H44441004_PIP  I43
  J1G2    42  VSS<75>  SCONN288_H44441004_PIP  I43
  J1G2    44  VSS<74>  SCONN288_H44441004_PIP  I43
  J1G2    46  VSS<73>  SCONN288_H44441004_PIP  I43
  J1G2    48  VSS<72>  SCONN288_H44441004_PIP  I43
  J1G2    50  VSS<71>  SCONN288_H44441004_PIP  I43
  J1G2    53  VSS<70>  SCONN288_H44441004_PIP  I43
  J1G2    55  VSS<69>  SCONN288_H44441004_PIP  I43
  J1G2    57  VSS<68>  SCONN288_H44441004_PIP  I43
  J1G2    94  VSS<67>  SCONN288_H44441004_PIP  I43
  J1G2    96  VSS<66>  SCONN288_H44441004_PIP  I43
  J1G2    98  VSS<65>  SCONN288_H44441004_PIP  I43
  J1G2   101  VSS<64>  SCONN288_H44441004_PIP  I43
  J1G2   103  VSS<63>  SCONN288_H44441004_PIP  I43
  J1G2   105  VSS<62>  SCONN288_H44441004_PIP  I43
  J1G2   107  VSS<61>  SCONN288_H44441004_PIP  I43
  J1G2   109  VSS<60>  SCONN288_H44441004_PIP  I43
  J1G2   112  VSS<59>  SCONN288_H44441004_PIP  I43
  J1G2   114  VSS<58>  SCONN288_H44441004_PIP  I43
  J1G2   116  VSS<57>  SCONN288_H44441004_PIP  I43
  J1G2   118  VSS<56>  SCONN288_H44441004_PIP  I43
  J1G2   120  VSS<55>  SCONN288_H44441004_PIP  I43
  J1G2   123  VSS<54>  SCONN288_H44441004_PIP  I43
  J1G2   125  VSS<53>  SCONN288_H44441004_PIP  I43
  J1G2   127  VSS<52>  SCONN288_H44441004_PIP  I43
  J1G2   129  VSS<51>  SCONN288_H44441004_PIP  I43
  J1G2   131  VSS<50>  SCONN288_H44441004_PIP  I43
  J1G2   134  VSS<49>  SCONN288_H44441004_PIP  I43
  J1G2   136  VSS<48>  SCONN288_H44441004_PIP  I43
  J1G2   138  VSS<47>  SCONN288_H44441004_PIP  I43
  J1G2   139  SA<0>  SCONN288_H44441004_PIP  I111
  J1G2   147  VSS<46>  SCONN288_H44441004_PIP  I43
  J1G2   149  VSS<45>  SCONN288_H44441004_PIP  I43
  J1G2   151  VSS<44>  SCONN288_H44441004_PIP  I43
  J1G2   154  VSS<43>  SCONN288_H44441004_PIP  I43
  J1G2   156  VSS<42>  SCONN288_H44441004_PIP  I43
  J1G2   158  VSS<41>  SCONN288_H44441004_PIP  I43
  J1G2   160  VSS<40>  SCONN288_H44441004_PIP  I43
  J1G2   162  VSS<39>  SCONN288_H44441004_PIP  I43
  J1G2   165  VSS<38>  SCONN288_H44441004_PIP  I43
  J1G2   167  VSS<37>  SCONN288_H44441004_PIP  I43
  J1G2   169  VSS<36>  SCONN288_H44441004_PIP  I43
  J1G2   171  VSS<35>  SCONN288_H44441004_PIP  I43
  J1G2   173  VSS<34>  SCONN288_H44441004_PIP  I43
  J1G2   176  VSS<33>  SCONN288_H44441004_PIP  I43
  J1G2   178  VSS<32>  SCONN288_H44441004_PIP  I43
  J1G2   180  VSS<31>  SCONN288_H44441004_PIP  I43
  J1G2   182  VSS<30>  SCONN288_H44441004_PIP  I43
  J1G2   184  VSS<29>  SCONN288_H44441004_PIP  I43
  J1G2   187  VSS<28>  SCONN288_H44441004_PIP  I43
  J1G2   189  VSS<27>  SCONN288_H44441004_PIP  I43
  J1G2   191  VSS<26>  SCONN288_H44441004_PIP  I43
  J1G2   193  VSS<25>  SCONN288_H44441004_PIP  I43
  J1G2   195  VSS<24>  SCONN288_H44441004_PIP  I43
  J1G2   198  VSS<23>  SCONN288_H44441004_PIP  I43
  J1G2   200  VSS<22>  SCONN288_H44441004_PIP  I43
  J1G2   202  VSS<21>  SCONN288_H44441004_PIP  I43
  J1G2   238  SA<2>  SCONN288_H44441004_PIP  I111
  J1G2   239  VSS<20>  SCONN288_H44441004_PIP  I43
  J1G2   241  VSS<19>  SCONN288_H44441004_PIP  I43
  J1G2   243  VSS<18>  SCONN288_H44441004_PIP  I43
  J1G2   246  VSS<17>  SCONN288_H44441004_PIP  I43
  J1G2   248  VSS<16>  SCONN288_H44441004_PIP  I43
  J1G2   250  VSS<15>  SCONN288_H44441004_PIP  I43
  J1G2   252  VSS<14>  SCONN288_H44441004_PIP  I43
  J1G2   254  VSS<13>  SCONN288_H44441004_PIP  I43
  J1G2   257  VSS<12>  SCONN288_H44441004_PIP  I43
  J1G2   259  VSS<11>  SCONN288_H44441004_PIP  I43
  J1G2   261  VSS<10>  SCONN288_H44441004_PIP  I43
  J1G2   263  VSS<9>  SCONN288_H44441004_PIP  I43
  J1G2   265  VSS<8>  SCONN288_H44441004_PIP  I43
  J1G2   268  VSS<7>  SCONN288_H44441004_PIP  I43
  J1G2   270  VSS<6>  SCONN288_H44441004_PIP  I43
  J1G2   272  VSS<5>  SCONN288_H44441004_PIP  I43
  J1G2   274  VSS<4>  SCONN288_H44441004_PIP  I43
  J1G2   276  VSS<3>  SCONN288_H44441004_PIP  I43
  J1G2   279  VSS<2>  SCONN288_H44441004_PIP  I43
  J1G2   281  VSS<1>  SCONN288_H44441004_PIP  I43
  J1G2   283  VSS<0>  SCONN288_H44441004_PIP  I43
  J1G3     2  VSS<93>  SCONN288_H44441004_PIP  I185
  J1G3     4  VSS<92>  SCONN288_H44441004_PIP  I185
  J1G3     6  VSS<91>  SCONN288_H44441004_PIP  I185
  J1G3     9  VSS<90>  SCONN288_H44441004_PIP  I185
  J1G3    11  VSS<89>  SCONN288_H44441004_PIP  I185
  J1G3    13  VSS<88>  SCONN288_H44441004_PIP  I185
  J1G3    15  VSS<87>  SCONN288_H44441004_PIP  I185
  J1G3    17  VSS<86>  SCONN288_H44441004_PIP  I185
  J1G3    20  VSS<85>  SCONN288_H44441004_PIP  I185
  J1G3    22  VSS<84>  SCONN288_H44441004_PIP  I185
  J1G3    24  VSS<83>  SCONN288_H44441004_PIP  I185
  J1G3    26  VSS<82>  SCONN288_H44441004_PIP  I185
  J1G3    28  VSS<81>  SCONN288_H44441004_PIP  I185
  J1G3    31  VSS<80>  SCONN288_H44441004_PIP  I185
  J1G3    33  VSS<79>  SCONN288_H44441004_PIP  I185
  J1G3    35  VSS<78>  SCONN288_H44441004_PIP  I185
  J1G3    37  VSS<77>  SCONN288_H44441004_PIP  I185
  J1G3    39  VSS<76>  SCONN288_H44441004_PIP  I185
  J1G3    42  VSS<75>  SCONN288_H44441004_PIP  I185
  J1G3    44  VSS<74>  SCONN288_H44441004_PIP  I185
  J1G3    46  VSS<73>  SCONN288_H44441004_PIP  I185
  J1G3    48  VSS<72>  SCONN288_H44441004_PIP  I185
  J1G3    50  VSS<71>  SCONN288_H44441004_PIP  I185
  J1G3    53  VSS<70>  SCONN288_H44441004_PIP  I185
  J1G3    55  VSS<69>  SCONN288_H44441004_PIP  I185
  J1G3    57  VSS<68>  SCONN288_H44441004_PIP  I185
  J1G3    94  VSS<67>  SCONN288_H44441004_PIP  I185
  J1G3    96  VSS<66>  SCONN288_H44441004_PIP  I185
  J1G3    98  VSS<65>  SCONN288_H44441004_PIP  I185
  J1G3   101  VSS<64>  SCONN288_H44441004_PIP  I185
  J1G3   103  VSS<63>  SCONN288_H44441004_PIP  I185
  J1G3   105  VSS<62>  SCONN288_H44441004_PIP  I185
  J1G3   107  VSS<61>  SCONN288_H44441004_PIP  I185
  J1G3   109  VSS<60>  SCONN288_H44441004_PIP  I185
  J1G3   112  VSS<59>  SCONN288_H44441004_PIP  I185
  J1G3   114  VSS<58>  SCONN288_H44441004_PIP  I185
  J1G3   116  VSS<57>  SCONN288_H44441004_PIP  I185
  J1G3   118  VSS<56>  SCONN288_H44441004_PIP  I185
  J1G3   120  VSS<55>  SCONN288_H44441004_PIP  I185
  J1G3   123  VSS<54>  SCONN288_H44441004_PIP  I185
  J1G3   125  VSS<53>  SCONN288_H44441004_PIP  I185
  J1G3   127  VSS<52>  SCONN288_H44441004_PIP  I185
  J1G3   129  VSS<51>  SCONN288_H44441004_PIP  I185
  J1G3   131  VSS<50>  SCONN288_H44441004_PIP  I185
  J1G3   134  VSS<49>  SCONN288_H44441004_PIP  I185
  J1G3   136  VSS<48>  SCONN288_H44441004_PIP  I185
  J1G3   138  VSS<47>  SCONN288_H44441004_PIP  I185
  J1G3   139  SA<0>  SCONN288_H44441004_PIP  I186
  J1G3   140  SA<1>  SCONN288_H44441004_PIP  I186
  J1G3   147  VSS<46>  SCONN288_H44441004_PIP  I185
  J1G3   149  VSS<45>  SCONN288_H44441004_PIP  I185
  J1G3   151  VSS<44>  SCONN288_H44441004_PIP  I185
  J1G3   154  VSS<43>  SCONN288_H44441004_PIP  I185
  J1G3   156  VSS<42>  SCONN288_H44441004_PIP  I185
  J1G3   158  VSS<41>  SCONN288_H44441004_PIP  I185
  J1G3   160  VSS<40>  SCONN288_H44441004_PIP  I185
  J1G3   162  VSS<39>  SCONN288_H44441004_PIP  I185
  J1G3   165  VSS<38>  SCONN288_H44441004_PIP  I185
  J1G3   167  VSS<37>  SCONN288_H44441004_PIP  I185
  J1G3   169  VSS<36>  SCONN288_H44441004_PIP  I185
  J1G3   171  VSS<35>  SCONN288_H44441004_PIP  I185
  J1G3   173  VSS<34>  SCONN288_H44441004_PIP  I185
  J1G3   176  VSS<33>  SCONN288_H44441004_PIP  I185
  J1G3   178  VSS<32>  SCONN288_H44441004_PIP  I185
  J1G3   180  VSS<31>  SCONN288_H44441004_PIP  I185
  J1G3   182  VSS<30>  SCONN288_H44441004_PIP  I185
  J1G3   184  VSS<29>  SCONN288_H44441004_PIP  I185
  J1G3   187  VSS<28>  SCONN288_H44441004_PIP  I185
  J1G3   189  VSS<27>  SCONN288_H44441004_PIP  I185
  J1G3   191  VSS<26>  SCONN288_H44441004_PIP  I185
  J1G3   193  VSS<25>  SCONN288_H44441004_PIP  I185
  J1G3   195  VSS<24>  SCONN288_H44441004_PIP  I185
  J1G3   198  VSS<23>  SCONN288_H44441004_PIP  I185
  J1G3   200  VSS<22>  SCONN288_H44441004_PIP  I185
  J1G3   202  VSS<21>  SCONN288_H44441004_PIP  I185
  J1G3   239  VSS<20>  SCONN288_H44441004_PIP  I185
  J1G3   241  VSS<19>  SCONN288_H44441004_PIP  I185
  J1G3   243  VSS<18>  SCONN288_H44441004_PIP  I185
  J1G3   246  VSS<17>  SCONN288_H44441004_PIP  I185
  J1G3   248  VSS<16>  SCONN288_H44441004_PIP  I185
  J1G3   250  VSS<15>  SCONN288_H44441004_PIP  I185
  J1G3   252  VSS<14>  SCONN288_H44441004_PIP  I185
  J1G3   254  VSS<13>  SCONN288_H44441004_PIP  I185
  J1G3   257  VSS<12>  SCONN288_H44441004_PIP  I185
  J1G3   259  VSS<11>  SCONN288_H44441004_PIP  I185
  J1G3   261  VSS<10>  SCONN288_H44441004_PIP  I185
  J1G3   263  VSS<9>  SCONN288_H44441004_PIP  I185
  J1G3   265  VSS<8>  SCONN288_H44441004_PIP  I185
  J1G3   268  VSS<7>  SCONN288_H44441004_PIP  I185
  J1G3   270  VSS<6>  SCONN288_H44441004_PIP  I185
  J1G3   272  VSS<5>  SCONN288_H44441004_PIP  I185
  J1G3   274  VSS<4>  SCONN288_H44441004_PIP  I185
  J1G3   276  VSS<3>  SCONN288_H44441004_PIP  I185
  J1G3   279  VSS<2>  SCONN288_H44441004_PIP  I185
  J1G3   281  VSS<1>  SCONN288_H44441004_PIP  I185
  J1G3   283  VSS<0>  SCONN288_H44441004_PIP  I185
  J2L1     2    IO2  CONN4_H73295001_PIP  I53
  J2L1     3    IO3  CONN4_H73295001_PIP  I53
  J2M1     1  GND<2>  CONN7_E82125014_PIP_TH  I52
  J2M1     4  GND<1>  CONN7_E82125014_PIP_TH  I52
  J2M1     7  GND<0>  CONN7_E82125014_PIP_TH  I52
  J2M1   MH1    MH1  CONN7_E82125014_PIP_TH  I52
  J2M1   MH2    MH2  CONN7_E82125014_PIP_TH  I52
  J4A1     2  VSS<93>  SCONN288_H44441004_PIP  I43
  J4A1     4  VSS<92>  SCONN288_H44441004_PIP  I43
  J4A1     6  VSS<91>  SCONN288_H44441004_PIP  I43
  J4A1     9  VSS<90>  SCONN288_H44441004_PIP  I43
  J4A1    11  VSS<89>  SCONN288_H44441004_PIP  I43
  J4A1    13  VSS<88>  SCONN288_H44441004_PIP  I43
  J4A1    15  VSS<87>  SCONN288_H44441004_PIP  I43
  J4A1    17  VSS<86>  SCONN288_H44441004_PIP  I43
  J4A1    20  VSS<85>  SCONN288_H44441004_PIP  I43
  J4A1    22  VSS<84>  SCONN288_H44441004_PIP  I43
  J4A1    24  VSS<83>  SCONN288_H44441004_PIP  I43
  J4A1    26  VSS<82>  SCONN288_H44441004_PIP  I43
  J4A1    28  VSS<81>  SCONN288_H44441004_PIP  I43
  J4A1    31  VSS<80>  SCONN288_H44441004_PIP  I43
  J4A1    33  VSS<79>  SCONN288_H44441004_PIP  I43
  J4A1    35  VSS<78>  SCONN288_H44441004_PIP  I43
  J4A1    37  VSS<77>  SCONN288_H44441004_PIP  I43
  J4A1    39  VSS<76>  SCONN288_H44441004_PIP  I43
  J4A1    42  VSS<75>  SCONN288_H44441004_PIP  I43
  J4A1    44  VSS<74>  SCONN288_H44441004_PIP  I43
  J4A1    46  VSS<73>  SCONN288_H44441004_PIP  I43
  J4A1    48  VSS<72>  SCONN288_H44441004_PIP  I43
  J4A1    50  VSS<71>  SCONN288_H44441004_PIP  I43
  J4A1    53  VSS<70>  SCONN288_H44441004_PIP  I43
  J4A1    55  VSS<69>  SCONN288_H44441004_PIP  I43
  J4A1    57  VSS<68>  SCONN288_H44441004_PIP  I43
  J4A1    94  VSS<67>  SCONN288_H44441004_PIP  I43
  J4A1    96  VSS<66>  SCONN288_H44441004_PIP  I43
  J4A1    98  VSS<65>  SCONN288_H44441004_PIP  I43
  J4A1   101  VSS<64>  SCONN288_H44441004_PIP  I43
  J4A1   103  VSS<63>  SCONN288_H44441004_PIP  I43
  J4A1   105  VSS<62>  SCONN288_H44441004_PIP  I43
  J4A1   107  VSS<61>  SCONN288_H44441004_PIP  I43
  J4A1   109  VSS<60>  SCONN288_H44441004_PIP  I43
  J4A1   112  VSS<59>  SCONN288_H44441004_PIP  I43
  J4A1   114  VSS<58>  SCONN288_H44441004_PIP  I43
  J4A1   116  VSS<57>  SCONN288_H44441004_PIP  I43
  J4A1   118  VSS<56>  SCONN288_H44441004_PIP  I43
  J4A1   120  VSS<55>  SCONN288_H44441004_PIP  I43
  J4A1   123  VSS<54>  SCONN288_H44441004_PIP  I43
  J4A1   125  VSS<53>  SCONN288_H44441004_PIP  I43
  J4A1   127  VSS<52>  SCONN288_H44441004_PIP  I43
  J4A1   129  VSS<51>  SCONN288_H44441004_PIP  I43
  J4A1   131  VSS<50>  SCONN288_H44441004_PIP  I43
  J4A1   134  VSS<49>  SCONN288_H44441004_PIP  I43
  J4A1   136  VSS<48>  SCONN288_H44441004_PIP  I43
  J4A1   138  VSS<47>  SCONN288_H44441004_PIP  I43
  J4A1   139  SA<0>  SCONN288_H44441004_PIP  I111
  J4A1   140  SA<1>  SCONN288_H44441004_PIP  I111
  J4A1   147  VSS<46>  SCONN288_H44441004_PIP  I43
  J4A1   149  VSS<45>  SCONN288_H44441004_PIP  I43
  J4A1   151  VSS<44>  SCONN288_H44441004_PIP  I43
  J4A1   154  VSS<43>  SCONN288_H44441004_PIP  I43
  J4A1   156  VSS<42>  SCONN288_H44441004_PIP  I43
  J4A1   158  VSS<41>  SCONN288_H44441004_PIP  I43
  J4A1   160  VSS<40>  SCONN288_H44441004_PIP  I43
  J4A1   162  VSS<39>  SCONN288_H44441004_PIP  I43
  J4A1   165  VSS<38>  SCONN288_H44441004_PIP  I43
  J4A1   167  VSS<37>  SCONN288_H44441004_PIP  I43
  J4A1   169  VSS<36>  SCONN288_H44441004_PIP  I43
  J4A1   171  VSS<35>  SCONN288_H44441004_PIP  I43
  J4A1   173  VSS<34>  SCONN288_H44441004_PIP  I43
  J4A1   176  VSS<33>  SCONN288_H44441004_PIP  I43
  J4A1   178  VSS<32>  SCONN288_H44441004_PIP  I43
  J4A1   180  VSS<31>  SCONN288_H44441004_PIP  I43
  J4A1   182  VSS<30>  SCONN288_H44441004_PIP  I43
  J4A1   184  VSS<29>  SCONN288_H44441004_PIP  I43
  J4A1   187  VSS<28>  SCONN288_H44441004_PIP  I43
  J4A1   189  VSS<27>  SCONN288_H44441004_PIP  I43
  J4A1   191  VSS<26>  SCONN288_H44441004_PIP  I43
  J4A1   193  VSS<25>  SCONN288_H44441004_PIP  I43
  J4A1   195  VSS<24>  SCONN288_H44441004_PIP  I43
  J4A1   198  VSS<23>  SCONN288_H44441004_PIP  I43
  J4A1   200  VSS<22>  SCONN288_H44441004_PIP  I43
  J4A1   202  VSS<21>  SCONN288_H44441004_PIP  I43
  J4A1   239  VSS<20>  SCONN288_H44441004_PIP  I43
  J4A1   241  VSS<19>  SCONN288_H44441004_PIP  I43
  J4A1   243  VSS<18>  SCONN288_H44441004_PIP  I43
  J4A1   246  VSS<17>  SCONN288_H44441004_PIP  I43
  J4A1   248  VSS<16>  SCONN288_H44441004_PIP  I43
  J4A1   250  VSS<15>  SCONN288_H44441004_PIP  I43
  J4A1   252  VSS<14>  SCONN288_H44441004_PIP  I43
  J4A1   254  VSS<13>  SCONN288_H44441004_PIP  I43
  J4A1   257  VSS<12>  SCONN288_H44441004_PIP  I43
  J4A1   259  VSS<11>  SCONN288_H44441004_PIP  I43
  J4A1   261  VSS<10>  SCONN288_H44441004_PIP  I43
  J4A1   263  VSS<9>  SCONN288_H44441004_PIP  I43
  J4A1   265  VSS<8>  SCONN288_H44441004_PIP  I43
  J4A1   268  VSS<7>  SCONN288_H44441004_PIP  I43
  J4A1   270  VSS<6>  SCONN288_H44441004_PIP  I43
  J4A1   272  VSS<5>  SCONN288_H44441004_PIP  I43
  J4A1   274  VSS<4>  SCONN288_H44441004_PIP  I43
  J4A1   276  VSS<3>  SCONN288_H44441004_PIP  I43
  J4A1   279  VSS<2>  SCONN288_H44441004_PIP  I43
  J4A1   281  VSS<1>  SCONN288_H44441004_PIP  I43
  J4A1   283  VSS<0>  SCONN288_H44441004_PIP  I43
  J4A2     2  VSS<93>  SCONN288_H44441004_PIP  I43
  J4A2     4  VSS<92>  SCONN288_H44441004_PIP  I43
  J4A2     6  VSS<91>  SCONN288_H44441004_PIP  I43
  J4A2     9  VSS<90>  SCONN288_H44441004_PIP  I43
  J4A2    11  VSS<89>  SCONN288_H44441004_PIP  I43
  J4A2    13  VSS<88>  SCONN288_H44441004_PIP  I43
  J4A2    15  VSS<87>  SCONN288_H44441004_PIP  I43
  J4A2    17  VSS<86>  SCONN288_H44441004_PIP  I43
  J4A2    20  VSS<85>  SCONN288_H44441004_PIP  I43
  J4A2    22  VSS<84>  SCONN288_H44441004_PIP  I43
  J4A2    24  VSS<83>  SCONN288_H44441004_PIP  I43
  J4A2    26  VSS<82>  SCONN288_H44441004_PIP  I43
  J4A2    28  VSS<81>  SCONN288_H44441004_PIP  I43
  J4A2    31  VSS<80>  SCONN288_H44441004_PIP  I43
  J4A2    33  VSS<79>  SCONN288_H44441004_PIP  I43
  J4A2    35  VSS<78>  SCONN288_H44441004_PIP  I43
  J4A2    37  VSS<77>  SCONN288_H44441004_PIP  I43
  J4A2    39  VSS<76>  SCONN288_H44441004_PIP  I43
  J4A2    42  VSS<75>  SCONN288_H44441004_PIP  I43
  J4A2    44  VSS<74>  SCONN288_H44441004_PIP  I43
  J4A2    46  VSS<73>  SCONN288_H44441004_PIP  I43
  J4A2    48  VSS<72>  SCONN288_H44441004_PIP  I43
  J4A2    50  VSS<71>  SCONN288_H44441004_PIP  I43
  J4A2    53  VSS<70>  SCONN288_H44441004_PIP  I43
  J4A2    55  VSS<69>  SCONN288_H44441004_PIP  I43
  J4A2    57  VSS<68>  SCONN288_H44441004_PIP  I43
  J4A2    94  VSS<67>  SCONN288_H44441004_PIP  I43
  J4A2    96  VSS<66>  SCONN288_H44441004_PIP  I43
  J4A2    98  VSS<65>  SCONN288_H44441004_PIP  I43
  J4A2   101  VSS<64>  SCONN288_H44441004_PIP  I43
  J4A2   103  VSS<63>  SCONN288_H44441004_PIP  I43
  J4A2   105  VSS<62>  SCONN288_H44441004_PIP  I43
  J4A2   107  VSS<61>  SCONN288_H44441004_PIP  I43
  J4A2   109  VSS<60>  SCONN288_H44441004_PIP  I43
  J4A2   112  VSS<59>  SCONN288_H44441004_PIP  I43
  J4A2   114  VSS<58>  SCONN288_H44441004_PIP  I43
  J4A2   116  VSS<57>  SCONN288_H44441004_PIP  I43
  J4A2   118  VSS<56>  SCONN288_H44441004_PIP  I43
  J4A2   120  VSS<55>  SCONN288_H44441004_PIP  I43
  J4A2   123  VSS<54>  SCONN288_H44441004_PIP  I43
  J4A2   125  VSS<53>  SCONN288_H44441004_PIP  I43
  J4A2   127  VSS<52>  SCONN288_H44441004_PIP  I43
  J4A2   129  VSS<51>  SCONN288_H44441004_PIP  I43
  J4A2   131  VSS<50>  SCONN288_H44441004_PIP  I43
  J4A2   134  VSS<49>  SCONN288_H44441004_PIP  I43
  J4A2   136  VSS<48>  SCONN288_H44441004_PIP  I43
  J4A2   138  VSS<47>  SCONN288_H44441004_PIP  I43
  J4A2   139  SA<0>  SCONN288_H44441004_PIP  I111
  J4A2   147  VSS<46>  SCONN288_H44441004_PIP  I43
  J4A2   149  VSS<45>  SCONN288_H44441004_PIP  I43
  J4A2   151  VSS<44>  SCONN288_H44441004_PIP  I43
  J4A2   154  VSS<43>  SCONN288_H44441004_PIP  I43
  J4A2   156  VSS<42>  SCONN288_H44441004_PIP  I43
  J4A2   158  VSS<41>  SCONN288_H44441004_PIP  I43
  J4A2   160  VSS<40>  SCONN288_H44441004_PIP  I43
  J4A2   162  VSS<39>  SCONN288_H44441004_PIP  I43
  J4A2   165  VSS<38>  SCONN288_H44441004_PIP  I43
  J4A2   167  VSS<37>  SCONN288_H44441004_PIP  I43
  J4A2   169  VSS<36>  SCONN288_H44441004_PIP  I43
  J4A2   171  VSS<35>  SCONN288_H44441004_PIP  I43
  J4A2   173  VSS<34>  SCONN288_H44441004_PIP  I43
  J4A2   176  VSS<33>  SCONN288_H44441004_PIP  I43
  J4A2   178  VSS<32>  SCONN288_H44441004_PIP  I43
  J4A2   180  VSS<31>  SCONN288_H44441004_PIP  I43
  J4A2   182  VSS<30>  SCONN288_H44441004_PIP  I43
  J4A2   184  VSS<29>  SCONN288_H44441004_PIP  I43
  J4A2   187  VSS<28>  SCONN288_H44441004_PIP  I43
  J4A2   189  VSS<27>  SCONN288_H44441004_PIP  I43
  J4A2   191  VSS<26>  SCONN288_H44441004_PIP  I43
  J4A2   193  VSS<25>  SCONN288_H44441004_PIP  I43
  J4A2   195  VSS<24>  SCONN288_H44441004_PIP  I43
  J4A2   198  VSS<23>  SCONN288_H44441004_PIP  I43
  J4A2   200  VSS<22>  SCONN288_H44441004_PIP  I43
  J4A2   202  VSS<21>  SCONN288_H44441004_PIP  I43
  J4A2   238  SA<2>  SCONN288_H44441004_PIP  I111
  J4A2   239  VSS<20>  SCONN288_H44441004_PIP  I43
  J4A2   241  VSS<19>  SCONN288_H44441004_PIP  I43
  J4A2   243  VSS<18>  SCONN288_H44441004_PIP  I43
  J4A2   246  VSS<17>  SCONN288_H44441004_PIP  I43
  J4A2   248  VSS<16>  SCONN288_H44441004_PIP  I43
  J4A2   250  VSS<15>  SCONN288_H44441004_PIP  I43
  J4A2   252  VSS<14>  SCONN288_H44441004_PIP  I43
  J4A2   254  VSS<13>  SCONN288_H44441004_PIP  I43
  J4A2   257  VSS<12>  SCONN288_H44441004_PIP  I43
  J4A2   259  VSS<11>  SCONN288_H44441004_PIP  I43
  J4A2   261  VSS<10>  SCONN288_H44441004_PIP  I43
  J4A2   263  VSS<9>  SCONN288_H44441004_PIP  I43
  J4A2   265  VSS<8>  SCONN288_H44441004_PIP  I43
  J4A2   268  VSS<7>  SCONN288_H44441004_PIP  I43
  J4A2   270  VSS<6>  SCONN288_H44441004_PIP  I43
  J4A2   272  VSS<5>  SCONN288_H44441004_PIP  I43
  J4A2   274  VSS<4>  SCONN288_H44441004_PIP  I43
  J4A2   276  VSS<3>  SCONN288_H44441004_PIP  I43
  J4A2   279  VSS<2>  SCONN288_H44441004_PIP  I43
  J4A2   281  VSS<1>  SCONN288_H44441004_PIP  I43
  J4A2   283  VSS<0>  SCONN288_H44441004_PIP  I43
  J4B1     2  VSS<93>  SCONN288_H44441004_PIP  I43
  J4B1     4  VSS<92>  SCONN288_H44441004_PIP  I43
  J4B1     6  VSS<91>  SCONN288_H44441004_PIP  I43
  J4B1     9  VSS<90>  SCONN288_H44441004_PIP  I43
  J4B1    11  VSS<89>  SCONN288_H44441004_PIP  I43
  J4B1    13  VSS<88>  SCONN288_H44441004_PIP  I43
  J4B1    15  VSS<87>  SCONN288_H44441004_PIP  I43
  J4B1    17  VSS<86>  SCONN288_H44441004_PIP  I43
  J4B1    20  VSS<85>  SCONN288_H44441004_PIP  I43
  J4B1    22  VSS<84>  SCONN288_H44441004_PIP  I43
  J4B1    24  VSS<83>  SCONN288_H44441004_PIP  I43
  J4B1    26  VSS<82>  SCONN288_H44441004_PIP  I43
  J4B1    28  VSS<81>  SCONN288_H44441004_PIP  I43
  J4B1    31  VSS<80>  SCONN288_H44441004_PIP  I43
  J4B1    33  VSS<79>  SCONN288_H44441004_PIP  I43
  J4B1    35  VSS<78>  SCONN288_H44441004_PIP  I43
  J4B1    37  VSS<77>  SCONN288_H44441004_PIP  I43
  J4B1    39  VSS<76>  SCONN288_H44441004_PIP  I43
  J4B1    42  VSS<75>  SCONN288_H44441004_PIP  I43
  J4B1    44  VSS<74>  SCONN288_H44441004_PIP  I43
  J4B1    46  VSS<73>  SCONN288_H44441004_PIP  I43
  J4B1    48  VSS<72>  SCONN288_H44441004_PIP  I43
  J4B1    50  VSS<71>  SCONN288_H44441004_PIP  I43
  J4B1    53  VSS<70>  SCONN288_H44441004_PIP  I43
  J4B1    55  VSS<69>  SCONN288_H44441004_PIP  I43
  J4B1    57  VSS<68>  SCONN288_H44441004_PIP  I43
  J4B1    94  VSS<67>  SCONN288_H44441004_PIP  I43
  J4B1    96  VSS<66>  SCONN288_H44441004_PIP  I43
  J4B1    98  VSS<65>  SCONN288_H44441004_PIP  I43
  J4B1   101  VSS<64>  SCONN288_H44441004_PIP  I43
  J4B1   103  VSS<63>  SCONN288_H44441004_PIP  I43
  J4B1   105  VSS<62>  SCONN288_H44441004_PIP  I43
  J4B1   107  VSS<61>  SCONN288_H44441004_PIP  I43
  J4B1   109  VSS<60>  SCONN288_H44441004_PIP  I43
  J4B1   112  VSS<59>  SCONN288_H44441004_PIP  I43
  J4B1   114  VSS<58>  SCONN288_H44441004_PIP  I43
  J4B1   116  VSS<57>  SCONN288_H44441004_PIP  I43
  J4B1   118  VSS<56>  SCONN288_H44441004_PIP  I43
  J4B1   120  VSS<55>  SCONN288_H44441004_PIP  I43
  J4B1   123  VSS<54>  SCONN288_H44441004_PIP  I43
  J4B1   125  VSS<53>  SCONN288_H44441004_PIP  I43
  J4B1   127  VSS<52>  SCONN288_H44441004_PIP  I43
  J4B1   129  VSS<51>  SCONN288_H44441004_PIP  I43
  J4B1   131  VSS<50>  SCONN288_H44441004_PIP  I43
  J4B1   134  VSS<49>  SCONN288_H44441004_PIP  I43
  J4B1   136  VSS<48>  SCONN288_H44441004_PIP  I43
  J4B1   138  VSS<47>  SCONN288_H44441004_PIP  I43
  J4B1   139  SA<0>  SCONN288_H44441004_PIP  I111
  J4B1   140  SA<1>  SCONN288_H44441004_PIP  I111
  J4B1   147  VSS<46>  SCONN288_H44441004_PIP  I43
  J4B1   149  VSS<45>  SCONN288_H44441004_PIP  I43
  J4B1   151  VSS<44>  SCONN288_H44441004_PIP  I43
  J4B1   154  VSS<43>  SCONN288_H44441004_PIP  I43
  J4B1   156  VSS<42>  SCONN288_H44441004_PIP  I43
  J4B1   158  VSS<41>  SCONN288_H44441004_PIP  I43
  J4B1   160  VSS<40>  SCONN288_H44441004_PIP  I43
  J4B1   162  VSS<39>  SCONN288_H44441004_PIP  I43
  J4B1   165  VSS<38>  SCONN288_H44441004_PIP  I43
  J4B1   167  VSS<37>  SCONN288_H44441004_PIP  I43
  J4B1   169  VSS<36>  SCONN288_H44441004_PIP  I43
  J4B1   171  VSS<35>  SCONN288_H44441004_PIP  I43
  J4B1   173  VSS<34>  SCONN288_H44441004_PIP  I43
  J4B1   176  VSS<33>  SCONN288_H44441004_PIP  I43
  J4B1   178  VSS<32>  SCONN288_H44441004_PIP  I43
  J4B1   180  VSS<31>  SCONN288_H44441004_PIP  I43
  J4B1   182  VSS<30>  SCONN288_H44441004_PIP  I43
  J4B1   184  VSS<29>  SCONN288_H44441004_PIP  I43
  J4B1   187  VSS<28>  SCONN288_H44441004_PIP  I43
  J4B1   189  VSS<27>  SCONN288_H44441004_PIP  I43
  J4B1   191  VSS<26>  SCONN288_H44441004_PIP  I43
  J4B1   193  VSS<25>  SCONN288_H44441004_PIP  I43
  J4B1   195  VSS<24>  SCONN288_H44441004_PIP  I43
  J4B1   198  VSS<23>  SCONN288_H44441004_PIP  I43
  J4B1   200  VSS<22>  SCONN288_H44441004_PIP  I43
  J4B1   202  VSS<21>  SCONN288_H44441004_PIP  I43
  J4B1   238  SA<2>  SCONN288_H44441004_PIP  I111
  J4B1   239  VSS<20>  SCONN288_H44441004_PIP  I43
  J4B1   241  VSS<19>  SCONN288_H44441004_PIP  I43
  J4B1   243  VSS<18>  SCONN288_H44441004_PIP  I43
  J4B1   246  VSS<17>  SCONN288_H44441004_PIP  I43
  J4B1   248  VSS<16>  SCONN288_H44441004_PIP  I43
  J4B1   250  VSS<15>  SCONN288_H44441004_PIP  I43
  J4B1   252  VSS<14>  SCONN288_H44441004_PIP  I43
  J4B1   254  VSS<13>  SCONN288_H44441004_PIP  I43
  J4B1   257  VSS<12>  SCONN288_H44441004_PIP  I43
  J4B1   259  VSS<11>  SCONN288_H44441004_PIP  I43
  J4B1   261  VSS<10>  SCONN288_H44441004_PIP  I43
  J4B1   263  VSS<9>  SCONN288_H44441004_PIP  I43
  J4B1   265  VSS<8>  SCONN288_H44441004_PIP  I43
  J4B1   268  VSS<7>  SCONN288_H44441004_PIP  I43
  J4B1   270  VSS<6>  SCONN288_H44441004_PIP  I43
  J4B1   272  VSS<5>  SCONN288_H44441004_PIP  I43
  J4B1   274  VSS<4>  SCONN288_H44441004_PIP  I43
  J4B1   276  VSS<3>  SCONN288_H44441004_PIP  I43
  J4B1   279  VSS<2>  SCONN288_H44441004_PIP  I43
  J4B1   281  VSS<1>  SCONN288_H44441004_PIP  I43
  J4B1   283  VSS<0>  SCONN288_H44441004_PIP  I43
  J4B2    A9   IOA9  SCONN120_H61426002_SM  I46
  J4B2   A10  IOA10  SCONN120_H61426002_SM  I46
  J4B2   A12  IOA12  SCONN120_H61426002_SM  I46
  J4B2   A14  IOA14  SCONN120_H61426002_SM  I46
  J4B2   A17  IOA17  SCONN120_H61426002_SM  I46
  J4B2    B9   IOB9  SCONN120_H61426002_SM  I46
  J4B2   B10  IOB10  SCONN120_H61426002_SM  I46
  J4B2   B12  IOB12  SCONN120_H61426002_SM  I46
  J4B2   B14  IOB14  SCONN120_H61426002_SM  I46
  J4B2   B17  IOB17  SCONN120_H61426002_SM  I46
  J4B2    C1   IOC1  SCONN120_H61426002_SM  I46
  J4B2    C2   IOC2  SCONN120_H61426002_SM  I46
  J4B2    C3   IOC3  SCONN120_H61426002_SM  I46
  J4B2    C4   IOC4  SCONN120_H61426002_SM  I46
  J4B2    C5   IOC5  SCONN120_H61426002_SM  I46
  J4B2    C6   IOC6  SCONN120_H61426002_SM  I46
  J4B2    C7   IOC7  SCONN120_H61426002_SM  I46
  J4B2    C8   IOC8  SCONN120_H61426002_SM  I46
  J4B2    C9   IOC9  SCONN120_H61426002_SM  I46
  J4B2   C10  IOC10  SCONN120_H61426002_SM  I46
  J4B2   C12  IOC12  SCONN120_H61426002_SM  I46
  J4B2   C14  IOC14  SCONN120_H61426002_SM  I46
  J4B2   C15  IOC15  SCONN120_H61426002_SM  I46
  J4B2   C16  IOC16  SCONN120_H61426002_SM  I46
  J4B2    D2   IOD2  SCONN120_H61426002_SM  I46
  J4B2    D3   IOD3  SCONN120_H61426002_SM  I46
  J4B2    D4   IOD4  SCONN120_H61426002_SM  I46
  J4B2    D5   IOD5  SCONN120_H61426002_SM  I46
  J4B2    D6   IOD6  SCONN120_H61426002_SM  I46
  J4B2    D7   IOD7  SCONN120_H61426002_SM  I46
  J4B2    D8   IOD8  SCONN120_H61426002_SM  I46
  J4B2    D9   IOD9  SCONN120_H61426002_SM  I46
  J4B2   D10  IOD10  SCONN120_H61426002_SM  I46
  J4B2   D11  IOD11  SCONN120_H61426002_SM  I46
  J4B2   D12  IOD12  SCONN120_H61426002_SM  I46
  J4B2   D13  IOD13  SCONN120_H61426002_SM  I46
  J4B2   D14  IOD14  SCONN120_H61426002_SM  I46
  J4B2    E2   IOE2  SCONN120_H61426002_SM  I46
  J4B2    E3   IOE3  SCONN120_H61426002_SM  I46
  J4B2    E4   IOE4  SCONN120_H61426002_SM  I46
  J4B2    E5   IOE5  SCONN120_H61426002_SM  I46
  J4B2    E6   IOE6  SCONN120_H61426002_SM  I46
  J4B2    E7   IOE7  SCONN120_H61426002_SM  I46
  J4B2    E9   IOE9  SCONN120_H61426002_SM  I46
  J4B2   E11  IOE11  SCONN120_H61426002_SM  I46
  J4B2   E12  IOE12  SCONN120_H61426002_SM  I46
  J4B2   E13  IOE13  SCONN120_H61426002_SM  I46
  J4B2   E14  IOE14  SCONN120_H61426002_SM  I46
  J4B2    F2   IOF2  SCONN120_H61426002_SM  I46
  J4B2    F3   IOF3  SCONN120_H61426002_SM  I46
  J4B2    F4   IOF4  SCONN120_H61426002_SM  I46
  J4B2    F5   IOF5  SCONN120_H61426002_SM  I46
  J4B2    F6   IOF6  SCONN120_H61426002_SM  I46
  J4B2    F7   IOF7  SCONN120_H61426002_SM  I46
  J4B2    F9   IOF9  SCONN120_H61426002_SM  I46
  J4B2   F11  IOF11  SCONN120_H61426002_SM  I46
  J4B2   F12  IOF12  SCONN120_H61426002_SM  I46
  J4B2   F13  IOF13  SCONN120_H61426002_SM  I46
  J4B2   F14  IOF14  SCONN120_H61426002_SM  I46
  J4E1   A19  IOA19  SCONN120_H61426002_SM  I45
  J4E1   A20  IOA20  SCONN120_H61426002_SM  I45
  J4E1   B19  IOB19  SCONN120_H61426002_SM  I45
  J4E1   B20  IOB20  SCONN120_H61426002_SM  I45
  J4E1   C19  IOC19  SCONN120_H61426002_SM  I45
  J4E1   C20  IOC20  SCONN120_H61426002_SM  I45
  J4E1    D3   IOD3  SCONN120_H61426002_SM  I45
  J4E1    D4   IOD4  SCONN120_H61426002_SM  I45
  J4E1    D5   IOD5  SCONN120_H61426002_SM  I45
  J4E1    D6   IOD6  SCONN120_H61426002_SM  I45
  J4E1    D7   IOD7  SCONN120_H61426002_SM  I45
  J4E1    D8   IOD8  SCONN120_H61426002_SM  I45
  J4E1    D9   IOD9  SCONN120_H61426002_SM  I45
  J4E1   D10  IOD10  SCONN120_H61426002_SM  I45
  J4E1   D11  IOD11  SCONN120_H61426002_SM  I45
  J4E1   D12  IOD12  SCONN120_H61426002_SM  I45
  J4E1   D13  IOD13  SCONN120_H61426002_SM  I45
  J4E1   D14  IOD14  SCONN120_H61426002_SM  I45
  J4E1   D15  IOD15  SCONN120_H61426002_SM  I45
  J4E1   D16  IOD16  SCONN120_H61426002_SM  I45
  J4E1   D17  IOD17  SCONN120_H61426002_SM  I45
  J4E1   D18  IOD18  SCONN120_H61426002_SM  I45
  J4E1   D19  IOD19  SCONN120_H61426002_SM  I45
  J4E1   D20  IOD20  SCONN120_H61426002_SM  I45
  J4E1    E3   IOE3  SCONN120_H61426002_SM  I45
  J4E1    E4   IOE4  SCONN120_H61426002_SM  I45
  J4E1    E6   IOE6  SCONN120_H61426002_SM  I45
  J4E1    E7   IOE7  SCONN120_H61426002_SM  I45
  J4E1    E8   IOE8  SCONN120_H61426002_SM  I45
  J4E1    E9   IOE9  SCONN120_H61426002_SM  I45
  J4E1   E10  IOE10  SCONN120_H61426002_SM  I45
  J4E1   E11  IOE11  SCONN120_H61426002_SM  I45
  J4E1   E12  IOE12  SCONN120_H61426002_SM  I45
  J4E1   E13  IOE13  SCONN120_H61426002_SM  I45
  J4E1   E14  IOE14  SCONN120_H61426002_SM  I45
  J4E1   E15  IOE15  SCONN120_H61426002_SM  I45
  J4E1   E16  IOE16  SCONN120_H61426002_SM  I45
  J4E1   E17  IOE17  SCONN120_H61426002_SM  I45
  J4E1   E18  IOE18  SCONN120_H61426002_SM  I45
  J4E1   E19  IOE19  SCONN120_H61426002_SM  I45
  J4E1   E20  IOE20  SCONN120_H61426002_SM  I45
  J4E1    F3   IOF3  SCONN120_H61426002_SM  I45
  J4E1    F4   IOF4  SCONN120_H61426002_SM  I45
  J4E1    F6   IOF6  SCONN120_H61426002_SM  I45
  J4E1    F7   IOF7  SCONN120_H61426002_SM  I45
  J4E1    F8   IOF8  SCONN120_H61426002_SM  I45
  J4E1    F9   IOF9  SCONN120_H61426002_SM  I45
  J4E1   F10  IOF10  SCONN120_H61426002_SM  I45
  J4E1   F11  IOF11  SCONN120_H61426002_SM  I45
  J4E1   F12  IOF12  SCONN120_H61426002_SM  I45
  J4E1   F13  IOF13  SCONN120_H61426002_SM  I45
  J4E1   F14  IOF14  SCONN120_H61426002_SM  I45
  J4E1   F15  IOF15  SCONN120_H61426002_SM  I45
  J4E1   F16  IOF16  SCONN120_H61426002_SM  I45
  J4E1   F17  IOF17  SCONN120_H61426002_SM  I45
  J4E1   F18  IOF18  SCONN120_H61426002_SM  I45
  J4E1   F19  IOF19  SCONN120_H61426002_SM  I45
  J4E1   F20  IOF20  SCONN120_H61426002_SM  I45
  J4G1     2  VSS<93>  SCONN288_H44441004_PIP  I259
  J4G1     4  VSS<92>  SCONN288_H44441004_PIP  I259
  J4G1     6  VSS<91>  SCONN288_H44441004_PIP  I259
  J4G1     9  VSS<90>  SCONN288_H44441004_PIP  I259
  J4G1    11  VSS<89>  SCONN288_H44441004_PIP  I259
  J4G1    13  VSS<88>  SCONN288_H44441004_PIP  I259
  J4G1    15  VSS<87>  SCONN288_H44441004_PIP  I259
  J4G1    17  VSS<86>  SCONN288_H44441004_PIP  I259
  J4G1    20  VSS<85>  SCONN288_H44441004_PIP  I259
  J4G1    22  VSS<84>  SCONN288_H44441004_PIP  I259
  J4G1    24  VSS<83>  SCONN288_H44441004_PIP  I259
  J4G1    26  VSS<82>  SCONN288_H44441004_PIP  I259
  J4G1    28  VSS<81>  SCONN288_H44441004_PIP  I259
  J4G1    31  VSS<80>  SCONN288_H44441004_PIP  I259
  J4G1    33  VSS<79>  SCONN288_H44441004_PIP  I259
  J4G1    35  VSS<78>  SCONN288_H44441004_PIP  I259
  J4G1    37  VSS<77>  SCONN288_H44441004_PIP  I259
  J4G1    39  VSS<76>  SCONN288_H44441004_PIP  I259
  J4G1    42  VSS<75>  SCONN288_H44441004_PIP  I259
  J4G1    44  VSS<74>  SCONN288_H44441004_PIP  I259
  J4G1    46  VSS<73>  SCONN288_H44441004_PIP  I259
  J4G1    48  VSS<72>  SCONN288_H44441004_PIP  I259
  J4G1    50  VSS<71>  SCONN288_H44441004_PIP  I259
  J4G1    53  VSS<70>  SCONN288_H44441004_PIP  I259
  J4G1    55  VSS<69>  SCONN288_H44441004_PIP  I259
  J4G1    57  VSS<68>  SCONN288_H44441004_PIP  I259
  J4G1    94  VSS<67>  SCONN288_H44441004_PIP  I259
  J4G1    96  VSS<66>  SCONN288_H44441004_PIP  I259
  J4G1    98  VSS<65>  SCONN288_H44441004_PIP  I259
  J4G1   101  VSS<64>  SCONN288_H44441004_PIP  I259
  J4G1   103  VSS<63>  SCONN288_H44441004_PIP  I259
  J4G1   105  VSS<62>  SCONN288_H44441004_PIP  I259
  J4G1   107  VSS<61>  SCONN288_H44441004_PIP  I259
  J4G1   109  VSS<60>  SCONN288_H44441004_PIP  I259
  J4G1   112  VSS<59>  SCONN288_H44441004_PIP  I259
  J4G1   114  VSS<58>  SCONN288_H44441004_PIP  I259
  J4G1   116  VSS<57>  SCONN288_H44441004_PIP  I259
  J4G1   118  VSS<56>  SCONN288_H44441004_PIP  I259
  J4G1   120  VSS<55>  SCONN288_H44441004_PIP  I259
  J4G1   123  VSS<54>  SCONN288_H44441004_PIP  I259
  J4G1   125  VSS<53>  SCONN288_H44441004_PIP  I259
  J4G1   127  VSS<52>  SCONN288_H44441004_PIP  I259
  J4G1   129  VSS<51>  SCONN288_H44441004_PIP  I259
  J4G1   131  VSS<50>  SCONN288_H44441004_PIP  I259
  J4G1   134  VSS<49>  SCONN288_H44441004_PIP  I259
  J4G1   136  VSS<48>  SCONN288_H44441004_PIP  I259
  J4G1   138  VSS<47>  SCONN288_H44441004_PIP  I259
  J4G1   139  SA<0>  SCONN288_H44441004_PIP   I1
  J4G1   140  SA<1>  SCONN288_H44441004_PIP   I1
  J4G1   147  VSS<46>  SCONN288_H44441004_PIP  I259
  J4G1   149  VSS<45>  SCONN288_H44441004_PIP  I259
  J4G1   151  VSS<44>  SCONN288_H44441004_PIP  I259
  J4G1   154  VSS<43>  SCONN288_H44441004_PIP  I259
  J4G1   156  VSS<42>  SCONN288_H44441004_PIP  I259
  J4G1   158  VSS<41>  SCONN288_H44441004_PIP  I259
  J4G1   160  VSS<40>  SCONN288_H44441004_PIP  I259
  J4G1   162  VSS<39>  SCONN288_H44441004_PIP  I259
  J4G1   165  VSS<38>  SCONN288_H44441004_PIP  I259
  J4G1   167  VSS<37>  SCONN288_H44441004_PIP  I259
  J4G1   169  VSS<36>  SCONN288_H44441004_PIP  I259
  J4G1   171  VSS<35>  SCONN288_H44441004_PIP  I259
  J4G1   173  VSS<34>  SCONN288_H44441004_PIP  I259
  J4G1   176  VSS<33>  SCONN288_H44441004_PIP  I259
  J4G1   178  VSS<32>  SCONN288_H44441004_PIP  I259
  J4G1   180  VSS<31>  SCONN288_H44441004_PIP  I259
  J4G1   182  VSS<30>  SCONN288_H44441004_PIP  I259
  J4G1   184  VSS<29>  SCONN288_H44441004_PIP  I259
  J4G1   187  VSS<28>  SCONN288_H44441004_PIP  I259
  J4G1   189  VSS<27>  SCONN288_H44441004_PIP  I259
  J4G1   191  VSS<26>  SCONN288_H44441004_PIP  I259
  J4G1   193  VSS<25>  SCONN288_H44441004_PIP  I259
  J4G1   195  VSS<24>  SCONN288_H44441004_PIP  I259
  J4G1   198  VSS<23>  SCONN288_H44441004_PIP  I259
  J4G1   200  VSS<22>  SCONN288_H44441004_PIP  I259
  J4G1   202  VSS<21>  SCONN288_H44441004_PIP  I259
  J4G1   238  SA<2>  SCONN288_H44441004_PIP   I1
  J4G1   239  VSS<20>  SCONN288_H44441004_PIP  I259
  J4G1   241  VSS<19>  SCONN288_H44441004_PIP  I259
  J4G1   243  VSS<18>  SCONN288_H44441004_PIP  I259
  J4G1   246  VSS<17>  SCONN288_H44441004_PIP  I259
  J4G1   248  VSS<16>  SCONN288_H44441004_PIP  I259
  J4G1   250  VSS<15>  SCONN288_H44441004_PIP  I259
  J4G1   252  VSS<14>  SCONN288_H44441004_PIP  I259
  J4G1   254  VSS<13>  SCONN288_H44441004_PIP  I259
  J4G1   257  VSS<12>  SCONN288_H44441004_PIP  I259
  J4G1   259  VSS<11>  SCONN288_H44441004_PIP  I259
  J4G1   261  VSS<10>  SCONN288_H44441004_PIP  I259
  J4G1   263  VSS<9>  SCONN288_H44441004_PIP  I259
  J4G1   265  VSS<8>  SCONN288_H44441004_PIP  I259
  J4G1   268  VSS<7>  SCONN288_H44441004_PIP  I259
  J4G1   270  VSS<6>  SCONN288_H44441004_PIP  I259
  J4G1   272  VSS<5>  SCONN288_H44441004_PIP  I259
  J4G1   274  VSS<4>  SCONN288_H44441004_PIP  I259
  J4G1   276  VSS<3>  SCONN288_H44441004_PIP  I259
  J4G1   279  VSS<2>  SCONN288_H44441004_PIP  I259
  J4G1   281  VSS<1>  SCONN288_H44441004_PIP  I259
  J4G1   283  VSS<0>  SCONN288_H44441004_PIP  I259
  J4G2     2  VSS<93>  SCONN288_H44441004_PIP  I43
  J4G2     4  VSS<92>  SCONN288_H44441004_PIP  I43
  J4G2     6  VSS<91>  SCONN288_H44441004_PIP  I43
  J4G2     9  VSS<90>  SCONN288_H44441004_PIP  I43
  J4G2    11  VSS<89>  SCONN288_H44441004_PIP  I43
  J4G2    13  VSS<88>  SCONN288_H44441004_PIP  I43
  J4G2    15  VSS<87>  SCONN288_H44441004_PIP  I43
  J4G2    17  VSS<86>  SCONN288_H44441004_PIP  I43
  J4G2    20  VSS<85>  SCONN288_H44441004_PIP  I43
  J4G2    22  VSS<84>  SCONN288_H44441004_PIP  I43
  J4G2    24  VSS<83>  SCONN288_H44441004_PIP  I43
  J4G2    26  VSS<82>  SCONN288_H44441004_PIP  I43
  J4G2    28  VSS<81>  SCONN288_H44441004_PIP  I43
  J4G2    31  VSS<80>  SCONN288_H44441004_PIP  I43
  J4G2    33  VSS<79>  SCONN288_H44441004_PIP  I43
  J4G2    35  VSS<78>  SCONN288_H44441004_PIP  I43
  J4G2    37  VSS<77>  SCONN288_H44441004_PIP  I43
  J4G2    39  VSS<76>  SCONN288_H44441004_PIP  I43
  J4G2    42  VSS<75>  SCONN288_H44441004_PIP  I43
  J4G2    44  VSS<74>  SCONN288_H44441004_PIP  I43
  J4G2    46  VSS<73>  SCONN288_H44441004_PIP  I43
  J4G2    48  VSS<72>  SCONN288_H44441004_PIP  I43
  J4G2    50  VSS<71>  SCONN288_H44441004_PIP  I43
  J4G2    53  VSS<70>  SCONN288_H44441004_PIP  I43
  J4G2    55  VSS<69>  SCONN288_H44441004_PIP  I43
  J4G2    57  VSS<68>  SCONN288_H44441004_PIP  I43
  J4G2    94  VSS<67>  SCONN288_H44441004_PIP  I43
  J4G2    96  VSS<66>  SCONN288_H44441004_PIP  I43
  J4G2    98  VSS<65>  SCONN288_H44441004_PIP  I43
  J4G2   101  VSS<64>  SCONN288_H44441004_PIP  I43
  J4G2   103  VSS<63>  SCONN288_H44441004_PIP  I43
  J4G2   105  VSS<62>  SCONN288_H44441004_PIP  I43
  J4G2   107  VSS<61>  SCONN288_H44441004_PIP  I43
  J4G2   109  VSS<60>  SCONN288_H44441004_PIP  I43
  J4G2   112  VSS<59>  SCONN288_H44441004_PIP  I43
  J4G2   114  VSS<58>  SCONN288_H44441004_PIP  I43
  J4G2   116  VSS<57>  SCONN288_H44441004_PIP  I43
  J4G2   118  VSS<56>  SCONN288_H44441004_PIP  I43
  J4G2   120  VSS<55>  SCONN288_H44441004_PIP  I43
  J4G2   123  VSS<54>  SCONN288_H44441004_PIP  I43
  J4G2   125  VSS<53>  SCONN288_H44441004_PIP  I43
  J4G2   127  VSS<52>  SCONN288_H44441004_PIP  I43
  J4G2   129  VSS<51>  SCONN288_H44441004_PIP  I43
  J4G2   131  VSS<50>  SCONN288_H44441004_PIP  I43
  J4G2   134  VSS<49>  SCONN288_H44441004_PIP  I43
  J4G2   136  VSS<48>  SCONN288_H44441004_PIP  I43
  J4G2   138  VSS<47>  SCONN288_H44441004_PIP  I43
  J4G2   139  SA<0>  SCONN288_H44441004_PIP  I111
  J4G2   147  VSS<46>  SCONN288_H44441004_PIP  I43
  J4G2   149  VSS<45>  SCONN288_H44441004_PIP  I43
  J4G2   151  VSS<44>  SCONN288_H44441004_PIP  I43
  J4G2   154  VSS<43>  SCONN288_H44441004_PIP  I43
  J4G2   156  VSS<42>  SCONN288_H44441004_PIP  I43
  J4G2   158  VSS<41>  SCONN288_H44441004_PIP  I43
  J4G2   160  VSS<40>  SCONN288_H44441004_PIP  I43
  J4G2   162  VSS<39>  SCONN288_H44441004_PIP  I43
  J4G2   165  VSS<38>  SCONN288_H44441004_PIP  I43
  J4G2   167  VSS<37>  SCONN288_H44441004_PIP  I43
  J4G2   169  VSS<36>  SCONN288_H44441004_PIP  I43
  J4G2   171  VSS<35>  SCONN288_H44441004_PIP  I43
  J4G2   173  VSS<34>  SCONN288_H44441004_PIP  I43
  J4G2   176  VSS<33>  SCONN288_H44441004_PIP  I43
  J4G2   178  VSS<32>  SCONN288_H44441004_PIP  I43
  J4G2   180  VSS<31>  SCONN288_H44441004_PIP  I43
  J4G2   182  VSS<30>  SCONN288_H44441004_PIP  I43
  J4G2   184  VSS<29>  SCONN288_H44441004_PIP  I43
  J4G2   187  VSS<28>  SCONN288_H44441004_PIP  I43
  J4G2   189  VSS<27>  SCONN288_H44441004_PIP  I43
  J4G2   191  VSS<26>  SCONN288_H44441004_PIP  I43
  J4G2   193  VSS<25>  SCONN288_H44441004_PIP  I43
  J4G2   195  VSS<24>  SCONN288_H44441004_PIP  I43
  J4G2   198  VSS<23>  SCONN288_H44441004_PIP  I43
  J4G2   200  VSS<22>  SCONN288_H44441004_PIP  I43
  J4G2   202  VSS<21>  SCONN288_H44441004_PIP  I43
  J4G2   238  SA<2>  SCONN288_H44441004_PIP  I111
  J4G2   239  VSS<20>  SCONN288_H44441004_PIP  I43
  J4G2   241  VSS<19>  SCONN288_H44441004_PIP  I43
  J4G2   243  VSS<18>  SCONN288_H44441004_PIP  I43
  J4G2   246  VSS<17>  SCONN288_H44441004_PIP  I43
  J4G2   248  VSS<16>  SCONN288_H44441004_PIP  I43
  J4G2   250  VSS<15>  SCONN288_H44441004_PIP  I43
  J4G2   252  VSS<14>  SCONN288_H44441004_PIP  I43
  J4G2   254  VSS<13>  SCONN288_H44441004_PIP  I43
  J4G2   257  VSS<12>  SCONN288_H44441004_PIP  I43
  J4G2   259  VSS<11>  SCONN288_H44441004_PIP  I43
  J4G2   261  VSS<10>  SCONN288_H44441004_PIP  I43
  J4G2   263  VSS<9>  SCONN288_H44441004_PIP  I43
  J4G2   265  VSS<8>  SCONN288_H44441004_PIP  I43
  J4G2   268  VSS<7>  SCONN288_H44441004_PIP  I43
  J4G2   270  VSS<6>  SCONN288_H44441004_PIP  I43
  J4G2   272  VSS<5>  SCONN288_H44441004_PIP  I43
  J4G2   274  VSS<4>  SCONN288_H44441004_PIP  I43
  J4G2   276  VSS<3>  SCONN288_H44441004_PIP  I43
  J4G2   279  VSS<2>  SCONN288_H44441004_PIP  I43
  J4G2   281  VSS<1>  SCONN288_H44441004_PIP  I43
  J4G2   283  VSS<0>  SCONN288_H44441004_PIP  I43
  J4G3     2  VSS<93>  SCONN288_H44441004_PIP  I43
  J4G3     4  VSS<92>  SCONN288_H44441004_PIP  I43
  J4G3     6  VSS<91>  SCONN288_H44441004_PIP  I43
  J4G3     9  VSS<90>  SCONN288_H44441004_PIP  I43
  J4G3    11  VSS<89>  SCONN288_H44441004_PIP  I43
  J4G3    13  VSS<88>  SCONN288_H44441004_PIP  I43
  J4G3    15  VSS<87>  SCONN288_H44441004_PIP  I43
  J4G3    17  VSS<86>  SCONN288_H44441004_PIP  I43
  J4G3    20  VSS<85>  SCONN288_H44441004_PIP  I43
  J4G3    22  VSS<84>  SCONN288_H44441004_PIP  I43
  J4G3    24  VSS<83>  SCONN288_H44441004_PIP  I43
  J4G3    26  VSS<82>  SCONN288_H44441004_PIP  I43
  J4G3    28  VSS<81>  SCONN288_H44441004_PIP  I43
  J4G3    31  VSS<80>  SCONN288_H44441004_PIP  I43
  J4G3    33  VSS<79>  SCONN288_H44441004_PIP  I43
  J4G3    35  VSS<78>  SCONN288_H44441004_PIP  I43
  J4G3    37  VSS<77>  SCONN288_H44441004_PIP  I43
  J4G3    39  VSS<76>  SCONN288_H44441004_PIP  I43
  J4G3    42  VSS<75>  SCONN288_H44441004_PIP  I43
  J4G3    44  VSS<74>  SCONN288_H44441004_PIP  I43
  J4G3    46  VSS<73>  SCONN288_H44441004_PIP  I43
  J4G3    48  VSS<72>  SCONN288_H44441004_PIP  I43
  J4G3    50  VSS<71>  SCONN288_H44441004_PIP  I43
  J4G3    53  VSS<70>  SCONN288_H44441004_PIP  I43
  J4G3    55  VSS<69>  SCONN288_H44441004_PIP  I43
  J4G3    57  VSS<68>  SCONN288_H44441004_PIP  I43
  J4G3    94  VSS<67>  SCONN288_H44441004_PIP  I43
  J4G3    96  VSS<66>  SCONN288_H44441004_PIP  I43
  J4G3    98  VSS<65>  SCONN288_H44441004_PIP  I43
  J4G3   101  VSS<64>  SCONN288_H44441004_PIP  I43
  J4G3   103  VSS<63>  SCONN288_H44441004_PIP  I43
  J4G3   105  VSS<62>  SCONN288_H44441004_PIP  I43
  J4G3   107  VSS<61>  SCONN288_H44441004_PIP  I43
  J4G3   109  VSS<60>  SCONN288_H44441004_PIP  I43
  J4G3   112  VSS<59>  SCONN288_H44441004_PIP  I43
  J4G3   114  VSS<58>  SCONN288_H44441004_PIP  I43
  J4G3   116  VSS<57>  SCONN288_H44441004_PIP  I43
  J4G3   118  VSS<56>  SCONN288_H44441004_PIP  I43
  J4G3   120  VSS<55>  SCONN288_H44441004_PIP  I43
  J4G3   123  VSS<54>  SCONN288_H44441004_PIP  I43
  J4G3   125  VSS<53>  SCONN288_H44441004_PIP  I43
  J4G3   127  VSS<52>  SCONN288_H44441004_PIP  I43
  J4G3   129  VSS<51>  SCONN288_H44441004_PIP  I43
  J4G3   131  VSS<50>  SCONN288_H44441004_PIP  I43
  J4G3   134  VSS<49>  SCONN288_H44441004_PIP  I43
  J4G3   136  VSS<48>  SCONN288_H44441004_PIP  I43
  J4G3   138  VSS<47>  SCONN288_H44441004_PIP  I43
  J4G3   139  SA<0>  SCONN288_H44441004_PIP  I111
  J4G3   140  SA<1>  SCONN288_H44441004_PIP  I111
  J4G3   147  VSS<46>  SCONN288_H44441004_PIP  I43
  J4G3   149  VSS<45>  SCONN288_H44441004_PIP  I43
  J4G3   151  VSS<44>  SCONN288_H44441004_PIP  I43
  J4G3   154  VSS<43>  SCONN288_H44441004_PIP  I43
  J4G3   156  VSS<42>  SCONN288_H44441004_PIP  I43
  J4G3   158  VSS<41>  SCONN288_H44441004_PIP  I43
  J4G3   160  VSS<40>  SCONN288_H44441004_PIP  I43
  J4G3   162  VSS<39>  SCONN288_H44441004_PIP  I43
  J4G3   165  VSS<38>  SCONN288_H44441004_PIP  I43
  J4G3   167  VSS<37>  SCONN288_H44441004_PIP  I43
  J4G3   169  VSS<36>  SCONN288_H44441004_PIP  I43
  J4G3   171  VSS<35>  SCONN288_H44441004_PIP  I43
  J4G3   173  VSS<34>  SCONN288_H44441004_PIP  I43
  J4G3   176  VSS<33>  SCONN288_H44441004_PIP  I43
  J4G3   178  VSS<32>  SCONN288_H44441004_PIP  I43
  J4G3   180  VSS<31>  SCONN288_H44441004_PIP  I43
  J4G3   182  VSS<30>  SCONN288_H44441004_PIP  I43
  J4G3   184  VSS<29>  SCONN288_H44441004_PIP  I43
  J4G3   187  VSS<28>  SCONN288_H44441004_PIP  I43
  J4G3   189  VSS<27>  SCONN288_H44441004_PIP  I43
  J4G3   191  VSS<26>  SCONN288_H44441004_PIP  I43
  J4G3   193  VSS<25>  SCONN288_H44441004_PIP  I43
  J4G3   195  VSS<24>  SCONN288_H44441004_PIP  I43
  J4G3   198  VSS<23>  SCONN288_H44441004_PIP  I43
  J4G3   200  VSS<22>  SCONN288_H44441004_PIP  I43
  J4G3   202  VSS<21>  SCONN288_H44441004_PIP  I43
  J4G3   239  VSS<20>  SCONN288_H44441004_PIP  I43
  J4G3   241  VSS<19>  SCONN288_H44441004_PIP  I43
  J4G3   243  VSS<18>  SCONN288_H44441004_PIP  I43
  J4G3   246  VSS<17>  SCONN288_H44441004_PIP  I43
  J4G3   248  VSS<16>  SCONN288_H44441004_PIP  I43
  J4G3   250  VSS<15>  SCONN288_H44441004_PIP  I43
  J4G3   252  VSS<14>  SCONN288_H44441004_PIP  I43
  J4G3   254  VSS<13>  SCONN288_H44441004_PIP  I43
  J4G3   257  VSS<12>  SCONN288_H44441004_PIP  I43
  J4G3   259  VSS<11>  SCONN288_H44441004_PIP  I43
  J4G3   261  VSS<10>  SCONN288_H44441004_PIP  I43
  J4G3   263  VSS<9>  SCONN288_H44441004_PIP  I43
  J4G3   265  VSS<8>  SCONN288_H44441004_PIP  I43
  J4G3   268  VSS<7>  SCONN288_H44441004_PIP  I43
  J4G3   270  VSS<6>  SCONN288_H44441004_PIP  I43
  J4G3   272  VSS<5>  SCONN288_H44441004_PIP  I43
  J4G3   274  VSS<4>  SCONN288_H44441004_PIP  I43
  J4G3   276  VSS<3>  SCONN288_H44441004_PIP  I43
  J4G3   279  VSS<2>  SCONN288_H44441004_PIP  I43
  J4G3   281  VSS<1>  SCONN288_H44441004_PIP  I43
  J4G3   283  VSS<0>  SCONN288_H44441004_PIP  I43
  J6B1    A9   IOA9  SCONN120_H61426002_SM  I56
  J6B1   A10  IOA10  SCONN120_H61426002_SM  I56
  J6B1   A12  IOA12  SCONN120_H61426002_SM  I56
  J6B1   A14  IOA14  SCONN120_H61426002_SM  I56
  J6B1   A17  IOA17  SCONN120_H61426002_SM  I56
  J6B1    B9   IOB9  SCONN120_H61426002_SM  I56
  J6B1   B10  IOB10  SCONN120_H61426002_SM  I56
  J6B1   B12  IOB12  SCONN120_H61426002_SM  I56
  J6B1   B14  IOB14  SCONN120_H61426002_SM  I56
  J6B1   B17  IOB17  SCONN120_H61426002_SM  I56
  J6B1    C1   IOC1  SCONN120_H61426002_SM  I56
  J6B1    C2   IOC2  SCONN120_H61426002_SM  I56
  J6B1    C3   IOC3  SCONN120_H61426002_SM  I56
  J6B1    C4   IOC4  SCONN120_H61426002_SM  I56
  J6B1    C5   IOC5  SCONN120_H61426002_SM  I56
  J6B1    C6   IOC6  SCONN120_H61426002_SM  I56
  J6B1    C7   IOC7  SCONN120_H61426002_SM  I56
  J6B1    C8   IOC8  SCONN120_H61426002_SM  I56
  J6B1    C9   IOC9  SCONN120_H61426002_SM  I56
  J6B1   C10  IOC10  SCONN120_H61426002_SM  I56
  J6B1   C12  IOC12  SCONN120_H61426002_SM  I56
  J6B1   C14  IOC14  SCONN120_H61426002_SM  I56
  J6B1   C15  IOC15  SCONN120_H61426002_SM  I56
  J6B1   C16  IOC16  SCONN120_H61426002_SM  I56
  J6B1    D2   IOD2  SCONN120_H61426002_SM  I56
  J6B1    D3   IOD3  SCONN120_H61426002_SM  I56
  J6B1    D4   IOD4  SCONN120_H61426002_SM  I56
  J6B1    D5   IOD5  SCONN120_H61426002_SM  I56
  J6B1    D6   IOD6  SCONN120_H61426002_SM  I56
  J6B1    D7   IOD7  SCONN120_H61426002_SM  I56
  J6B1    D8   IOD8  SCONN120_H61426002_SM  I56
  J6B1    D9   IOD9  SCONN120_H61426002_SM  I56
  J6B1   D10  IOD10  SCONN120_H61426002_SM  I56
  J6B1   D11  IOD11  SCONN120_H61426002_SM  I56
  J6B1   D12  IOD12  SCONN120_H61426002_SM  I56
  J6B1   D13  IOD13  SCONN120_H61426002_SM  I56
  J6B1   D14  IOD14  SCONN120_H61426002_SM  I56
  J6B1    E2   IOE2  SCONN120_H61426002_SM  I56
  J6B1    E3   IOE3  SCONN120_H61426002_SM  I56
  J6B1    E4   IOE4  SCONN120_H61426002_SM  I56
  J6B1    E5   IOE5  SCONN120_H61426002_SM  I56
  J6B1    E6   IOE6  SCONN120_H61426002_SM  I56
  J6B1    E7   IOE7  SCONN120_H61426002_SM  I56
  J6B1    E9   IOE9  SCONN120_H61426002_SM  I56
  J6B1   E11  IOE11  SCONN120_H61426002_SM  I56
  J6B1   E12  IOE12  SCONN120_H61426002_SM  I56
  J6B1   E13  IOE13  SCONN120_H61426002_SM  I56
  J6B1   E14  IOE14  SCONN120_H61426002_SM  I56
  J6B1    F2   IOF2  SCONN120_H61426002_SM  I56
  J6B1    F3   IOF3  SCONN120_H61426002_SM  I56
  J6B1    F4   IOF4  SCONN120_H61426002_SM  I56
  J6B1    F5   IOF5  SCONN120_H61426002_SM  I56
  J6B1    F6   IOF6  SCONN120_H61426002_SM  I56
  J6B1    F7   IOF7  SCONN120_H61426002_SM  I56
  J6B1    F9   IOF9  SCONN120_H61426002_SM  I56
  J6B1   F11  IOF11  SCONN120_H61426002_SM  I56
  J6B1   F12  IOF12  SCONN120_H61426002_SM  I56
  J6B1   F13  IOF13  SCONN120_H61426002_SM  I56
  J6B1   F14  IOF14  SCONN120_H61426002_SM  I56
  J6E1   A19  IOA19  SCONN120_H61426002_SM  I55
  J6E1   A20  IOA20  SCONN120_H61426002_SM  I55
  J6E1   B19  IOB19  SCONN120_H61426002_SM  I55
  J6E1   B20  IOB20  SCONN120_H61426002_SM  I55
  J6E1   C19  IOC19  SCONN120_H61426002_SM  I55
  J6E1   C20  IOC20  SCONN120_H61426002_SM  I55
  J6E1    D3   IOD3  SCONN120_H61426002_SM  I55
  J6E1    D4   IOD4  SCONN120_H61426002_SM  I55
  J6E1    D5   IOD5  SCONN120_H61426002_SM  I55
  J6E1    D6   IOD6  SCONN120_H61426002_SM  I55
  J6E1    D7   IOD7  SCONN120_H61426002_SM  I55
  J6E1    D8   IOD8  SCONN120_H61426002_SM  I55
  J6E1    D9   IOD9  SCONN120_H61426002_SM  I55
  J6E1   D10  IOD10  SCONN120_H61426002_SM  I55
  J6E1   D11  IOD11  SCONN120_H61426002_SM  I55
  J6E1   D12  IOD12  SCONN120_H61426002_SM  I55
  J6E1   D13  IOD13  SCONN120_H61426002_SM  I55
  J6E1   D14  IOD14  SCONN120_H61426002_SM  I55
  J6E1   D15  IOD15  SCONN120_H61426002_SM  I55
  J6E1   D16  IOD16  SCONN120_H61426002_SM  I55
  J6E1   D17  IOD17  SCONN120_H61426002_SM  I55
  J6E1   D18  IOD18  SCONN120_H61426002_SM  I55
  J6E1   D19  IOD19  SCONN120_H61426002_SM  I55
  J6E1   D20  IOD20  SCONN120_H61426002_SM  I55
  J6E1    E3   IOE3  SCONN120_H61426002_SM  I55
  J6E1    E4   IOE4  SCONN120_H61426002_SM  I55
  J6E1    E6   IOE6  SCONN120_H61426002_SM  I55
  J6E1    E7   IOE7  SCONN120_H61426002_SM  I55
  J6E1    E8   IOE8  SCONN120_H61426002_SM  I55
  J6E1    E9   IOE9  SCONN120_H61426002_SM  I55
  J6E1   E10  IOE10  SCONN120_H61426002_SM  I55
  J6E1   E11  IOE11  SCONN120_H61426002_SM  I55
  J6E1   E12  IOE12  SCONN120_H61426002_SM  I55
  J6E1   E13  IOE13  SCONN120_H61426002_SM  I55
  J6E1   E14  IOE14  SCONN120_H61426002_SM  I55
  J6E1   E15  IOE15  SCONN120_H61426002_SM  I55
  J6E1   E16  IOE16  SCONN120_H61426002_SM  I55
  J6E1   E17  IOE17  SCONN120_H61426002_SM  I55
  J6E1   E18  IOE18  SCONN120_H61426002_SM  I55
  J6E1   E19  IOE19  SCONN120_H61426002_SM  I55
  J6E1   E20  IOE20  SCONN120_H61426002_SM  I55
  J6E1    F3   IOF3  SCONN120_H61426002_SM  I55
  J6E1    F4   IOF4  SCONN120_H61426002_SM  I55
  J6E1    F6   IOF6  SCONN120_H61426002_SM  I55
  J6E1    F7   IOF7  SCONN120_H61426002_SM  I55
  J6E1    F8   IOF8  SCONN120_H61426002_SM  I55
  J6E1    F9   IOF9  SCONN120_H61426002_SM  I55
  J6E1   F10  IOF10  SCONN120_H61426002_SM  I55
  J6E1   F11  IOF11  SCONN120_H61426002_SM  I55
  J6E1   F12  IOF12  SCONN120_H61426002_SM  I55
  J6E1   F13  IOF13  SCONN120_H61426002_SM  I55
  J6E1   F14  IOF14  SCONN120_H61426002_SM  I55
  J6E1   F15  IOF15  SCONN120_H61426002_SM  I55
  J6E1   F16  IOF16  SCONN120_H61426002_SM  I55
  J6E1   F17  IOF17  SCONN120_H61426002_SM  I55
  J6E1   F18  IOF18  SCONN120_H61426002_SM  I55
  J6E1   F19  IOF19  SCONN120_H61426002_SM  I55
  J6E1   F20  IOF20  SCONN120_H61426002_SM  I55
  J6L1     2  VSS<93>  SCONN288_H44441003_PIP  I43
  J6L1     4  VSS<92>  SCONN288_H44441003_PIP  I43
  J6L1     6  VSS<91>  SCONN288_H44441003_PIP  I43
  J6L1     9  VSS<90>  SCONN288_H44441003_PIP  I43
  J6L1    11  VSS<89>  SCONN288_H44441003_PIP  I43
  J6L1    13  VSS<88>  SCONN288_H44441003_PIP  I43
  J6L1    15  VSS<87>  SCONN288_H44441003_PIP  I43
  J6L1    17  VSS<86>  SCONN288_H44441003_PIP  I43
  J6L1    20  VSS<85>  SCONN288_H44441003_PIP  I43
  J6L1    22  VSS<84>  SCONN288_H44441003_PIP  I43
  J6L1    24  VSS<83>  SCONN288_H44441003_PIP  I43
  J6L1    26  VSS<82>  SCONN288_H44441003_PIP  I43
  J6L1    28  VSS<81>  SCONN288_H44441003_PIP  I43
  J6L1    31  VSS<80>  SCONN288_H44441003_PIP  I43
  J6L1    33  VSS<79>  SCONN288_H44441003_PIP  I43
  J6L1    35  VSS<78>  SCONN288_H44441003_PIP  I43
  J6L1    37  VSS<77>  SCONN288_H44441003_PIP  I43
  J6L1    39  VSS<76>  SCONN288_H44441003_PIP  I43
  J6L1    42  VSS<75>  SCONN288_H44441003_PIP  I43
  J6L1    44  VSS<74>  SCONN288_H44441003_PIP  I43
  J6L1    46  VSS<73>  SCONN288_H44441003_PIP  I43
  J6L1    48  VSS<72>  SCONN288_H44441003_PIP  I43
  J6L1    50  VSS<71>  SCONN288_H44441003_PIP  I43
  J6L1    53  VSS<70>  SCONN288_H44441003_PIP  I43
  J6L1    55  VSS<69>  SCONN288_H44441003_PIP  I43
  J6L1    57  VSS<68>  SCONN288_H44441003_PIP  I43
  J6L1    94  VSS<67>  SCONN288_H44441003_PIP  I43
  J6L1    96  VSS<66>  SCONN288_H44441003_PIP  I43
  J6L1    98  VSS<65>  SCONN288_H44441003_PIP  I43
  J6L1   101  VSS<64>  SCONN288_H44441003_PIP  I43
  J6L1   103  VSS<63>  SCONN288_H44441003_PIP  I43
  J6L1   105  VSS<62>  SCONN288_H44441003_PIP  I43
  J6L1   107  VSS<61>  SCONN288_H44441003_PIP  I43
  J6L1   109  VSS<60>  SCONN288_H44441003_PIP  I43
  J6L1   112  VSS<59>  SCONN288_H44441003_PIP  I43
  J6L1   114  VSS<58>  SCONN288_H44441003_PIP  I43
  J6L1   116  VSS<57>  SCONN288_H44441003_PIP  I43
  J6L1   118  VSS<56>  SCONN288_H44441003_PIP  I43
  J6L1   120  VSS<55>  SCONN288_H44441003_PIP  I43
  J6L1   123  VSS<54>  SCONN288_H44441003_PIP  I43
  J6L1   125  VSS<53>  SCONN288_H44441003_PIP  I43
  J6L1   127  VSS<52>  SCONN288_H44441003_PIP  I43
  J6L1   129  VSS<51>  SCONN288_H44441003_PIP  I43
  J6L1   131  VSS<50>  SCONN288_H44441003_PIP  I43
  J6L1   134  VSS<49>  SCONN288_H44441003_PIP  I43
  J6L1   136  VSS<48>  SCONN288_H44441003_PIP  I43
  J6L1   138  VSS<47>  SCONN288_H44441003_PIP  I43
  J6L1   140  SA<1>  SCONN288_H44441003_PIP  I111
  J6L1   147  VSS<46>  SCONN288_H44441003_PIP  I43
  J6L1   149  VSS<45>  SCONN288_H44441003_PIP  I43
  J6L1   151  VSS<44>  SCONN288_H44441003_PIP  I43
  J6L1   154  VSS<43>  SCONN288_H44441003_PIP  I43
  J6L1   156  VSS<42>  SCONN288_H44441003_PIP  I43
  J6L1   158  VSS<41>  SCONN288_H44441003_PIP  I43
  J6L1   160  VSS<40>  SCONN288_H44441003_PIP  I43
  J6L1   162  VSS<39>  SCONN288_H44441003_PIP  I43
  J6L1   165  VSS<38>  SCONN288_H44441003_PIP  I43
  J6L1   167  VSS<37>  SCONN288_H44441003_PIP  I43
  J6L1   169  VSS<36>  SCONN288_H44441003_PIP  I43
  J6L1   171  VSS<35>  SCONN288_H44441003_PIP  I43
  J6L1   173  VSS<34>  SCONN288_H44441003_PIP  I43
  J6L1   176  VSS<33>  SCONN288_H44441003_PIP  I43
  J6L1   178  VSS<32>  SCONN288_H44441003_PIP  I43
  J6L1   180  VSS<31>  SCONN288_H44441003_PIP  I43
  J6L1   182  VSS<30>  SCONN288_H44441003_PIP  I43
  J6L1   184  VSS<29>  SCONN288_H44441003_PIP  I43
  J6L1   187  VSS<28>  SCONN288_H44441003_PIP  I43
  J6L1   189  VSS<27>  SCONN288_H44441003_PIP  I43
  J6L1   191  VSS<26>  SCONN288_H44441003_PIP  I43
  J6L1   193  VSS<25>  SCONN288_H44441003_PIP  I43
  J6L1   195  VSS<24>  SCONN288_H44441003_PIP  I43
  J6L1   198  VSS<23>  SCONN288_H44441003_PIP  I43
  J6L1   200  VSS<22>  SCONN288_H44441003_PIP  I43
  J6L1   202  VSS<21>  SCONN288_H44441003_PIP  I43
  J6L1   239  VSS<20>  SCONN288_H44441003_PIP  I43
  J6L1   241  VSS<19>  SCONN288_H44441003_PIP  I43
  J6L1   243  VSS<18>  SCONN288_H44441003_PIP  I43
  J6L1   246  VSS<17>  SCONN288_H44441003_PIP  I43
  J6L1   248  VSS<16>  SCONN288_H44441003_PIP  I43
  J6L1   250  VSS<15>  SCONN288_H44441003_PIP  I43
  J6L1   252  VSS<14>  SCONN288_H44441003_PIP  I43
  J6L1   254  VSS<13>  SCONN288_H44441003_PIP  I43
  J6L1   257  VSS<12>  SCONN288_H44441003_PIP  I43
  J6L1   259  VSS<11>  SCONN288_H44441003_PIP  I43
  J6L1   261  VSS<10>  SCONN288_H44441003_PIP  I43
  J6L1   263  VSS<9>  SCONN288_H44441003_PIP  I43
  J6L1   265  VSS<8>  SCONN288_H44441003_PIP  I43
  J6L1   268  VSS<7>  SCONN288_H44441003_PIP  I43
  J6L1   270  VSS<6>  SCONN288_H44441003_PIP  I43
  J6L1   272  VSS<5>  SCONN288_H44441003_PIP  I43
  J6L1   274  VSS<4>  SCONN288_H44441003_PIP  I43
  J6L1   276  VSS<3>  SCONN288_H44441003_PIP  I43
  J6L1   279  VSS<2>  SCONN288_H44441003_PIP  I43
  J6L1   281  VSS<1>  SCONN288_H44441003_PIP  I43
  J6L1   283  VSS<0>  SCONN288_H44441003_PIP  I43
  J6L2     2  VSS<93>  SCONN288_H44441003_PIP  I138
  J6L2     4  VSS<92>  SCONN288_H44441003_PIP  I138
  J6L2     6  VSS<91>  SCONN288_H44441003_PIP  I138
  J6L2     9  VSS<90>  SCONN288_H44441003_PIP  I138
  J6L2    11  VSS<89>  SCONN288_H44441003_PIP  I138
  J6L2    13  VSS<88>  SCONN288_H44441003_PIP  I138
  J6L2    15  VSS<87>  SCONN288_H44441003_PIP  I138
  J6L2    17  VSS<86>  SCONN288_H44441003_PIP  I138
  J6L2    20  VSS<85>  SCONN288_H44441003_PIP  I138
  J6L2    22  VSS<84>  SCONN288_H44441003_PIP  I138
  J6L2    24  VSS<83>  SCONN288_H44441003_PIP  I138
  J6L2    26  VSS<82>  SCONN288_H44441003_PIP  I138
  J6L2    28  VSS<81>  SCONN288_H44441003_PIP  I138
  J6L2    31  VSS<80>  SCONN288_H44441003_PIP  I138
  J6L2    33  VSS<79>  SCONN288_H44441003_PIP  I138
  J6L2    35  VSS<78>  SCONN288_H44441003_PIP  I138
  J6L2    37  VSS<77>  SCONN288_H44441003_PIP  I138
  J6L2    39  VSS<76>  SCONN288_H44441003_PIP  I138
  J6L2    42  VSS<75>  SCONN288_H44441003_PIP  I138
  J6L2    44  VSS<74>  SCONN288_H44441003_PIP  I138
  J6L2    46  VSS<73>  SCONN288_H44441003_PIP  I138
  J6L2    48  VSS<72>  SCONN288_H44441003_PIP  I138
  J6L2    50  VSS<71>  SCONN288_H44441003_PIP  I138
  J6L2    53  VSS<70>  SCONN288_H44441003_PIP  I138
  J6L2    55  VSS<69>  SCONN288_H44441003_PIP  I138
  J6L2    57  VSS<68>  SCONN288_H44441003_PIP  I138
  J6L2    94  VSS<67>  SCONN288_H44441003_PIP  I138
  J6L2    96  VSS<66>  SCONN288_H44441003_PIP  I138
  J6L2    98  VSS<65>  SCONN288_H44441003_PIP  I138
  J6L2   101  VSS<64>  SCONN288_H44441003_PIP  I138
  J6L2   103  VSS<63>  SCONN288_H44441003_PIP  I138
  J6L2   105  VSS<62>  SCONN288_H44441003_PIP  I138
  J6L2   107  VSS<61>  SCONN288_H44441003_PIP  I138
  J6L2   109  VSS<60>  SCONN288_H44441003_PIP  I138
  J6L2   112  VSS<59>  SCONN288_H44441003_PIP  I138
  J6L2   114  VSS<58>  SCONN288_H44441003_PIP  I138
  J6L2   116  VSS<57>  SCONN288_H44441003_PIP  I138
  J6L2   118  VSS<56>  SCONN288_H44441003_PIP  I138
  J6L2   120  VSS<55>  SCONN288_H44441003_PIP  I138
  J6L2   123  VSS<54>  SCONN288_H44441003_PIP  I138
  J6L2   125  VSS<53>  SCONN288_H44441003_PIP  I138
  J6L2   127  VSS<52>  SCONN288_H44441003_PIP  I138
  J6L2   129  VSS<51>  SCONN288_H44441003_PIP  I138
  J6L2   131  VSS<50>  SCONN288_H44441003_PIP  I138
  J6L2   134  VSS<49>  SCONN288_H44441003_PIP  I138
  J6L2   136  VSS<48>  SCONN288_H44441003_PIP  I138
  J6L2   138  VSS<47>  SCONN288_H44441003_PIP  I138
  J6L2   147  VSS<46>  SCONN288_H44441003_PIP  I138
  J6L2   149  VSS<45>  SCONN288_H44441003_PIP  I138
  J6L2   151  VSS<44>  SCONN288_H44441003_PIP  I138
  J6L2   154  VSS<43>  SCONN288_H44441003_PIP  I138
  J6L2   156  VSS<42>  SCONN288_H44441003_PIP  I138
  J6L2   158  VSS<41>  SCONN288_H44441003_PIP  I138
  J6L2   160  VSS<40>  SCONN288_H44441003_PIP  I138
  J6L2   162  VSS<39>  SCONN288_H44441003_PIP  I138
  J6L2   165  VSS<38>  SCONN288_H44441003_PIP  I138
  J6L2   167  VSS<37>  SCONN288_H44441003_PIP  I138
  J6L2   169  VSS<36>  SCONN288_H44441003_PIP  I138
  J6L2   171  VSS<35>  SCONN288_H44441003_PIP  I138
  J6L2   173  VSS<34>  SCONN288_H44441003_PIP  I138
  J6L2   176  VSS<33>  SCONN288_H44441003_PIP  I138
  J6L2   178  VSS<32>  SCONN288_H44441003_PIP  I138
  J6L2   180  VSS<31>  SCONN288_H44441003_PIP  I138
  J6L2   182  VSS<30>  SCONN288_H44441003_PIP  I138
  J6L2   184  VSS<29>  SCONN288_H44441003_PIP  I138
  J6L2   187  VSS<28>  SCONN288_H44441003_PIP  I138
  J6L2   189  VSS<27>  SCONN288_H44441003_PIP  I138
  J6L2   191  VSS<26>  SCONN288_H44441003_PIP  I138
  J6L2   193  VSS<25>  SCONN288_H44441003_PIP  I138
  J6L2   195  VSS<24>  SCONN288_H44441003_PIP  I138
  J6L2   198  VSS<23>  SCONN288_H44441003_PIP  I138
  J6L2   200  VSS<22>  SCONN288_H44441003_PIP  I138
  J6L2   202  VSS<21>  SCONN288_H44441003_PIP  I138
  J6L2   238  SA<2>  SCONN288_H44441003_PIP  I12
  J6L2   239  VSS<20>  SCONN288_H44441003_PIP  I138
  J6L2   241  VSS<19>  SCONN288_H44441003_PIP  I138
  J6L2   243  VSS<18>  SCONN288_H44441003_PIP  I138
  J6L2   246  VSS<17>  SCONN288_H44441003_PIP  I138
  J6L2   248  VSS<16>  SCONN288_H44441003_PIP  I138
  J6L2   250  VSS<15>  SCONN288_H44441003_PIP  I138
  J6L2   252  VSS<14>  SCONN288_H44441003_PIP  I138
  J6L2   254  VSS<13>  SCONN288_H44441003_PIP  I138
  J6L2   257  VSS<12>  SCONN288_H44441003_PIP  I138
  J6L2   259  VSS<11>  SCONN288_H44441003_PIP  I138
  J6L2   261  VSS<10>  SCONN288_H44441003_PIP  I138
  J6L2   263  VSS<9>  SCONN288_H44441003_PIP  I138
  J6L2   265  VSS<8>  SCONN288_H44441003_PIP  I138
  J6L2   268  VSS<7>  SCONN288_H44441003_PIP  I138
  J6L2   270  VSS<6>  SCONN288_H44441003_PIP  I138
  J6L2   272  VSS<5>  SCONN288_H44441003_PIP  I138
  J6L2   274  VSS<4>  SCONN288_H44441003_PIP  I138
  J6L2   276  VSS<3>  SCONN288_H44441003_PIP  I138
  J6L2   279  VSS<2>  SCONN288_H44441003_PIP  I138
  J6L2   281  VSS<1>  SCONN288_H44441003_PIP  I138
  J6L2   283  VSS<0>  SCONN288_H44441003_PIP  I138
  J6M1     2  VSS<93>  SCONN288_H44441003_PIP  I44
  J6M1     4  VSS<92>  SCONN288_H44441003_PIP  I44
  J6M1     6  VSS<91>  SCONN288_H44441003_PIP  I44
  J6M1     9  VSS<90>  SCONN288_H44441003_PIP  I44
  J6M1    11  VSS<89>  SCONN288_H44441003_PIP  I44
  J6M1    13  VSS<88>  SCONN288_H44441003_PIP  I44
  J6M1    15  VSS<87>  SCONN288_H44441003_PIP  I44
  J6M1    17  VSS<86>  SCONN288_H44441003_PIP  I44
  J6M1    20  VSS<85>  SCONN288_H44441003_PIP  I44
  J6M1    22  VSS<84>  SCONN288_H44441003_PIP  I44
  J6M1    24  VSS<83>  SCONN288_H44441003_PIP  I44
  J6M1    26  VSS<82>  SCONN288_H44441003_PIP  I44
  J6M1    28  VSS<81>  SCONN288_H44441003_PIP  I44
  J6M1    31  VSS<80>  SCONN288_H44441003_PIP  I44
  J6M1    33  VSS<79>  SCONN288_H44441003_PIP  I44
  J6M1    35  VSS<78>  SCONN288_H44441003_PIP  I44
  J6M1    37  VSS<77>  SCONN288_H44441003_PIP  I44
  J6M1    39  VSS<76>  SCONN288_H44441003_PIP  I44
  J6M1    42  VSS<75>  SCONN288_H44441003_PIP  I44
  J6M1    44  VSS<74>  SCONN288_H44441003_PIP  I44
  J6M1    46  VSS<73>  SCONN288_H44441003_PIP  I44
  J6M1    48  VSS<72>  SCONN288_H44441003_PIP  I44
  J6M1    50  VSS<71>  SCONN288_H44441003_PIP  I44
  J6M1    53  VSS<70>  SCONN288_H44441003_PIP  I44
  J6M1    55  VSS<69>  SCONN288_H44441003_PIP  I44
  J6M1    57  VSS<68>  SCONN288_H44441003_PIP  I44
  J6M1    94  VSS<67>  SCONN288_H44441003_PIP  I44
  J6M1    96  VSS<66>  SCONN288_H44441003_PIP  I44
  J6M1    98  VSS<65>  SCONN288_H44441003_PIP  I44
  J6M1   101  VSS<64>  SCONN288_H44441003_PIP  I44
  J6M1   103  VSS<63>  SCONN288_H44441003_PIP  I44
  J6M1   105  VSS<62>  SCONN288_H44441003_PIP  I44
  J6M1   107  VSS<61>  SCONN288_H44441003_PIP  I44
  J6M1   109  VSS<60>  SCONN288_H44441003_PIP  I44
  J6M1   112  VSS<59>  SCONN288_H44441003_PIP  I44
  J6M1   114  VSS<58>  SCONN288_H44441003_PIP  I44
  J6M1   116  VSS<57>  SCONN288_H44441003_PIP  I44
  J6M1   118  VSS<56>  SCONN288_H44441003_PIP  I44
  J6M1   120  VSS<55>  SCONN288_H44441003_PIP  I44
  J6M1   123  VSS<54>  SCONN288_H44441003_PIP  I44
  J6M1   125  VSS<53>  SCONN288_H44441003_PIP  I44
  J6M1   127  VSS<52>  SCONN288_H44441003_PIP  I44
  J6M1   129  VSS<51>  SCONN288_H44441003_PIP  I44
  J6M1   131  VSS<50>  SCONN288_H44441003_PIP  I44
  J6M1   134  VSS<49>  SCONN288_H44441003_PIP  I44
  J6M1   136  VSS<48>  SCONN288_H44441003_PIP  I44
  J6M1   138  VSS<47>  SCONN288_H44441003_PIP  I44
  J6M1   140  SA<1>  SCONN288_H44441003_PIP  I158
  J6M1   147  VSS<46>  SCONN288_H44441003_PIP  I44
  J6M1   149  VSS<45>  SCONN288_H44441003_PIP  I44
  J6M1   151  VSS<44>  SCONN288_H44441003_PIP  I44
  J6M1   154  VSS<43>  SCONN288_H44441003_PIP  I44
  J6M1   156  VSS<42>  SCONN288_H44441003_PIP  I44
  J6M1   158  VSS<41>  SCONN288_H44441003_PIP  I44
  J6M1   160  VSS<40>  SCONN288_H44441003_PIP  I44
  J6M1   162  VSS<39>  SCONN288_H44441003_PIP  I44
  J6M1   165  VSS<38>  SCONN288_H44441003_PIP  I44
  J6M1   167  VSS<37>  SCONN288_H44441003_PIP  I44
  J6M1   169  VSS<36>  SCONN288_H44441003_PIP  I44
  J6M1   171  VSS<35>  SCONN288_H44441003_PIP  I44
  J6M1   173  VSS<34>  SCONN288_H44441003_PIP  I44
  J6M1   176  VSS<33>  SCONN288_H44441003_PIP  I44
  J6M1   178  VSS<32>  SCONN288_H44441003_PIP  I44
  J6M1   180  VSS<31>  SCONN288_H44441003_PIP  I44
  J6M1   182  VSS<30>  SCONN288_H44441003_PIP  I44
  J6M1   184  VSS<29>  SCONN288_H44441003_PIP  I44
  J6M1   187  VSS<28>  SCONN288_H44441003_PIP  I44
  J6M1   189  VSS<27>  SCONN288_H44441003_PIP  I44
  J6M1   191  VSS<26>  SCONN288_H44441003_PIP  I44
  J6M1   193  VSS<25>  SCONN288_H44441003_PIP  I44
  J6M1   195  VSS<24>  SCONN288_H44441003_PIP  I44
  J6M1   198  VSS<23>  SCONN288_H44441003_PIP  I44
  J6M1   200  VSS<22>  SCONN288_H44441003_PIP  I44
  J6M1   202  VSS<21>  SCONN288_H44441003_PIP  I44
  J6M1   238  SA<2>  SCONN288_H44441003_PIP  I158
  J6M1   239  VSS<20>  SCONN288_H44441003_PIP  I44
  J6M1   241  VSS<19>  SCONN288_H44441003_PIP  I44
  J6M1   243  VSS<18>  SCONN288_H44441003_PIP  I44
  J6M1   246  VSS<17>  SCONN288_H44441003_PIP  I44
  J6M1   248  VSS<16>  SCONN288_H44441003_PIP  I44
  J6M1   250  VSS<15>  SCONN288_H44441003_PIP  I44
  J6M1   252  VSS<14>  SCONN288_H44441003_PIP  I44
  J6M1   254  VSS<13>  SCONN288_H44441003_PIP  I44
  J6M1   257  VSS<12>  SCONN288_H44441003_PIP  I44
  J6M1   259  VSS<11>  SCONN288_H44441003_PIP  I44
  J6M1   261  VSS<10>  SCONN288_H44441003_PIP  I44
  J6M1   263  VSS<9>  SCONN288_H44441003_PIP  I44
  J6M1   265  VSS<8>  SCONN288_H44441003_PIP  I44
  J6M1   268  VSS<7>  SCONN288_H44441003_PIP  I44
  J6M1   270  VSS<6>  SCONN288_H44441003_PIP  I44
  J6M1   272  VSS<5>  SCONN288_H44441003_PIP  I44
  J6M1   274  VSS<4>  SCONN288_H44441003_PIP  I44
  J6M1   276  VSS<3>  SCONN288_H44441003_PIP  I44
  J6M1   279  VSS<2>  SCONN288_H44441003_PIP  I44
  J6M1   281  VSS<1>  SCONN288_H44441003_PIP  I44
  J6M1   283  VSS<0>  SCONN288_H44441003_PIP  I44
  J6T1     2  VSS<93>  SCONN288_H44441003_PIP  I139
  J6T1     4  VSS<92>  SCONN288_H44441003_PIP  I139
  J6T1     6  VSS<91>  SCONN288_H44441003_PIP  I139
  J6T1     9  VSS<90>  SCONN288_H44441003_PIP  I139
  J6T1    11  VSS<89>  SCONN288_H44441003_PIP  I139
  J6T1    13  VSS<88>  SCONN288_H44441003_PIP  I139
  J6T1    15  VSS<87>  SCONN288_H44441003_PIP  I139
  J6T1    17  VSS<86>  SCONN288_H44441003_PIP  I139
  J6T1    20  VSS<85>  SCONN288_H44441003_PIP  I139
  J6T1    22  VSS<84>  SCONN288_H44441003_PIP  I139
  J6T1    24  VSS<83>  SCONN288_H44441003_PIP  I139
  J6T1    26  VSS<82>  SCONN288_H44441003_PIP  I139
  J6T1    28  VSS<81>  SCONN288_H44441003_PIP  I139
  J6T1    31  VSS<80>  SCONN288_H44441003_PIP  I139
  J6T1    33  VSS<79>  SCONN288_H44441003_PIP  I139
  J6T1    35  VSS<78>  SCONN288_H44441003_PIP  I139
  J6T1    37  VSS<77>  SCONN288_H44441003_PIP  I139
  J6T1    39  VSS<76>  SCONN288_H44441003_PIP  I139
  J6T1    42  VSS<75>  SCONN288_H44441003_PIP  I139
  J6T1    44  VSS<74>  SCONN288_H44441003_PIP  I139
  J6T1    46  VSS<73>  SCONN288_H44441003_PIP  I139
  J6T1    48  VSS<72>  SCONN288_H44441003_PIP  I139
  J6T1    50  VSS<71>  SCONN288_H44441003_PIP  I139
  J6T1    53  VSS<70>  SCONN288_H44441003_PIP  I139
  J6T1    55  VSS<69>  SCONN288_H44441003_PIP  I139
  J6T1    57  VSS<68>  SCONN288_H44441003_PIP  I139
  J6T1    94  VSS<67>  SCONN288_H44441003_PIP  I139
  J6T1    96  VSS<66>  SCONN288_H44441003_PIP  I139
  J6T1    98  VSS<65>  SCONN288_H44441003_PIP  I139
  J6T1   101  VSS<64>  SCONN288_H44441003_PIP  I139
  J6T1   103  VSS<63>  SCONN288_H44441003_PIP  I139
  J6T1   105  VSS<62>  SCONN288_H44441003_PIP  I139
  J6T1   107  VSS<61>  SCONN288_H44441003_PIP  I139
  J6T1   109  VSS<60>  SCONN288_H44441003_PIP  I139
  J6T1   112  VSS<59>  SCONN288_H44441003_PIP  I139
  J6T1   114  VSS<58>  SCONN288_H44441003_PIP  I139
  J6T1   116  VSS<57>  SCONN288_H44441003_PIP  I139
  J6T1   118  VSS<56>  SCONN288_H44441003_PIP  I139
  J6T1   120  VSS<55>  SCONN288_H44441003_PIP  I139
  J6T1   123  VSS<54>  SCONN288_H44441003_PIP  I139
  J6T1   125  VSS<53>  SCONN288_H44441003_PIP  I139
  J6T1   127  VSS<52>  SCONN288_H44441003_PIP  I139
  J6T1   129  VSS<51>  SCONN288_H44441003_PIP  I139
  J6T1   131  VSS<50>  SCONN288_H44441003_PIP  I139
  J6T1   134  VSS<49>  SCONN288_H44441003_PIP  I139
  J6T1   136  VSS<48>  SCONN288_H44441003_PIP  I139
  J6T1   138  VSS<47>  SCONN288_H44441003_PIP  I139
  J6T1   140  SA<1>  SCONN288_H44441003_PIP  I13
  J6T1   147  VSS<46>  SCONN288_H44441003_PIP  I139
  J6T1   149  VSS<45>  SCONN288_H44441003_PIP  I139
  J6T1   151  VSS<44>  SCONN288_H44441003_PIP  I139
  J6T1   154  VSS<43>  SCONN288_H44441003_PIP  I139
  J6T1   156  VSS<42>  SCONN288_H44441003_PIP  I139
  J6T1   158  VSS<41>  SCONN288_H44441003_PIP  I139
  J6T1   160  VSS<40>  SCONN288_H44441003_PIP  I139
  J6T1   162  VSS<39>  SCONN288_H44441003_PIP  I139
  J6T1   165  VSS<38>  SCONN288_H44441003_PIP  I139
  J6T1   167  VSS<37>  SCONN288_H44441003_PIP  I139
  J6T1   169  VSS<36>  SCONN288_H44441003_PIP  I139
  J6T1   171  VSS<35>  SCONN288_H44441003_PIP  I139
  J6T1   173  VSS<34>  SCONN288_H44441003_PIP  I139
  J6T1   176  VSS<33>  SCONN288_H44441003_PIP  I139
  J6T1   178  VSS<32>  SCONN288_H44441003_PIP  I139
  J6T1   180  VSS<31>  SCONN288_H44441003_PIP  I139
  J6T1   182  VSS<30>  SCONN288_H44441003_PIP  I139
  J6T1   184  VSS<29>  SCONN288_H44441003_PIP  I139
  J6T1   187  VSS<28>  SCONN288_H44441003_PIP  I139
  J6T1   189  VSS<27>  SCONN288_H44441003_PIP  I139
  J6T1   191  VSS<26>  SCONN288_H44441003_PIP  I139
  J6T1   193  VSS<25>  SCONN288_H44441003_PIP  I139
  J6T1   195  VSS<24>  SCONN288_H44441003_PIP  I139
  J6T1   198  VSS<23>  SCONN288_H44441003_PIP  I139
  J6T1   200  VSS<22>  SCONN288_H44441003_PIP  I139
  J6T1   202  VSS<21>  SCONN288_H44441003_PIP  I139
  J6T1   238  SA<2>  SCONN288_H44441003_PIP  I13
  J6T1   239  VSS<20>  SCONN288_H44441003_PIP  I139
  J6T1   241  VSS<19>  SCONN288_H44441003_PIP  I139
  J6T1   243  VSS<18>  SCONN288_H44441003_PIP  I139
  J6T1   246  VSS<17>  SCONN288_H44441003_PIP  I139
  J6T1   248  VSS<16>  SCONN288_H44441003_PIP  I139
  J6T1   250  VSS<15>  SCONN288_H44441003_PIP  I139
  J6T1   252  VSS<14>  SCONN288_H44441003_PIP  I139
  J6T1   254  VSS<13>  SCONN288_H44441003_PIP  I139
  J6T1   257  VSS<12>  SCONN288_H44441003_PIP  I139
  J6T1   259  VSS<11>  SCONN288_H44441003_PIP  I139
  J6T1   261  VSS<10>  SCONN288_H44441003_PIP  I139
  J6T1   263  VSS<9>  SCONN288_H44441003_PIP  I139
  J6T1   265  VSS<8>  SCONN288_H44441003_PIP  I139
  J6T1   268  VSS<7>  SCONN288_H44441003_PIP  I139
  J6T1   270  VSS<6>  SCONN288_H44441003_PIP  I139
  J6T1   272  VSS<5>  SCONN288_H44441003_PIP  I139
  J6T1   274  VSS<4>  SCONN288_H44441003_PIP  I139
  J6T1   276  VSS<3>  SCONN288_H44441003_PIP  I139
  J6T1   279  VSS<2>  SCONN288_H44441003_PIP  I139
  J6T1   281  VSS<1>  SCONN288_H44441003_PIP  I139
  J6T1   283  VSS<0>  SCONN288_H44441003_PIP  I139
  J6U1     2  VSS<93>  SCONN288_H44441003_PIP  I138
  J6U1     4  VSS<92>  SCONN288_H44441003_PIP  I138
  J6U1     6  VSS<91>  SCONN288_H44441003_PIP  I138
  J6U1     9  VSS<90>  SCONN288_H44441003_PIP  I138
  J6U1    11  VSS<89>  SCONN288_H44441003_PIP  I138
  J6U1    13  VSS<88>  SCONN288_H44441003_PIP  I138
  J6U1    15  VSS<87>  SCONN288_H44441003_PIP  I138
  J6U1    17  VSS<86>  SCONN288_H44441003_PIP  I138
  J6U1    20  VSS<85>  SCONN288_H44441003_PIP  I138
  J6U1    22  VSS<84>  SCONN288_H44441003_PIP  I138
  J6U1    24  VSS<83>  SCONN288_H44441003_PIP  I138
  J6U1    26  VSS<82>  SCONN288_H44441003_PIP  I138
  J6U1    28  VSS<81>  SCONN288_H44441003_PIP  I138
  J6U1    31  VSS<80>  SCONN288_H44441003_PIP  I138
  J6U1    33  VSS<79>  SCONN288_H44441003_PIP  I138
  J6U1    35  VSS<78>  SCONN288_H44441003_PIP  I138
  J6U1    37  VSS<77>  SCONN288_H44441003_PIP  I138
  J6U1    39  VSS<76>  SCONN288_H44441003_PIP  I138
  J6U1    42  VSS<75>  SCONN288_H44441003_PIP  I138
  J6U1    44  VSS<74>  SCONN288_H44441003_PIP  I138
  J6U1    46  VSS<73>  SCONN288_H44441003_PIP  I138
  J6U1    48  VSS<72>  SCONN288_H44441003_PIP  I138
  J6U1    50  VSS<71>  SCONN288_H44441003_PIP  I138
  J6U1    53  VSS<70>  SCONN288_H44441003_PIP  I138
  J6U1    55  VSS<69>  SCONN288_H44441003_PIP  I138
  J6U1    57  VSS<68>  SCONN288_H44441003_PIP  I138
  J6U1    94  VSS<67>  SCONN288_H44441003_PIP  I138
  J6U1    96  VSS<66>  SCONN288_H44441003_PIP  I138
  J6U1    98  VSS<65>  SCONN288_H44441003_PIP  I138
  J6U1   101  VSS<64>  SCONN288_H44441003_PIP  I138
  J6U1   103  VSS<63>  SCONN288_H44441003_PIP  I138
  J6U1   105  VSS<62>  SCONN288_H44441003_PIP  I138
  J6U1   107  VSS<61>  SCONN288_H44441003_PIP  I138
  J6U1   109  VSS<60>  SCONN288_H44441003_PIP  I138
  J6U1   112  VSS<59>  SCONN288_H44441003_PIP  I138
  J6U1   114  VSS<58>  SCONN288_H44441003_PIP  I138
  J6U1   116  VSS<57>  SCONN288_H44441003_PIP  I138
  J6U1   118  VSS<56>  SCONN288_H44441003_PIP  I138
  J6U1   120  VSS<55>  SCONN288_H44441003_PIP  I138
  J6U1   123  VSS<54>  SCONN288_H44441003_PIP  I138
  J6U1   125  VSS<53>  SCONN288_H44441003_PIP  I138
  J6U1   127  VSS<52>  SCONN288_H44441003_PIP  I138
  J6U1   129  VSS<51>  SCONN288_H44441003_PIP  I138
  J6U1   131  VSS<50>  SCONN288_H44441003_PIP  I138
  J6U1   134  VSS<49>  SCONN288_H44441003_PIP  I138
  J6U1   136  VSS<48>  SCONN288_H44441003_PIP  I138
  J6U1   138  VSS<47>  SCONN288_H44441003_PIP  I138
  J6U1   147  VSS<46>  SCONN288_H44441003_PIP  I138
  J6U1   149  VSS<45>  SCONN288_H44441003_PIP  I138
  J6U1   151  VSS<44>  SCONN288_H44441003_PIP  I138
  J6U1   154  VSS<43>  SCONN288_H44441003_PIP  I138
  J6U1   156  VSS<42>  SCONN288_H44441003_PIP  I138
  J6U1   158  VSS<41>  SCONN288_H44441003_PIP  I138
  J6U1   160  VSS<40>  SCONN288_H44441003_PIP  I138
  J6U1   162  VSS<39>  SCONN288_H44441003_PIP  I138
  J6U1   165  VSS<38>  SCONN288_H44441003_PIP  I138
  J6U1   167  VSS<37>  SCONN288_H44441003_PIP  I138
  J6U1   169  VSS<36>  SCONN288_H44441003_PIP  I138
  J6U1   171  VSS<35>  SCONN288_H44441003_PIP  I138
  J6U1   173  VSS<34>  SCONN288_H44441003_PIP  I138
  J6U1   176  VSS<33>  SCONN288_H44441003_PIP  I138
  J6U1   178  VSS<32>  SCONN288_H44441003_PIP  I138
  J6U1   180  VSS<31>  SCONN288_H44441003_PIP  I138
  J6U1   182  VSS<30>  SCONN288_H44441003_PIP  I138
  J6U1   184  VSS<29>  SCONN288_H44441003_PIP  I138
  J6U1   187  VSS<28>  SCONN288_H44441003_PIP  I138
  J6U1   189  VSS<27>  SCONN288_H44441003_PIP  I138
  J6U1   191  VSS<26>  SCONN288_H44441003_PIP  I138
  J6U1   193  VSS<25>  SCONN288_H44441003_PIP  I138
  J6U1   195  VSS<24>  SCONN288_H44441003_PIP  I138
  J6U1   198  VSS<23>  SCONN288_H44441003_PIP  I138
  J6U1   200  VSS<22>  SCONN288_H44441003_PIP  I138
  J6U1   202  VSS<21>  SCONN288_H44441003_PIP  I138
  J6U1   238  SA<2>  SCONN288_H44441003_PIP  I14
  J6U1   239  VSS<20>  SCONN288_H44441003_PIP  I138
  J6U1   241  VSS<19>  SCONN288_H44441003_PIP  I138
  J6U1   243  VSS<18>  SCONN288_H44441003_PIP  I138
  J6U1   246  VSS<17>  SCONN288_H44441003_PIP  I138
  J6U1   248  VSS<16>  SCONN288_H44441003_PIP  I138
  J6U1   250  VSS<15>  SCONN288_H44441003_PIP  I138
  J6U1   252  VSS<14>  SCONN288_H44441003_PIP  I138
  J6U1   254  VSS<13>  SCONN288_H44441003_PIP  I138
  J6U1   257  VSS<12>  SCONN288_H44441003_PIP  I138
  J6U1   259  VSS<11>  SCONN288_H44441003_PIP  I138
  J6U1   261  VSS<10>  SCONN288_H44441003_PIP  I138
  J6U1   263  VSS<9>  SCONN288_H44441003_PIP  I138
  J6U1   265  VSS<8>  SCONN288_H44441003_PIP  I138
  J6U1   268  VSS<7>  SCONN288_H44441003_PIP  I138
  J6U1   270  VSS<6>  SCONN288_H44441003_PIP  I138
  J6U1   272  VSS<5>  SCONN288_H44441003_PIP  I138
  J6U1   274  VSS<4>  SCONN288_H44441003_PIP  I138
  J6U1   276  VSS<3>  SCONN288_H44441003_PIP  I138
  J6U1   279  VSS<2>  SCONN288_H44441003_PIP  I138
  J6U1   281  VSS<1>  SCONN288_H44441003_PIP  I138
  J6U1   283  VSS<0>  SCONN288_H44441003_PIP  I138
  J6U2     2  VSS<93>  SCONN288_H44441003_PIP  I43
  J6U2     4  VSS<92>  SCONN288_H44441003_PIP  I43
  J6U2     6  VSS<91>  SCONN288_H44441003_PIP  I43
  J6U2     9  VSS<90>  SCONN288_H44441003_PIP  I43
  J6U2    11  VSS<89>  SCONN288_H44441003_PIP  I43
  J6U2    13  VSS<88>  SCONN288_H44441003_PIP  I43
  J6U2    15  VSS<87>  SCONN288_H44441003_PIP  I43
  J6U2    17  VSS<86>  SCONN288_H44441003_PIP  I43
  J6U2    20  VSS<85>  SCONN288_H44441003_PIP  I43
  J6U2    22  VSS<84>  SCONN288_H44441003_PIP  I43
  J6U2    24  VSS<83>  SCONN288_H44441003_PIP  I43
  J6U2    26  VSS<82>  SCONN288_H44441003_PIP  I43
  J6U2    28  VSS<81>  SCONN288_H44441003_PIP  I43
  J6U2    31  VSS<80>  SCONN288_H44441003_PIP  I43
  J6U2    33  VSS<79>  SCONN288_H44441003_PIP  I43
  J6U2    35  VSS<78>  SCONN288_H44441003_PIP  I43
  J6U2    37  VSS<77>  SCONN288_H44441003_PIP  I43
  J6U2    39  VSS<76>  SCONN288_H44441003_PIP  I43
  J6U2    42  VSS<75>  SCONN288_H44441003_PIP  I43
  J6U2    44  VSS<74>  SCONN288_H44441003_PIP  I43
  J6U2    46  VSS<73>  SCONN288_H44441003_PIP  I43
  J6U2    48  VSS<72>  SCONN288_H44441003_PIP  I43
  J6U2    50  VSS<71>  SCONN288_H44441003_PIP  I43
  J6U2    53  VSS<70>  SCONN288_H44441003_PIP  I43
  J6U2    55  VSS<69>  SCONN288_H44441003_PIP  I43
  J6U2    57  VSS<68>  SCONN288_H44441003_PIP  I43
  J6U2    94  VSS<67>  SCONN288_H44441003_PIP  I43
  J6U2    96  VSS<66>  SCONN288_H44441003_PIP  I43
  J6U2    98  VSS<65>  SCONN288_H44441003_PIP  I43
  J6U2   101  VSS<64>  SCONN288_H44441003_PIP  I43
  J6U2   103  VSS<63>  SCONN288_H44441003_PIP  I43
  J6U2   105  VSS<62>  SCONN288_H44441003_PIP  I43
  J6U2   107  VSS<61>  SCONN288_H44441003_PIP  I43
  J6U2   109  VSS<60>  SCONN288_H44441003_PIP  I43
  J6U2   112  VSS<59>  SCONN288_H44441003_PIP  I43
  J6U2   114  VSS<58>  SCONN288_H44441003_PIP  I43
  J6U2   116  VSS<57>  SCONN288_H44441003_PIP  I43
  J6U2   118  VSS<56>  SCONN288_H44441003_PIP  I43
  J6U2   120  VSS<55>  SCONN288_H44441003_PIP  I43
  J6U2   123  VSS<54>  SCONN288_H44441003_PIP  I43
  J6U2   125  VSS<53>  SCONN288_H44441003_PIP  I43
  J6U2   127  VSS<52>  SCONN288_H44441003_PIP  I43
  J6U2   129  VSS<51>  SCONN288_H44441003_PIP  I43
  J6U2   131  VSS<50>  SCONN288_H44441003_PIP  I43
  J6U2   134  VSS<49>  SCONN288_H44441003_PIP  I43
  J6U2   136  VSS<48>  SCONN288_H44441003_PIP  I43
  J6U2   138  VSS<47>  SCONN288_H44441003_PIP  I43
  J6U2   140  SA<1>  SCONN288_H44441003_PIP  I111
  J6U2   147  VSS<46>  SCONN288_H44441003_PIP  I43
  J6U2   149  VSS<45>  SCONN288_H44441003_PIP  I43
  J6U2   151  VSS<44>  SCONN288_H44441003_PIP  I43
  J6U2   154  VSS<43>  SCONN288_H44441003_PIP  I43
  J6U2   156  VSS<42>  SCONN288_H44441003_PIP  I43
  J6U2   158  VSS<41>  SCONN288_H44441003_PIP  I43
  J6U2   160  VSS<40>  SCONN288_H44441003_PIP  I43
  J6U2   162  VSS<39>  SCONN288_H44441003_PIP  I43
  J6U2   165  VSS<38>  SCONN288_H44441003_PIP  I43
  J6U2   167  VSS<37>  SCONN288_H44441003_PIP  I43
  J6U2   169  VSS<36>  SCONN288_H44441003_PIP  I43
  J6U2   171  VSS<35>  SCONN288_H44441003_PIP  I43
  J6U2   173  VSS<34>  SCONN288_H44441003_PIP  I43
  J6U2   176  VSS<33>  SCONN288_H44441003_PIP  I43
  J6U2   178  VSS<32>  SCONN288_H44441003_PIP  I43
  J6U2   180  VSS<31>  SCONN288_H44441003_PIP  I43
  J6U2   182  VSS<30>  SCONN288_H44441003_PIP  I43
  J6U2   184  VSS<29>  SCONN288_H44441003_PIP  I43
  J6U2   187  VSS<28>  SCONN288_H44441003_PIP  I43
  J6U2   189  VSS<27>  SCONN288_H44441003_PIP  I43
  J6U2   191  VSS<26>  SCONN288_H44441003_PIP  I43
  J6U2   193  VSS<25>  SCONN288_H44441003_PIP  I43
  J6U2   195  VSS<24>  SCONN288_H44441003_PIP  I43
  J6U2   198  VSS<23>  SCONN288_H44441003_PIP  I43
  J6U2   200  VSS<22>  SCONN288_H44441003_PIP  I43
  J6U2   202  VSS<21>  SCONN288_H44441003_PIP  I43
  J6U2   239  VSS<20>  SCONN288_H44441003_PIP  I43
  J6U2   241  VSS<19>  SCONN288_H44441003_PIP  I43
  J6U2   243  VSS<18>  SCONN288_H44441003_PIP  I43
  J6U2   246  VSS<17>  SCONN288_H44441003_PIP  I43
  J6U2   248  VSS<16>  SCONN288_H44441003_PIP  I43
  J6U2   250  VSS<15>  SCONN288_H44441003_PIP  I43
  J6U2   252  VSS<14>  SCONN288_H44441003_PIP  I43
  J6U2   254  VSS<13>  SCONN288_H44441003_PIP  I43
  J6U2   257  VSS<12>  SCONN288_H44441003_PIP  I43
  J6U2   259  VSS<11>  SCONN288_H44441003_PIP  I43
  J6U2   261  VSS<10>  SCONN288_H44441003_PIP  I43
  J6U2   263  VSS<9>  SCONN288_H44441003_PIP  I43
  J6U2   265  VSS<8>  SCONN288_H44441003_PIP  I43
  J6U2   268  VSS<7>  SCONN288_H44441003_PIP  I43
  J6U2   270  VSS<6>  SCONN288_H44441003_PIP  I43
  J6U2   272  VSS<5>  SCONN288_H44441003_PIP  I43
  J6U2   274  VSS<4>  SCONN288_H44441003_PIP  I43
  J6U2   276  VSS<3>  SCONN288_H44441003_PIP  I43
  J6U2   279  VSS<2>  SCONN288_H44441003_PIP  I43
  J6U2   281  VSS<1>  SCONN288_H44441003_PIP  I43
  J6U2   283  VSS<0>  SCONN288_H44441003_PIP  I43
  J7G2     7    IO7  CONN8_C77962004  I47
  J8A1   1A3  GND<23>  CONN72_G97614002_A_CP  I163
  J8A1   1A6  GND<22>  CONN72_G97614002_A_CP  I163
  J8A1   1A9  GND<21>  CONN72_G97614002_A_CP  I163
  J8A1   1B1  SIDEBANDA_3  CONN72_G97614002_A_CP  I163
  J8A1   1B3  GND<20>  CONN72_G97614002_A_CP  I163
  J8A1   1B6  GND<19>  CONN72_G97614002_A_CP  I163
  J8A1   1B9  GND<18>  CONN72_G97614002_A_CP  I163
  J8A1   1C2  SIDEBANDA_2  CONN72_G97614002_A_CP  I163
  J8A1   1C3  GND<17>  CONN72_G97614002_A_CP  I163
  J8A1   1C6  GND<16>  CONN72_G97614002_A_CP  I163
  J8A1   1C9  GND<15>  CONN72_G97614002_A_CP  I163
  J8A1   1D3  GND<14>  CONN72_G97614002_A_CP  I163
  J8A1   1D6  GND<13>  CONN72_G97614002_A_CP  I163
  J8A1   1D9  GND<12>  CONN72_G97614002_A_CP  I163
  J8A1   2A3  GND<11>  CONN72_G97614002_A_CP  I163
  J8A1   2A6  GND<10>  CONN72_G97614002_A_CP  I163
  J8A1   2A9  GND<9>  CONN72_G97614002_A_CP  I163
  J8A1   2B1  SIDEBANDB_3  CONN72_G97614002_A_CP  I163
  J8A1   2B3  GND<8>  CONN72_G97614002_A_CP  I163
  J8A1   2B6  GND<7>  CONN72_G97614002_A_CP  I163
  J8A1   2B9  GND<6>  CONN72_G97614002_A_CP  I163
  J8A1   2C2  SIDEBANDB_2  CONN72_G97614002_A_CP  I163
  J8A1   2C3  GND<5>  CONN72_G97614002_A_CP  I163
  J8A1   2C6  GND<4>  CONN72_G97614002_A_CP  I163
  J8A1   2C9  GND<3>  CONN72_G97614002_A_CP  I163
  J8A1   2D3  GND<2>  CONN72_G97614002_A_CP  I163
  J8A1   2D6  GND<1>  CONN72_G97614002_A_CP  I163
  J8A1   2D9  GND<0>  CONN72_G97614002_A_CP  I163
  J8A2    A3   GND1  CONN36_G97614001_CP  I26
  J8A2    A6   GND2  CONN36_G97614001_CP  I26
  J8A2    A9   GND3  CONN36_G97614001_CP  I26
  J8A2    B1  SIDEBAND3  CONN36_G97614001_CP  I26
  J8A2    B3   GND4  CONN36_G97614001_CP  I26
  J8A2    B6   GND5  CONN36_G97614001_CP  I26
  J8A2    B9   GND6  CONN36_G97614001_CP  I26
  J8A2    C2  SIDEBAND2  CONN36_G97614001_CP  I26
  J8A2    C3   GND7  CONN36_G97614001_CP  I26
  J8A2    C6   GND8  CONN36_G97614001_CP  I26
  J8A2    C9   GND9  CONN36_G97614001_CP  I26
  J8A2    D3  GND10  CONN36_G97614001_CP  I26
  J8A2    D6  GND11  CONN36_G97614001_CP  I26
  J8A2    D9  GND12  CONN36_G97614001_CP  I26
  J8A3     1  GND<2>  CONN7_E82125014_PIP_TH  I17
  J8A3     4  GND<1>  CONN7_E82125014_PIP_TH  I17
  J8A3     7  GND<0>  CONN7_E82125014_PIP_TH  I17
  J8A3   MH1    MH1  CONN7_E82125014_PIP_TH  I17
  J8A3   MH2    MH2  CONN7_E82125014_PIP_TH  I17
  J8A4     2    IO2  CONN4_H73295001_PIP  I25
  J8A4     3    IO3  CONN4_H73295001_PIP  I25
  J8B1     1    IO1  SCONN24_H46321001_SM   I1
  J8B1     7    IO7  SCONN24_H46321001_SM   I1
  J8B1     9    IO9  SCONN24_H46321001_SM   I1
  J8B1    15   IO15  SCONN24_H46321001_SM   I1
  J8B1    23   IO23  SCONN24_H46321001_SM   I1
  J8B1   MP1    MP1  SCONN24_H46321001_SM   I1
  J8B1   MP2    MP2  SCONN24_H46321001_SM   I1
  J8C1     2    IO2  CONN3_C95678002_PIP  I285
  J8D4     2    IO2  CONN3_C95678002_PIP  I122
  J8E1    11   IO11  SCONN11_H67026001_SM  I87
  J8E1   MP1    MP1  SCONN11_H67026001_SM  I87
  J8E1   MP2    MP2  SCONN11_H67026001_SM  I87
  J8E3     3    IO3  SCONN80_E67482007_SM  I119
  J8E3     8    IO8  SCONN80_E67482007_SM  I119
  J8E3     9    IO9  SCONN80_E67482007_SM  I119
  J8E3    11   IO11  SCONN80_E67482007_SM  I119
  J8E3    14   IO14  SCONN80_E67482007_SM  I119
  J8E3    16   IO16  SCONN80_E67482007_SM  I119
  J8E3    17   IO17  SCONN80_E67482007_SM  I119
  J8E3    19   IO19  SCONN80_E67482007_SM  I119
  J8E3    22   IO22  SCONN80_E67482007_SM  I119
  J8E3    24   IO24  SCONN80_E67482007_SM  I119
  J8E3    25   IO25  SCONN80_E67482007_SM  I119
  J8E3    27   IO27  SCONN80_E67482007_SM  I119
  J8E3    30   IO30  SCONN80_E67482007_SM  I119
  J8E3    32   IO32  SCONN80_E67482007_SM  I119
  J8E3    33   IO33  SCONN80_E67482007_SM  I119
  J8E3    35   IO35  SCONN80_E67482007_SM  I119
  J8E3    38   IO38  SCONN80_E67482007_SM  I119
  J8E3    40   IO40  SCONN80_E67482007_SM  I119
  J8E3    41   IO41  SCONN80_E67482007_SM  I119
  J8E3    43   IO43  SCONN80_E67482007_SM  I119
  J8E3    46   IO46  SCONN80_E67482007_SM  I119
  J8E3    48   IO48  SCONN80_E67482007_SM  I119
  J8E3    49   IO49  SCONN80_E67482007_SM  I119
  J8E3    51   IO51  SCONN80_E67482007_SM  I119
  J8E3    54   IO54  SCONN80_E67482007_SM  I119
  J8E3    56   IO56  SCONN80_E67482007_SM  I119
  J8E3    57   IO57  SCONN80_E67482007_SM  I119
  J8E3    59   IO59  SCONN80_E67482007_SM  I119
  J8E3    62   IO62  SCONN80_E67482007_SM  I119
  J8E3    64   IO64  SCONN80_E67482007_SM  I119
  J8E3    65   IO65  SCONN80_E67482007_SM  I119
  J8E3    67   IO67  SCONN80_E67482007_SM  I119
  J8E3    70   IO70  SCONN80_E67482007_SM  I119
  J8E3    72   IO72  SCONN80_E67482007_SM  I119
  J8E3    73   IO73  SCONN80_E67482007_SM  I119
  J8E3    78   IO78  SCONN80_E67482007_SM  I119
  J8E4     4    IO4  SCONN64_H87568002_A_SMT  I27
  J8E4     7    IO7  SCONN64_H87568002_A_SMT  I27
  J8E4    10   IO10  SCONN64_H87568002_A_SMT  I27
  J8E4    13   IO13  SCONN64_H87568002_A_SMT  I27
  J8E4    16   IO16  SCONN64_H87568002_A_SMT  I27
  J8E4    19   IO19  SCONN64_H87568002_A_SMT  I27
  J8E4    22   IO22  SCONN64_H87568002_A_SMT  I27
  J8E4    25   IO25  SCONN64_H87568002_A_SMT  I27
  J8E4    28   IO28  SCONN64_H87568002_A_SMT  I27
  J8E4    39   IO39  SCONN64_H87568002_A_SMT  I27
  J8E4    42   IO42  SCONN64_H87568002_A_SMT  I27
  J8E4    45   IO45  SCONN64_H87568002_A_SMT  I27
  J8E4    48   IO48  SCONN64_H87568002_A_SMT  I27
  J8E4    51   IO51  SCONN64_H87568002_A_SMT  I27
  J8E4    54   IO54  SCONN64_H87568002_A_SMT  I27
  J8E4    57   IO57  SCONN64_H87568002_A_SMT  I27
  J8E4    60   IO60  SCONN64_H87568002_A_SMT  I27
  J8E4    63   IO63  SCONN64_H87568002_A_SMT  I27
  J8F1     1  GND<0>  SCONN75K_H17033002_SMT1  I53
  J8F1     3  GND<1>  SCONN75K_H17033002_SMT1  I53
  J8F1     9  GND<2>  SCONN75K_H17033002_SMT1  I53
  J8F1    15  GND<3>  SCONN75K_H17033002_SMT1  I53
  J8F1    21  GND<4>  SCONN75K_H17033002_SMT1  I53
  J8F1    27  GND<5>  SCONN75K_H17033002_SMT1  I53
  J8F1    33  GND<6>  SCONN75K_H17033002_SMT1  I53
  J8F1    39  GND<7>  SCONN75K_H17033002_SMT1  I53
  J8F1    45  GND<8>  SCONN75K_H17033002_SMT1  I53
  J8F1    51  GND<9>  SCONN75K_H17033002_SMT1  I53
  J8F1    57  GND<10>  SCONN75K_H17033002_SMT1  I53
  J8F1    71  GND<11>  SCONN75K_H17033002_SMT1  I53
  J8F1    73  GND<12>  SCONN75K_H17033002_SMT1  I53
  J8F1    75  GND<13>  SCONN75K_H17033002_SMT1  I53
  J8F1   MP1    MP1  SCONN75K_H17033002_SMT1  I53
  J8F1   MP2    MP2  SCONN75K_H17033002_SMT1  I53
  J8G1    13   IO13  SCONN200_H68296001_SM  I258
  J8G1    14   IO14  SCONN200_H68296001_SM  I258
  J8G1    26   IO26  SCONN200_H68296001_SM  I258
  J8G1    31   IO31  SCONN200_H68296001_SM  I258
  J8G1    34   IO34  SCONN200_H68296001_SM  I258
  J8G1    37   IO37  SCONN200_H68296001_SM  I258
  J8G1    40   IO40  SCONN200_H68296001_SM  I258
  J8G1    43   IO43  SCONN200_H68296001_SM  I258
  J8G1    46   IO46  SCONN200_H68296001_SM  I258
  J8G1    49   IO49  SCONN200_H68296001_SM  I258
  J8G1    52   IO52  SCONN200_H68296001_SM  I258
  J8G1    55   IO55  SCONN200_H68296001_SM  I258
  J8G1    58   IO58  SCONN200_H68296001_SM  I258
  J8G1    61   IO61  SCONN200_H68296001_SM  I258
  J8G1    64   IO64  SCONN200_H68296001_SM  I258
  J8G1    65   IO65  SCONN200_H68296001_SM  I258
  J8G1    68   IO68  SCONN200_H68296001_SM  I258
  J8G1    71   IO71  SCONN200_H68296001_SM  I258
  J8G1    74   IO74  SCONN200_H68296001_SM  I258
  J8G1    77   IO77  SCONN200_H68296001_SM  I258
  J8G1    80   IO80  SCONN200_H68296001_SM  I258
  J8G1    83   IO83  SCONN200_H68296001_SM  I258
  J8G1    86   IO86  SCONN200_H68296001_SM  I258
  J8G1    89   IO89  SCONN200_H68296001_SM  I258
  J8G1    92   IO92  SCONN200_H68296001_SM  I258
  J8G1    95   IO95  SCONN200_H68296001_SM  I258
  J8G1    98   IO98  SCONN200_H68296001_SM  I258
  J8G1   101  IO101  SCONN200_H68296001_SM  I243
  J8G1   104  IO104  SCONN200_H68296001_SM  I243
  J8G1   107  IO107  SCONN200_H68296001_SM  I243
  J8G1   110  IO110  SCONN200_H68296001_SM  I243
  J8G1   113  IO113  SCONN200_H68296001_SM  I243
  J8G1   116  IO116  SCONN200_H68296001_SM  I243
  J8G1   119  IO119  SCONN200_H68296001_SM  I243
  J8G1   122  IO122  SCONN200_H68296001_SM  I243
  J8G1   125  IO125  SCONN200_H68296001_SM  I243
  J8G1   128  IO128  SCONN200_H68296001_SM  I243
  J8G1   131  IO131  SCONN200_H68296001_SM  I243
  J8G1   134  IO134  SCONN200_H68296001_SM  I243
  J8G1   137  IO137  SCONN200_H68296001_SM  I243
  J8G1   140  IO140  SCONN200_H68296001_SM  I243
  J8G1   143  IO143  SCONN200_H68296001_SM  I243
  J8G1   146  IO146  SCONN200_H68296001_SM  I243
  J8G1   149  IO149  SCONN200_H68296001_SM  I243
  J8G1   152  IO152  SCONN200_H68296001_SM  I243
  J8G1   155  IO155  SCONN200_H68296001_SM  I243
  J8G1   158  IO158  SCONN200_H68296001_SM  I243
  J8G1   161  IO161  SCONN200_H68296001_SM  I243
  J8G1   164  IO164  SCONN200_H68296001_SM  I243
  J8G1   167  IO167  SCONN200_H68296001_SM  I243
  J8G1   170  IO170  SCONN200_H68296001_SM  I243
  J8G1   173  IO173  SCONN200_H68296001_SM  I243
  J8G1   176  IO176  SCONN200_H68296001_SM  I243
  J8G1   179  IO179  SCONN200_H68296001_SM  I243
  J8G1   182  IO182  SCONN200_H68296001_SM  I243
  J8G1   185  IO185  SCONN200_H68296001_SM  I243
  J8G1   188  IO188  SCONN200_H68296001_SM  I243
  J8G1   191  IO191  SCONN200_H68296001_SM  I243
  J8G1   194  IO194  SCONN200_H68296001_SM  I243
  J8G1   197  IO197  SCONN200_H68296001_SM  I243
  J8G1   200  IO200  SCONN200_H68296001_SM  I243
  J8G1   MH1    MH1  SCONN200_H68296001_SM  I258
  J8G1   MH2    MH2  SCONN200_H68296001_SM  I258
  J8G2     5    IO5  CONN12_C73564003  I124
  J8G2     6    IO6  CONN12_C73564003  I124
  J8G2    11   IO11  CONN12_C73564003  I124
  J8G2    12   IO12  CONN12_C73564003  I124
  J9A1     1    IO1  CONN4_D42317002_PIP  I131
  J9A1     3    IO3  CONN4_D42317002_PIP  I131
  J9A2    13   IO13  CONN14_H54902001_PIP  I171
  J9A3     2    IO2  SCONN60_C21100002  I26
  J9A3     7    IO7  SCONN60_C21100002  I26
  J9A3     8    IO8  SCONN60_C21100002  I26
  J9A3    13   IO13  SCONN60_C21100002  I26
  J9A3    14   IO14  SCONN60_C21100002  I26
  J9A3    19   IO19  SCONN60_C21100002  I26
  J9A3    20   IO20  SCONN60_C21100002  I26
  J9A3    25   IO25  SCONN60_C21100002  I26
  J9A3    26   IO26  SCONN60_C21100002  I26
  J9A3    31   IO31  SCONN60_C21100002  I26
  J9A3    32   IO32  SCONN60_C21100002  I26
  J9A3    37   IO37  SCONN60_C21100002  I26
  J9A3    38   IO38  SCONN60_C21100002  I26
  J9A3    49   IO49  SCONN60_C21100002  I26
  J9A3    50   IO50  SCONN60_C21100002  I26
  J9A3    59   IO59  SCONN60_C21100002  I26
  J9B1     4    GND  CONN9_H51826001_PIP2  I69
  J9B1     7  GND_DRAIN  CONN9_H51826001_PIP2  I69
  J9B1   MH1    MH1  CONN9_H51826001_PIP2  I69
  J9B1   MH2    MH2  CONN9_H51826001_PIP2  I69
  J9B1   MH3    MH3  CONN9_H51826001_PIP2  I69
  J9B1   MH4    MH4  CONN9_H51826001_PIP2  I69
  J9B2     2    IO2  CONN3_C95678002_PIP  I281
  J9B3     8    IO8  SCONN120_A28699018_SM  I336
  J9B3     9    IO9  SCONN120_A28699018_SM  I336
  J9B3    10   IO10  SCONN120_A28699018_SM  I336
  J9B3    11   IO11  SCONN120_A28699018_SM  I336
  J9B3    14   IO14  SCONN120_A28699018_SM  I336
  J9B3    15   IO15  SCONN120_A28699018_SM  I336
  J9B3    16   IO16  SCONN120_A28699018_SM  I336
  J9B3    17   IO17  SCONN120_A28699018_SM  I336
  J9B3    26   IO26  SCONN120_A28699018_SM  I336
  J9B3    38   IO38  SCONN120_A28699018_SM  I336
  J9B3    39   IO39  SCONN120_A28699018_SM  I336
  J9B3    41   IO41  SCONN120_A28699018_SM  I336
  J9B3    44   IO44  SCONN120_A28699018_SM  I336
  J9B3    46   IO46  SCONN120_A28699018_SM  I336
  J9B3    47   IO47  SCONN120_A28699018_SM  I336
  J9B3    49   IO49  SCONN120_A28699018_SM  I336
  J9B3    52   IO52  SCONN120_A28699018_SM  I336
  J9B3    54   IO54  SCONN120_A28699018_SM  I336
  J9B3    55   IO55  SCONN120_A28699018_SM  I336
  J9B3    57   IO57  SCONN120_A28699018_SM  I336
  J9B3    60   IO60  SCONN120_A28699018_SM  I336
  J9B3    62   IO62  SCONN120_A28699018_SM  I336
  J9B3    63   IO63  SCONN120_A28699018_SM  I336
  J9B3    65   IO65  SCONN120_A28699018_SM  I336
  J9B3    68   IO68  SCONN120_A28699018_SM  I336
  J9B3    70   IO70  SCONN120_A28699018_SM  I336
  J9B3    71   IO71  SCONN120_A28699018_SM  I336
  J9B3    73   IO73  SCONN120_A28699018_SM  I336
  J9B3    76   IO76  SCONN120_A28699018_SM  I336
  J9B3    78   IO78  SCONN120_A28699018_SM  I336
  J9B3    79   IO79  SCONN120_A28699018_SM  I336
  J9B3    81   IO81  SCONN120_A28699018_SM  I336
  J9B3    84   IO84  SCONN120_A28699018_SM  I336
  J9B3    86   IO86  SCONN120_A28699018_SM  I336
  J9B3    87   IO87  SCONN120_A28699018_SM  I336
  J9B3    89   IO89  SCONN120_A28699018_SM  I336
  J9B3    92   IO92  SCONN120_A28699018_SM  I336
  J9B3    94   IO94  SCONN120_A28699018_SM  I336
  J9B3    95   IO95  SCONN120_A28699018_SM  I336
  J9B3    97   IO97  SCONN120_A28699018_SM  I336
  J9B3   100  IO100  SCONN120_A28699018_SM  I336
  J9B3   102  IO102  SCONN120_A28699018_SM  I336
  J9B3   103  IO103  SCONN120_A28699018_SM  I336
  J9B3   105  IO105  SCONN120_A28699018_SM  I336
  J9B3   108  IO108  SCONN120_A28699018_SM  I336
  J9B3   110  IO110  SCONN120_A28699018_SM  I336
  J9B3   111  IO111  SCONN120_A28699018_SM  I336
  J9B3   113  IO113  SCONN120_A28699018_SM  I336
  J9B3   116  IO116  SCONN120_A28699018_SM  I336
  J9B3   118  IO118  SCONN120_A28699018_SM  I336
  J9B3   119  IO119  SCONN120_A28699018_SM  I336
  J9B4     2    IO2  SCONN10_C12536004  I175
  J9B4    10   IO10  SCONN10_C12536004  I175
  J9L1     2  VSS<93>  SCONN288_H44441003_PIP  I25
  J9L1     4  VSS<92>  SCONN288_H44441003_PIP  I25
  J9L1     6  VSS<91>  SCONN288_H44441003_PIP  I25
  J9L1     9  VSS<90>  SCONN288_H44441003_PIP  I25
  J9L1    11  VSS<89>  SCONN288_H44441003_PIP  I25
  J9L1    13  VSS<88>  SCONN288_H44441003_PIP  I25
  J9L1    15  VSS<87>  SCONN288_H44441003_PIP  I25
  J9L1    17  VSS<86>  SCONN288_H44441003_PIP  I25
  J9L1    20  VSS<85>  SCONN288_H44441003_PIP  I25
  J9L1    22  VSS<84>  SCONN288_H44441003_PIP  I25
  J9L1    24  VSS<83>  SCONN288_H44441003_PIP  I25
  J9L1    26  VSS<82>  SCONN288_H44441003_PIP  I25
  J9L1    28  VSS<81>  SCONN288_H44441003_PIP  I25
  J9L1    31  VSS<80>  SCONN288_H44441003_PIP  I25
  J9L1    33  VSS<79>  SCONN288_H44441003_PIP  I25
  J9L1    35  VSS<78>  SCONN288_H44441003_PIP  I25
  J9L1    37  VSS<77>  SCONN288_H44441003_PIP  I25
  J9L1    39  VSS<76>  SCONN288_H44441003_PIP  I25
  J9L1    42  VSS<75>  SCONN288_H44441003_PIP  I25
  J9L1    44  VSS<74>  SCONN288_H44441003_PIP  I25
  J9L1    46  VSS<73>  SCONN288_H44441003_PIP  I25
  J9L1    48  VSS<72>  SCONN288_H44441003_PIP  I25
  J9L1    50  VSS<71>  SCONN288_H44441003_PIP  I25
  J9L1    53  VSS<70>  SCONN288_H44441003_PIP  I25
  J9L1    55  VSS<69>  SCONN288_H44441003_PIP  I25
  J9L1    57  VSS<68>  SCONN288_H44441003_PIP  I25
  J9L1    94  VSS<67>  SCONN288_H44441003_PIP  I25
  J9L1    96  VSS<66>  SCONN288_H44441003_PIP  I25
  J9L1    98  VSS<65>  SCONN288_H44441003_PIP  I25
  J9L1   101  VSS<64>  SCONN288_H44441003_PIP  I25
  J9L1   103  VSS<63>  SCONN288_H44441003_PIP  I25
  J9L1   105  VSS<62>  SCONN288_H44441003_PIP  I25
  J9L1   107  VSS<61>  SCONN288_H44441003_PIP  I25
  J9L1   109  VSS<60>  SCONN288_H44441003_PIP  I25
  J9L1   112  VSS<59>  SCONN288_H44441003_PIP  I25
  J9L1   114  VSS<58>  SCONN288_H44441003_PIP  I25
  J9L1   116  VSS<57>  SCONN288_H44441003_PIP  I25
  J9L1   118  VSS<56>  SCONN288_H44441003_PIP  I25
  J9L1   120  VSS<55>  SCONN288_H44441003_PIP  I25
  J9L1   123  VSS<54>  SCONN288_H44441003_PIP  I25
  J9L1   125  VSS<53>  SCONN288_H44441003_PIP  I25
  J9L1   127  VSS<52>  SCONN288_H44441003_PIP  I25
  J9L1   129  VSS<51>  SCONN288_H44441003_PIP  I25
  J9L1   131  VSS<50>  SCONN288_H44441003_PIP  I25
  J9L1   134  VSS<49>  SCONN288_H44441003_PIP  I25
  J9L1   136  VSS<48>  SCONN288_H44441003_PIP  I25
  J9L1   138  VSS<47>  SCONN288_H44441003_PIP  I25
  J9L1   140  SA<1>  SCONN288_H44441003_PIP  I111
  J9L1   147  VSS<46>  SCONN288_H44441003_PIP  I25
  J9L1   149  VSS<45>  SCONN288_H44441003_PIP  I25
  J9L1   151  VSS<44>  SCONN288_H44441003_PIP  I25
  J9L1   154  VSS<43>  SCONN288_H44441003_PIP  I25
  J9L1   156  VSS<42>  SCONN288_H44441003_PIP  I25
  J9L1   158  VSS<41>  SCONN288_H44441003_PIP  I25
  J9L1   160  VSS<40>  SCONN288_H44441003_PIP  I25
  J9L1   162  VSS<39>  SCONN288_H44441003_PIP  I25
  J9L1   165  VSS<38>  SCONN288_H44441003_PIP  I25
  J9L1   167  VSS<37>  SCONN288_H44441003_PIP  I25
  J9L1   169  VSS<36>  SCONN288_H44441003_PIP  I25
  J9L1   171  VSS<35>  SCONN288_H44441003_PIP  I25
  J9L1   173  VSS<34>  SCONN288_H44441003_PIP  I25
  J9L1   176  VSS<33>  SCONN288_H44441003_PIP  I25
  J9L1   178  VSS<32>  SCONN288_H44441003_PIP  I25
  J9L1   180  VSS<31>  SCONN288_H44441003_PIP  I25
  J9L1   182  VSS<30>  SCONN288_H44441003_PIP  I25
  J9L1   184  VSS<29>  SCONN288_H44441003_PIP  I25
  J9L1   187  VSS<28>  SCONN288_H44441003_PIP  I25
  J9L1   189  VSS<27>  SCONN288_H44441003_PIP  I25
  J9L1   191  VSS<26>  SCONN288_H44441003_PIP  I25
  J9L1   193  VSS<25>  SCONN288_H44441003_PIP  I25
  J9L1   195  VSS<24>  SCONN288_H44441003_PIP  I25
  J9L1   198  VSS<23>  SCONN288_H44441003_PIP  I25
  J9L1   200  VSS<22>  SCONN288_H44441003_PIP  I25
  J9L1   202  VSS<21>  SCONN288_H44441003_PIP  I25
  J9L1   239  VSS<20>  SCONN288_H44441003_PIP  I25
  J9L1   241  VSS<19>  SCONN288_H44441003_PIP  I25
  J9L1   243  VSS<18>  SCONN288_H44441003_PIP  I25
  J9L1   246  VSS<17>  SCONN288_H44441003_PIP  I25
  J9L1   248  VSS<16>  SCONN288_H44441003_PIP  I25
  J9L1   250  VSS<15>  SCONN288_H44441003_PIP  I25
  J9L1   252  VSS<14>  SCONN288_H44441003_PIP  I25
  J9L1   254  VSS<13>  SCONN288_H44441003_PIP  I25
  J9L1   257  VSS<12>  SCONN288_H44441003_PIP  I25
  J9L1   259  VSS<11>  SCONN288_H44441003_PIP  I25
  J9L1   261  VSS<10>  SCONN288_H44441003_PIP  I25
  J9L1   263  VSS<9>  SCONN288_H44441003_PIP  I25
  J9L1   265  VSS<8>  SCONN288_H44441003_PIP  I25
  J9L1   268  VSS<7>  SCONN288_H44441003_PIP  I25
  J9L1   270  VSS<6>  SCONN288_H44441003_PIP  I25
  J9L1   272  VSS<5>  SCONN288_H44441003_PIP  I25
  J9L1   274  VSS<4>  SCONN288_H44441003_PIP  I25
  J9L1   276  VSS<3>  SCONN288_H44441003_PIP  I25
  J9L1   279  VSS<2>  SCONN288_H44441003_PIP  I25
  J9L1   281  VSS<1>  SCONN288_H44441003_PIP  I25
  J9L1   283  VSS<0>  SCONN288_H44441003_PIP  I25
  J9L2     2  VSS<93>  SCONN288_H44441003_PIP  I138
  J9L2     4  VSS<92>  SCONN288_H44441003_PIP  I138
  J9L2     6  VSS<91>  SCONN288_H44441003_PIP  I138
  J9L2     9  VSS<90>  SCONN288_H44441003_PIP  I138
  J9L2    11  VSS<89>  SCONN288_H44441003_PIP  I138
  J9L2    13  VSS<88>  SCONN288_H44441003_PIP  I138
  J9L2    15  VSS<87>  SCONN288_H44441003_PIP  I138
  J9L2    17  VSS<86>  SCONN288_H44441003_PIP  I138
  J9L2    20  VSS<85>  SCONN288_H44441003_PIP  I138
  J9L2    22  VSS<84>  SCONN288_H44441003_PIP  I138
  J9L2    24  VSS<83>  SCONN288_H44441003_PIP  I138
  J9L2    26  VSS<82>  SCONN288_H44441003_PIP  I138
  J9L2    28  VSS<81>  SCONN288_H44441003_PIP  I138
  J9L2    31  VSS<80>  SCONN288_H44441003_PIP  I138
  J9L2    33  VSS<79>  SCONN288_H44441003_PIP  I138
  J9L2    35  VSS<78>  SCONN288_H44441003_PIP  I138
  J9L2    37  VSS<77>  SCONN288_H44441003_PIP  I138
  J9L2    39  VSS<76>  SCONN288_H44441003_PIP  I138
  J9L2    42  VSS<75>  SCONN288_H44441003_PIP  I138
  J9L2    44  VSS<74>  SCONN288_H44441003_PIP  I138
  J9L2    46  VSS<73>  SCONN288_H44441003_PIP  I138
  J9L2    48  VSS<72>  SCONN288_H44441003_PIP  I138
  J9L2    50  VSS<71>  SCONN288_H44441003_PIP  I138
  J9L2    53  VSS<70>  SCONN288_H44441003_PIP  I138
  J9L2    55  VSS<69>  SCONN288_H44441003_PIP  I138
  J9L2    57  VSS<68>  SCONN288_H44441003_PIP  I138
  J9L2    94  VSS<67>  SCONN288_H44441003_PIP  I138
  J9L2    96  VSS<66>  SCONN288_H44441003_PIP  I138
  J9L2    98  VSS<65>  SCONN288_H44441003_PIP  I138
  J9L2   101  VSS<64>  SCONN288_H44441003_PIP  I138
  J9L2   103  VSS<63>  SCONN288_H44441003_PIP  I138
  J9L2   105  VSS<62>  SCONN288_H44441003_PIP  I138
  J9L2   107  VSS<61>  SCONN288_H44441003_PIP  I138
  J9L2   109  VSS<60>  SCONN288_H44441003_PIP  I138
  J9L2   112  VSS<59>  SCONN288_H44441003_PIP  I138
  J9L2   114  VSS<58>  SCONN288_H44441003_PIP  I138
  J9L2   116  VSS<57>  SCONN288_H44441003_PIP  I138
  J9L2   118  VSS<56>  SCONN288_H44441003_PIP  I138
  J9L2   120  VSS<55>  SCONN288_H44441003_PIP  I138
  J9L2   123  VSS<54>  SCONN288_H44441003_PIP  I138
  J9L2   125  VSS<53>  SCONN288_H44441003_PIP  I138
  J9L2   127  VSS<52>  SCONN288_H44441003_PIP  I138
  J9L2   129  VSS<51>  SCONN288_H44441003_PIP  I138
  J9L2   131  VSS<50>  SCONN288_H44441003_PIP  I138
  J9L2   134  VSS<49>  SCONN288_H44441003_PIP  I138
  J9L2   136  VSS<48>  SCONN288_H44441003_PIP  I138
  J9L2   138  VSS<47>  SCONN288_H44441003_PIP  I138
  J9L2   147  VSS<46>  SCONN288_H44441003_PIP  I138
  J9L2   149  VSS<45>  SCONN288_H44441003_PIP  I138
  J9L2   151  VSS<44>  SCONN288_H44441003_PIP  I138
  J9L2   154  VSS<43>  SCONN288_H44441003_PIP  I138
  J9L2   156  VSS<42>  SCONN288_H44441003_PIP  I138
  J9L2   158  VSS<41>  SCONN288_H44441003_PIP  I138
  J9L2   160  VSS<40>  SCONN288_H44441003_PIP  I138
  J9L2   162  VSS<39>  SCONN288_H44441003_PIP  I138
  J9L2   165  VSS<38>  SCONN288_H44441003_PIP  I138
  J9L2   167  VSS<37>  SCONN288_H44441003_PIP  I138
  J9L2   169  VSS<36>  SCONN288_H44441003_PIP  I138
  J9L2   171  VSS<35>  SCONN288_H44441003_PIP  I138
  J9L2   173  VSS<34>  SCONN288_H44441003_PIP  I138
  J9L2   176  VSS<33>  SCONN288_H44441003_PIP  I138
  J9L2   178  VSS<32>  SCONN288_H44441003_PIP  I138
  J9L2   180  VSS<31>  SCONN288_H44441003_PIP  I138
  J9L2   182  VSS<30>  SCONN288_H44441003_PIP  I138
  J9L2   184  VSS<29>  SCONN288_H44441003_PIP  I138
  J9L2   187  VSS<28>  SCONN288_H44441003_PIP  I138
  J9L2   189  VSS<27>  SCONN288_H44441003_PIP  I138
  J9L2   191  VSS<26>  SCONN288_H44441003_PIP  I138
  J9L2   193  VSS<25>  SCONN288_H44441003_PIP  I138
  J9L2   195  VSS<24>  SCONN288_H44441003_PIP  I138
  J9L2   198  VSS<23>  SCONN288_H44441003_PIP  I138
  J9L2   200  VSS<22>  SCONN288_H44441003_PIP  I138
  J9L2   202  VSS<21>  SCONN288_H44441003_PIP  I138
  J9L2   238  SA<2>  SCONN288_H44441003_PIP  I12
  J9L2   239  VSS<20>  SCONN288_H44441003_PIP  I138
  J9L2   241  VSS<19>  SCONN288_H44441003_PIP  I138
  J9L2   243  VSS<18>  SCONN288_H44441003_PIP  I138
  J9L2   246  VSS<17>  SCONN288_H44441003_PIP  I138
  J9L2   248  VSS<16>  SCONN288_H44441003_PIP  I138
  J9L2   250  VSS<15>  SCONN288_H44441003_PIP  I138
  J9L2   252  VSS<14>  SCONN288_H44441003_PIP  I138
  J9L2   254  VSS<13>  SCONN288_H44441003_PIP  I138
  J9L2   257  VSS<12>  SCONN288_H44441003_PIP  I138
  J9L2   259  VSS<11>  SCONN288_H44441003_PIP  I138
  J9L2   261  VSS<10>  SCONN288_H44441003_PIP  I138
  J9L2   263  VSS<9>  SCONN288_H44441003_PIP  I138
  J9L2   265  VSS<8>  SCONN288_H44441003_PIP  I138
  J9L2   268  VSS<7>  SCONN288_H44441003_PIP  I138
  J9L2   270  VSS<6>  SCONN288_H44441003_PIP  I138
  J9L2   272  VSS<5>  SCONN288_H44441003_PIP  I138
  J9L2   274  VSS<4>  SCONN288_H44441003_PIP  I138
  J9L2   276  VSS<3>  SCONN288_H44441003_PIP  I138
  J9L2   279  VSS<2>  SCONN288_H44441003_PIP  I138
  J9L2   281  VSS<1>  SCONN288_H44441003_PIP  I138
  J9L2   283  VSS<0>  SCONN288_H44441003_PIP  I138
  J9M1     2  VSS<93>  SCONN288_H44441003_PIP  I138
  J9M1     4  VSS<92>  SCONN288_H44441003_PIP  I138
  J9M1     6  VSS<91>  SCONN288_H44441003_PIP  I138
  J9M1     9  VSS<90>  SCONN288_H44441003_PIP  I138
  J9M1    11  VSS<89>  SCONN288_H44441003_PIP  I138
  J9M1    13  VSS<88>  SCONN288_H44441003_PIP  I138
  J9M1    15  VSS<87>  SCONN288_H44441003_PIP  I138
  J9M1    17  VSS<86>  SCONN288_H44441003_PIP  I138
  J9M1    20  VSS<85>  SCONN288_H44441003_PIP  I138
  J9M1    22  VSS<84>  SCONN288_H44441003_PIP  I138
  J9M1    24  VSS<83>  SCONN288_H44441003_PIP  I138
  J9M1    26  VSS<82>  SCONN288_H44441003_PIP  I138
  J9M1    28  VSS<81>  SCONN288_H44441003_PIP  I138
  J9M1    31  VSS<80>  SCONN288_H44441003_PIP  I138
  J9M1    33  VSS<79>  SCONN288_H44441003_PIP  I138
  J9M1    35  VSS<78>  SCONN288_H44441003_PIP  I138
  J9M1    37  VSS<77>  SCONN288_H44441003_PIP  I138
  J9M1    39  VSS<76>  SCONN288_H44441003_PIP  I138
  J9M1    42  VSS<75>  SCONN288_H44441003_PIP  I138
  J9M1    44  VSS<74>  SCONN288_H44441003_PIP  I138
  J9M1    46  VSS<73>  SCONN288_H44441003_PIP  I138
  J9M1    48  VSS<72>  SCONN288_H44441003_PIP  I138
  J9M1    50  VSS<71>  SCONN288_H44441003_PIP  I138
  J9M1    53  VSS<70>  SCONN288_H44441003_PIP  I138
  J9M1    55  VSS<69>  SCONN288_H44441003_PIP  I138
  J9M1    57  VSS<68>  SCONN288_H44441003_PIP  I138
  J9M1    94  VSS<67>  SCONN288_H44441003_PIP  I138
  J9M1    96  VSS<66>  SCONN288_H44441003_PIP  I138
  J9M1    98  VSS<65>  SCONN288_H44441003_PIP  I138
  J9M1   101  VSS<64>  SCONN288_H44441003_PIP  I138
  J9M1   103  VSS<63>  SCONN288_H44441003_PIP  I138
  J9M1   105  VSS<62>  SCONN288_H44441003_PIP  I138
  J9M1   107  VSS<61>  SCONN288_H44441003_PIP  I138
  J9M1   109  VSS<60>  SCONN288_H44441003_PIP  I138
  J9M1   112  VSS<59>  SCONN288_H44441003_PIP  I138
  J9M1   114  VSS<58>  SCONN288_H44441003_PIP  I138
  J9M1   116  VSS<57>  SCONN288_H44441003_PIP  I138
  J9M1   118  VSS<56>  SCONN288_H44441003_PIP  I138
  J9M1   120  VSS<55>  SCONN288_H44441003_PIP  I138
  J9M1   123  VSS<54>  SCONN288_H44441003_PIP  I138
  J9M1   125  VSS<53>  SCONN288_H44441003_PIP  I138
  J9M1   127  VSS<52>  SCONN288_H44441003_PIP  I138
  J9M1   129  VSS<51>  SCONN288_H44441003_PIP  I138
  J9M1   131  VSS<50>  SCONN288_H44441003_PIP  I138
  J9M1   134  VSS<49>  SCONN288_H44441003_PIP  I138
  J9M1   136  VSS<48>  SCONN288_H44441003_PIP  I138
  J9M1   138  VSS<47>  SCONN288_H44441003_PIP  I138
  J9M1   140  SA<1>  SCONN288_H44441003_PIP  I14
  J9M1   147  VSS<46>  SCONN288_H44441003_PIP  I138
  J9M1   149  VSS<45>  SCONN288_H44441003_PIP  I138
  J9M1   151  VSS<44>  SCONN288_H44441003_PIP  I138
  J9M1   154  VSS<43>  SCONN288_H44441003_PIP  I138
  J9M1   156  VSS<42>  SCONN288_H44441003_PIP  I138
  J9M1   158  VSS<41>  SCONN288_H44441003_PIP  I138
  J9M1   160  VSS<40>  SCONN288_H44441003_PIP  I138
  J9M1   162  VSS<39>  SCONN288_H44441003_PIP  I138
  J9M1   165  VSS<38>  SCONN288_H44441003_PIP  I138
  J9M1   167  VSS<37>  SCONN288_H44441003_PIP  I138
  J9M1   169  VSS<36>  SCONN288_H44441003_PIP  I138
  J9M1   171  VSS<35>  SCONN288_H44441003_PIP  I138
  J9M1   173  VSS<34>  SCONN288_H44441003_PIP  I138
  J9M1   176  VSS<33>  SCONN288_H44441003_PIP  I138
  J9M1   178  VSS<32>  SCONN288_H44441003_PIP  I138
  J9M1   180  VSS<31>  SCONN288_H44441003_PIP  I138
  J9M1   182  VSS<30>  SCONN288_H44441003_PIP  I138
  J9M1   184  VSS<29>  SCONN288_H44441003_PIP  I138
  J9M1   187  VSS<28>  SCONN288_H44441003_PIP  I138
  J9M1   189  VSS<27>  SCONN288_H44441003_PIP  I138
  J9M1   191  VSS<26>  SCONN288_H44441003_PIP  I138
  J9M1   193  VSS<25>  SCONN288_H44441003_PIP  I138
  J9M1   195  VSS<24>  SCONN288_H44441003_PIP  I138
  J9M1   198  VSS<23>  SCONN288_H44441003_PIP  I138
  J9M1   200  VSS<22>  SCONN288_H44441003_PIP  I138
  J9M1   202  VSS<21>  SCONN288_H44441003_PIP  I138
  J9M1   238  SA<2>  SCONN288_H44441003_PIP  I14
  J9M1   239  VSS<20>  SCONN288_H44441003_PIP  I138
  J9M1   241  VSS<19>  SCONN288_H44441003_PIP  I138
  J9M1   243  VSS<18>  SCONN288_H44441003_PIP  I138
  J9M1   246  VSS<17>  SCONN288_H44441003_PIP  I138
  J9M1   248  VSS<16>  SCONN288_H44441003_PIP  I138
  J9M1   250  VSS<15>  SCONN288_H44441003_PIP  I138
  J9M1   252  VSS<14>  SCONN288_H44441003_PIP  I138
  J9M1   254  VSS<13>  SCONN288_H44441003_PIP  I138
  J9M1   257  VSS<12>  SCONN288_H44441003_PIP  I138
  J9M1   259  VSS<11>  SCONN288_H44441003_PIP  I138
  J9M1   261  VSS<10>  SCONN288_H44441003_PIP  I138
  J9M1   263  VSS<9>  SCONN288_H44441003_PIP  I138
  J9M1   265  VSS<8>  SCONN288_H44441003_PIP  I138
  J9M1   268  VSS<7>  SCONN288_H44441003_PIP  I138
  J9M1   270  VSS<6>  SCONN288_H44441003_PIP  I138
  J9M1   272  VSS<5>  SCONN288_H44441003_PIP  I138
  J9M1   274  VSS<4>  SCONN288_H44441003_PIP  I138
  J9M1   276  VSS<3>  SCONN288_H44441003_PIP  I138
  J9M1   279  VSS<2>  SCONN288_H44441003_PIP  I138
  J9M1   281  VSS<1>  SCONN288_H44441003_PIP  I138
  J9M1   283  VSS<0>  SCONN288_H44441003_PIP  I138
  J9T1     2  VSS<93>  SCONN288_H44441003_PIP  I144
  J9T1     4  VSS<92>  SCONN288_H44441003_PIP  I144
  J9T1     6  VSS<91>  SCONN288_H44441003_PIP  I144
  J9T1     9  VSS<90>  SCONN288_H44441003_PIP  I144
  J9T1    11  VSS<89>  SCONN288_H44441003_PIP  I144
  J9T1    13  VSS<88>  SCONN288_H44441003_PIP  I144
  J9T1    15  VSS<87>  SCONN288_H44441003_PIP  I144
  J9T1    17  VSS<86>  SCONN288_H44441003_PIP  I144
  J9T1    20  VSS<85>  SCONN288_H44441003_PIP  I144
  J9T1    22  VSS<84>  SCONN288_H44441003_PIP  I144
  J9T1    24  VSS<83>  SCONN288_H44441003_PIP  I144
  J9T1    26  VSS<82>  SCONN288_H44441003_PIP  I144
  J9T1    28  VSS<81>  SCONN288_H44441003_PIP  I144
  J9T1    31  VSS<80>  SCONN288_H44441003_PIP  I144
  J9T1    33  VSS<79>  SCONN288_H44441003_PIP  I144
  J9T1    35  VSS<78>  SCONN288_H44441003_PIP  I144
  J9T1    37  VSS<77>  SCONN288_H44441003_PIP  I144
  J9T1    39  VSS<76>  SCONN288_H44441003_PIP  I144
  J9T1    42  VSS<75>  SCONN288_H44441003_PIP  I144
  J9T1    44  VSS<74>  SCONN288_H44441003_PIP  I144
  J9T1    46  VSS<73>  SCONN288_H44441003_PIP  I144
  J9T1    48  VSS<72>  SCONN288_H44441003_PIP  I144
  J9T1    50  VSS<71>  SCONN288_H44441003_PIP  I144
  J9T1    53  VSS<70>  SCONN288_H44441003_PIP  I144
  J9T1    55  VSS<69>  SCONN288_H44441003_PIP  I144
  J9T1    57  VSS<68>  SCONN288_H44441003_PIP  I144
  J9T1    94  VSS<67>  SCONN288_H44441003_PIP  I144
  J9T1    96  VSS<66>  SCONN288_H44441003_PIP  I144
  J9T1    98  VSS<65>  SCONN288_H44441003_PIP  I144
  J9T1   101  VSS<64>  SCONN288_H44441003_PIP  I144
  J9T1   103  VSS<63>  SCONN288_H44441003_PIP  I144
  J9T1   105  VSS<62>  SCONN288_H44441003_PIP  I144
  J9T1   107  VSS<61>  SCONN288_H44441003_PIP  I144
  J9T1   109  VSS<60>  SCONN288_H44441003_PIP  I144
  J9T1   112  VSS<59>  SCONN288_H44441003_PIP  I144
  J9T1   114  VSS<58>  SCONN288_H44441003_PIP  I144
  J9T1   116  VSS<57>  SCONN288_H44441003_PIP  I144
  J9T1   118  VSS<56>  SCONN288_H44441003_PIP  I144
  J9T1   120  VSS<55>  SCONN288_H44441003_PIP  I144
  J9T1   123  VSS<54>  SCONN288_H44441003_PIP  I144
  J9T1   125  VSS<53>  SCONN288_H44441003_PIP  I144
  J9T1   127  VSS<52>  SCONN288_H44441003_PIP  I144
  J9T1   129  VSS<51>  SCONN288_H44441003_PIP  I144
  J9T1   131  VSS<50>  SCONN288_H44441003_PIP  I144
  J9T1   134  VSS<49>  SCONN288_H44441003_PIP  I144
  J9T1   136  VSS<48>  SCONN288_H44441003_PIP  I144
  J9T1   138  VSS<47>  SCONN288_H44441003_PIP  I144
  J9T1   140  SA<1>  SCONN288_H44441003_PIP  I13
  J9T1   147  VSS<46>  SCONN288_H44441003_PIP  I144
  J9T1   149  VSS<45>  SCONN288_H44441003_PIP  I144
  J9T1   151  VSS<44>  SCONN288_H44441003_PIP  I144
  J9T1   154  VSS<43>  SCONN288_H44441003_PIP  I144
  J9T1   156  VSS<42>  SCONN288_H44441003_PIP  I144
  J9T1   158  VSS<41>  SCONN288_H44441003_PIP  I144
  J9T1   160  VSS<40>  SCONN288_H44441003_PIP  I144
  J9T1   162  VSS<39>  SCONN288_H44441003_PIP  I144
  J9T1   165  VSS<38>  SCONN288_H44441003_PIP  I144
  J9T1   167  VSS<37>  SCONN288_H44441003_PIP  I144
  J9T1   169  VSS<36>  SCONN288_H44441003_PIP  I144
  J9T1   171  VSS<35>  SCONN288_H44441003_PIP  I144
  J9T1   173  VSS<34>  SCONN288_H44441003_PIP  I144
  J9T1   176  VSS<33>  SCONN288_H44441003_PIP  I144
  J9T1   178  VSS<32>  SCONN288_H44441003_PIP  I144
  J9T1   180  VSS<31>  SCONN288_H44441003_PIP  I144
  J9T1   182  VSS<30>  SCONN288_H44441003_PIP  I144
  J9T1   184  VSS<29>  SCONN288_H44441003_PIP  I144
  J9T1   187  VSS<28>  SCONN288_H44441003_PIP  I144
  J9T1   189  VSS<27>  SCONN288_H44441003_PIP  I144
  J9T1   191  VSS<26>  SCONN288_H44441003_PIP  I144
  J9T1   193  VSS<25>  SCONN288_H44441003_PIP  I144
  J9T1   195  VSS<24>  SCONN288_H44441003_PIP  I144
  J9T1   198  VSS<23>  SCONN288_H44441003_PIP  I144
  J9T1   200  VSS<22>  SCONN288_H44441003_PIP  I144
  J9T1   202  VSS<21>  SCONN288_H44441003_PIP  I144
  J9T1   238  SA<2>  SCONN288_H44441003_PIP  I13
  J9T1   239  VSS<20>  SCONN288_H44441003_PIP  I144
  J9T1   241  VSS<19>  SCONN288_H44441003_PIP  I144
  J9T1   243  VSS<18>  SCONN288_H44441003_PIP  I144
  J9T1   246  VSS<17>  SCONN288_H44441003_PIP  I144
  J9T1   248  VSS<16>  SCONN288_H44441003_PIP  I144
  J9T1   250  VSS<15>  SCONN288_H44441003_PIP  I144
  J9T1   252  VSS<14>  SCONN288_H44441003_PIP  I144
  J9T1   254  VSS<13>  SCONN288_H44441003_PIP  I144
  J9T1   257  VSS<12>  SCONN288_H44441003_PIP  I144
  J9T1   259  VSS<11>  SCONN288_H44441003_PIP  I144
  J9T1   261  VSS<10>  SCONN288_H44441003_PIP  I144
  J9T1   263  VSS<9>  SCONN288_H44441003_PIP  I144
  J9T1   265  VSS<8>  SCONN288_H44441003_PIP  I144
  J9T1   268  VSS<7>  SCONN288_H44441003_PIP  I144
  J9T1   270  VSS<6>  SCONN288_H44441003_PIP  I144
  J9T1   272  VSS<5>  SCONN288_H44441003_PIP  I144
  J9T1   274  VSS<4>  SCONN288_H44441003_PIP  I144
  J9T1   276  VSS<3>  SCONN288_H44441003_PIP  I144
  J9T1   279  VSS<2>  SCONN288_H44441003_PIP  I144
  J9T1   281  VSS<1>  SCONN288_H44441003_PIP  I144
  J9T1   283  VSS<0>  SCONN288_H44441003_PIP  I144
  J9U1     2  VSS<93>  SCONN288_H44441003_PIP  I138
  J9U1     4  VSS<92>  SCONN288_H44441003_PIP  I138
  J9U1     6  VSS<91>  SCONN288_H44441003_PIP  I138
  J9U1     9  VSS<90>  SCONN288_H44441003_PIP  I138
  J9U1    11  VSS<89>  SCONN288_H44441003_PIP  I138
  J9U1    13  VSS<88>  SCONN288_H44441003_PIP  I138
  J9U1    15  VSS<87>  SCONN288_H44441003_PIP  I138
  J9U1    17  VSS<86>  SCONN288_H44441003_PIP  I138
  J9U1    20  VSS<85>  SCONN288_H44441003_PIP  I138
  J9U1    22  VSS<84>  SCONN288_H44441003_PIP  I138
  J9U1    24  VSS<83>  SCONN288_H44441003_PIP  I138
  J9U1    26  VSS<82>  SCONN288_H44441003_PIP  I138
  J9U1    28  VSS<81>  SCONN288_H44441003_PIP  I138
  J9U1    31  VSS<80>  SCONN288_H44441003_PIP  I138
  J9U1    33  VSS<79>  SCONN288_H44441003_PIP  I138
  J9U1    35  VSS<78>  SCONN288_H44441003_PIP  I138
  J9U1    37  VSS<77>  SCONN288_H44441003_PIP  I138
  J9U1    39  VSS<76>  SCONN288_H44441003_PIP  I138
  J9U1    42  VSS<75>  SCONN288_H44441003_PIP  I138
  J9U1    44  VSS<74>  SCONN288_H44441003_PIP  I138
  J9U1    46  VSS<73>  SCONN288_H44441003_PIP  I138
  J9U1    48  VSS<72>  SCONN288_H44441003_PIP  I138
  J9U1    50  VSS<71>  SCONN288_H44441003_PIP  I138
  J9U1    53  VSS<70>  SCONN288_H44441003_PIP  I138
  J9U1    55  VSS<69>  SCONN288_H44441003_PIP  I138
  J9U1    57  VSS<68>  SCONN288_H44441003_PIP  I138
  J9U1    94  VSS<67>  SCONN288_H44441003_PIP  I138
  J9U1    96  VSS<66>  SCONN288_H44441003_PIP  I138
  J9U1    98  VSS<65>  SCONN288_H44441003_PIP  I138
  J9U1   101  VSS<64>  SCONN288_H44441003_PIP  I138
  J9U1   103  VSS<63>  SCONN288_H44441003_PIP  I138
  J9U1   105  VSS<62>  SCONN288_H44441003_PIP  I138
  J9U1   107  VSS<61>  SCONN288_H44441003_PIP  I138
  J9U1   109  VSS<60>  SCONN288_H44441003_PIP  I138
  J9U1   112  VSS<59>  SCONN288_H44441003_PIP  I138
  J9U1   114  VSS<58>  SCONN288_H44441003_PIP  I138
  J9U1   116  VSS<57>  SCONN288_H44441003_PIP  I138
  J9U1   118  VSS<56>  SCONN288_H44441003_PIP  I138
  J9U1   120  VSS<55>  SCONN288_H44441003_PIP  I138
  J9U1   123  VSS<54>  SCONN288_H44441003_PIP  I138
  J9U1   125  VSS<53>  SCONN288_H44441003_PIP  I138
  J9U1   127  VSS<52>  SCONN288_H44441003_PIP  I138
  J9U1   129  VSS<51>  SCONN288_H44441003_PIP  I138
  J9U1   131  VSS<50>  SCONN288_H44441003_PIP  I138
  J9U1   134  VSS<49>  SCONN288_H44441003_PIP  I138
  J9U1   136  VSS<48>  SCONN288_H44441003_PIP  I138
  J9U1   138  VSS<47>  SCONN288_H44441003_PIP  I138
  J9U1   147  VSS<46>  SCONN288_H44441003_PIP  I138
  J9U1   149  VSS<45>  SCONN288_H44441003_PIP  I138
  J9U1   151  VSS<44>  SCONN288_H44441003_PIP  I138
  J9U1   154  VSS<43>  SCONN288_H44441003_PIP  I138
  J9U1   156  VSS<42>  SCONN288_H44441003_PIP  I138
  J9U1   158  VSS<41>  SCONN288_H44441003_PIP  I138
  J9U1   160  VSS<40>  SCONN288_H44441003_PIP  I138
  J9U1   162  VSS<39>  SCONN288_H44441003_PIP  I138
  J9U1   165  VSS<38>  SCONN288_H44441003_PIP  I138
  J9U1   167  VSS<37>  SCONN288_H44441003_PIP  I138
  J9U1   169  VSS<36>  SCONN288_H44441003_PIP  I138
  J9U1   171  VSS<35>  SCONN288_H44441003_PIP  I138
  J9U1   173  VSS<34>  SCONN288_H44441003_PIP  I138
  J9U1   176  VSS<33>  SCONN288_H44441003_PIP  I138
  J9U1   178  VSS<32>  SCONN288_H44441003_PIP  I138
  J9U1   180  VSS<31>  SCONN288_H44441003_PIP  I138
  J9U1   182  VSS<30>  SCONN288_H44441003_PIP  I138
  J9U1   184  VSS<29>  SCONN288_H44441003_PIP  I138
  J9U1   187  VSS<28>  SCONN288_H44441003_PIP  I138
  J9U1   189  VSS<27>  SCONN288_H44441003_PIP  I138
  J9U1   191  VSS<26>  SCONN288_H44441003_PIP  I138
  J9U1   193  VSS<25>  SCONN288_H44441003_PIP  I138
  J9U1   195  VSS<24>  SCONN288_H44441003_PIP  I138
  J9U1   198  VSS<23>  SCONN288_H44441003_PIP  I138
  J9U1   200  VSS<22>  SCONN288_H44441003_PIP  I138
  J9U1   202  VSS<21>  SCONN288_H44441003_PIP  I138
  J9U1   238  SA<2>  SCONN288_H44441003_PIP  I24
  J9U1   239  VSS<20>  SCONN288_H44441003_PIP  I138
  J9U1   241  VSS<19>  SCONN288_H44441003_PIP  I138
  J9U1   243  VSS<18>  SCONN288_H44441003_PIP  I138
  J9U1   246  VSS<17>  SCONN288_H44441003_PIP  I138
  J9U1   248  VSS<16>  SCONN288_H44441003_PIP  I138
  J9U1   250  VSS<15>  SCONN288_H44441003_PIP  I138
  J9U1   252  VSS<14>  SCONN288_H44441003_PIP  I138
  J9U1   254  VSS<13>  SCONN288_H44441003_PIP  I138
  J9U1   257  VSS<12>  SCONN288_H44441003_PIP  I138
  J9U1   259  VSS<11>  SCONN288_H44441003_PIP  I138
  J9U1   261  VSS<10>  SCONN288_H44441003_PIP  I138
  J9U1   263  VSS<9>  SCONN288_H44441003_PIP  I138
  J9U1   265  VSS<8>  SCONN288_H44441003_PIP  I138
  J9U1   268  VSS<7>  SCONN288_H44441003_PIP  I138
  J9U1   270  VSS<6>  SCONN288_H44441003_PIP  I138
  J9U1   272  VSS<5>  SCONN288_H44441003_PIP  I138
  J9U1   274  VSS<4>  SCONN288_H44441003_PIP  I138
  J9U1   276  VSS<3>  SCONN288_H44441003_PIP  I138
  J9U1   279  VSS<2>  SCONN288_H44441003_PIP  I138
  J9U1   281  VSS<1>  SCONN288_H44441003_PIP  I138
  J9U1   283  VSS<0>  SCONN288_H44441003_PIP  I138
  J9U2     2  VSS<93>  SCONN288_H44441003_PIP  I188
  J9U2     4  VSS<92>  SCONN288_H44441003_PIP  I188
  J9U2     6  VSS<91>  SCONN288_H44441003_PIP  I188
  J9U2     9  VSS<90>  SCONN288_H44441003_PIP  I188
  J9U2    11  VSS<89>  SCONN288_H44441003_PIP  I188
  J9U2    13  VSS<88>  SCONN288_H44441003_PIP  I188
  J9U2    15  VSS<87>  SCONN288_H44441003_PIP  I188
  J9U2    17  VSS<86>  SCONN288_H44441003_PIP  I188
  J9U2    20  VSS<85>  SCONN288_H44441003_PIP  I188
  J9U2    22  VSS<84>  SCONN288_H44441003_PIP  I188
  J9U2    24  VSS<83>  SCONN288_H44441003_PIP  I188
  J9U2    26  VSS<82>  SCONN288_H44441003_PIP  I188
  J9U2    28  VSS<81>  SCONN288_H44441003_PIP  I188
  J9U2    31  VSS<80>  SCONN288_H44441003_PIP  I188
  J9U2    33  VSS<79>  SCONN288_H44441003_PIP  I188
  J9U2    35  VSS<78>  SCONN288_H44441003_PIP  I188
  J9U2    37  VSS<77>  SCONN288_H44441003_PIP  I188
  J9U2    39  VSS<76>  SCONN288_H44441003_PIP  I188
  J9U2    42  VSS<75>  SCONN288_H44441003_PIP  I188
  J9U2    44  VSS<74>  SCONN288_H44441003_PIP  I188
  J9U2    46  VSS<73>  SCONN288_H44441003_PIP  I188
  J9U2    48  VSS<72>  SCONN288_H44441003_PIP  I188
  J9U2    50  VSS<71>  SCONN288_H44441003_PIP  I188
  J9U2    53  VSS<70>  SCONN288_H44441003_PIP  I188
  J9U2    55  VSS<69>  SCONN288_H44441003_PIP  I188
  J9U2    57  VSS<68>  SCONN288_H44441003_PIP  I188
  J9U2    94  VSS<67>  SCONN288_H44441003_PIP  I188
  J9U2    96  VSS<66>  SCONN288_H44441003_PIP  I188
  J9U2    98  VSS<65>  SCONN288_H44441003_PIP  I188
  J9U2   101  VSS<64>  SCONN288_H44441003_PIP  I188
  J9U2   103  VSS<63>  SCONN288_H44441003_PIP  I188
  J9U2   105  VSS<62>  SCONN288_H44441003_PIP  I188
  J9U2   107  VSS<61>  SCONN288_H44441003_PIP  I188
  J9U2   109  VSS<60>  SCONN288_H44441003_PIP  I188
  J9U2   112  VSS<59>  SCONN288_H44441003_PIP  I188
  J9U2   114  VSS<58>  SCONN288_H44441003_PIP  I188
  J9U2   116  VSS<57>  SCONN288_H44441003_PIP  I188
  J9U2   118  VSS<56>  SCONN288_H44441003_PIP  I188
  J9U2   120  VSS<55>  SCONN288_H44441003_PIP  I188
  J9U2   123  VSS<54>  SCONN288_H44441003_PIP  I188
  J9U2   125  VSS<53>  SCONN288_H44441003_PIP  I188
  J9U2   127  VSS<52>  SCONN288_H44441003_PIP  I188
  J9U2   129  VSS<51>  SCONN288_H44441003_PIP  I188
  J9U2   131  VSS<50>  SCONN288_H44441003_PIP  I188
  J9U2   134  VSS<49>  SCONN288_H44441003_PIP  I188
  J9U2   136  VSS<48>  SCONN288_H44441003_PIP  I188
  J9U2   138  VSS<47>  SCONN288_H44441003_PIP  I188
  J9U2   140  SA<1>  SCONN288_H44441003_PIP  I187
  J9U2   147  VSS<46>  SCONN288_H44441003_PIP  I188
  J9U2   149  VSS<45>  SCONN288_H44441003_PIP  I188
  J9U2   151  VSS<44>  SCONN288_H44441003_PIP  I188
  J9U2   154  VSS<43>  SCONN288_H44441003_PIP  I188
  J9U2   156  VSS<42>  SCONN288_H44441003_PIP  I188
  J9U2   158  VSS<41>  SCONN288_H44441003_PIP  I188
  J9U2   160  VSS<40>  SCONN288_H44441003_PIP  I188
  J9U2   162  VSS<39>  SCONN288_H44441003_PIP  I188
  J9U2   165  VSS<38>  SCONN288_H44441003_PIP  I188
  J9U2   167  VSS<37>  SCONN288_H44441003_PIP  I188
  J9U2   169  VSS<36>  SCONN288_H44441003_PIP  I188
  J9U2   171  VSS<35>  SCONN288_H44441003_PIP  I188
  J9U2   173  VSS<34>  SCONN288_H44441003_PIP  I188
  J9U2   176  VSS<33>  SCONN288_H44441003_PIP  I188
  J9U2   178  VSS<32>  SCONN288_H44441003_PIP  I188
  J9U2   180  VSS<31>  SCONN288_H44441003_PIP  I188
  J9U2   182  VSS<30>  SCONN288_H44441003_PIP  I188
  J9U2   184  VSS<29>  SCONN288_H44441003_PIP  I188
  J9U2   187  VSS<28>  SCONN288_H44441003_PIP  I188
  J9U2   189  VSS<27>  SCONN288_H44441003_PIP  I188
  J9U2   191  VSS<26>  SCONN288_H44441003_PIP  I188
  J9U2   193  VSS<25>  SCONN288_H44441003_PIP  I188
  J9U2   195  VSS<24>  SCONN288_H44441003_PIP  I188
  J9U2   198  VSS<23>  SCONN288_H44441003_PIP  I188
  J9U2   200  VSS<22>  SCONN288_H44441003_PIP  I188
  J9U2   202  VSS<21>  SCONN288_H44441003_PIP  I188
  J9U2   239  VSS<20>  SCONN288_H44441003_PIP  I188
  J9U2   241  VSS<19>  SCONN288_H44441003_PIP  I188
  J9U2   243  VSS<18>  SCONN288_H44441003_PIP  I188
  J9U2   246  VSS<17>  SCONN288_H44441003_PIP  I188
  J9U2   248  VSS<16>  SCONN288_H44441003_PIP  I188
  J9U2   250  VSS<15>  SCONN288_H44441003_PIP  I188
  J9U2   252  VSS<14>  SCONN288_H44441003_PIP  I188
  J9U2   254  VSS<13>  SCONN288_H44441003_PIP  I188
  J9U2   257  VSS<12>  SCONN288_H44441003_PIP  I188
  J9U2   259  VSS<11>  SCONN288_H44441003_PIP  I188
  J9U2   261  VSS<10>  SCONN288_H44441003_PIP  I188
  J9U2   263  VSS<9>  SCONN288_H44441003_PIP  I188
  J9U2   265  VSS<8>  SCONN288_H44441003_PIP  I188
  J9U2   268  VSS<7>  SCONN288_H44441003_PIP  I188
  J9U2   270  VSS<6>  SCONN288_H44441003_PIP  I188
  J9U2   272  VSS<5>  SCONN288_H44441003_PIP  I188
  J9U2   274  VSS<4>  SCONN288_H44441003_PIP  I188
  J9U2   276  VSS<3>  SCONN288_H44441003_PIP  I188
  J9U2   279  VSS<2>  SCONN288_H44441003_PIP  I188
  J9U2   281  VSS<1>  SCONN288_H44441003_PIP  I188
  J9U2   283  VSS<0>  SCONN288_H44441003_PIP  I188
  Q1D2     2    SRC  FET_N       I203
  Q1D3     2      E  NPN_SM      I58
  Q1L1     2      E  NPN_SM       I9
  Q1L2     4  SOURCE<0>  FET_N_DUAL_SMLF  I187
  Q1L3     2      E  NPN_SM       I8
  Q1L4     1  SOURCE<0>  FET_N_DUAL_SMLF  I19
  Q2P1     2    SRC  FET_N       I58
  Q2P2     2    SRC  FET_N       I124
  Q2T1     2      E  NPN_SM      I330
  Q2T2     2    SRC  FET_N       I340
  Q2U1     1  SOURCE<0>  FET_N_DUAL_SMLF  I28
  Q2U1     4  SOURCE<0>  FET_N_DUAL_SMLF  I113
  Q3U1     1  SOURCE<0>  FET_N_DUAL_SMLF  I49
  Q3U1     4  SOURCE<0>  FET_N_DUAL_SMLF  I89
  Q4B1     1  SOURCE<0>  FET_N_DUAL_SMLF  I84
  Q4B1     4  SOURCE<0>  FET_N_DUAL_SMLF  I77
  Q4B2     1  SOURCE<0>  FET_N_DUAL_SMLF  I32
  Q4B2     4  SOURCE<0>  FET_N_DUAL_SMLF  I33
  Q4U1     1  SOURCE<0>  FET_N_DUAL_SMLF  I98
  Q4U1     4  SOURCE<0>  FET_N_DUAL_SMLF  I102
  Q6F1     2    SRC  FET_N       I18
  Q7D1     2    SRC  FET_N       I10
  Q7E1     1  SOURCE<0>  FET_N_DUAL_SMLF  I60
  Q7E1     4  SOURCE<0>  FET_N_DUAL_SMLF  I64
  Q7E2     1  SOURCE<0>  FET_N_DUAL_SMLF  I69
  Q7E2     4  SOURCE<0>  FET_N_DUAL_SMLF  I75
  Q7E3     1  SOURCE<0>  FET_N_DUAL_SMLF  I52
  Q7E3     4  SOURCE<0>  FET_N_DUAL_SMLF  I51
  Q7E4     2    SRC  FET_N       I104
  Q7E5     1  SOURCE<0>  FET_N_DUAL_SMLF  I111
  Q7E5     4  SOURCE<0>  FET_N_DUAL_SMLF  I59
  Q7E6     1  SOURCE<0>  FET_N_DUAL_SMLF  I112
  Q7E6     4  SOURCE<0>  FET_N_DUAL_SMLF  I69
  Q7E8     2    SRC  FET_N       I119
  Q8D1     1   E<0>  NPN_DUAL    I36
  Q8D1     4   E<0>  NPN_DUAL    I35
  Q8E1     2    SRC  FET_N       I134
  Q8E2     2    SRC  FET_N       I13
  Q8F1     2    SRC  FET_N       I126
  Q8F2     2    SRC  FET_N       I67
  Q9A2     1  SOURCE<0>  FET_N_DUAL_SMLF  I175
  Q9A2     4  SOURCE<0>  FET_N_DUAL_SMLF  I180
  Q9A3     2    SRC  FET_N       I49
  Q9E1     1  SOURCE<0>  FET_N_DUAL_SMLF  I135
  Q9E1     4  SOURCE<0>  FET_N_DUAL_SMLF  I55
  Q9F1     1  SOURCE<0>  FET_N_DUAL_SMLF  I80
  Q9F1     4  SOURCE<0>  FET_N_DUAL_SMLF  I79
  Q9G1     1  SOURCE<0>  FET_N_DUAL_SMLF  I162
  Q9P1     1  SOURCE<0>  FET_N_DUAL_SMLF  I196
  Q9P1     4  SOURCE<0>  FET_N_DUAL_SMLF  I199
  Q9T1     2      E  NPN_SM      I181
  R1A1     2      B  RES         I58
  R1A2     2      B  RES         I105
  R1A3     2      B  RES         I103
  R1B9     2      B  RES         I58
  R1B12    2      B  RES         I78
  R1B15    2      B  RES         I77
  R1C4     2      B  RES         I33
  R1C16    2      B  RES         I56
  R1C32    1      A  RES         I312
  R1C33    1      A  RES         I313
  R1C36    2      B  RES         I337
  R1C37    2      B  RES         I52
  R1D31    2      B  RES         I43
  R1D41    1      A  RES         I19
  R1D52    2      B  RES         I59
  R1D54    2      B  RES         I75
  R1D55    2      B  RES         I76
  R1E3     2      B  RES          I7
  R1E8     2      B  RES          I9
  R1E13    2      B  RES         I67
  R1E14    2      B  RES         I68
  R1F6     2      B  RES          I2
  R1G3     2      B  RES         I20
  R1G17    2      B  RES         I36
  R1G20    2      B  RES         I58
  R1G22    2      B  RES         I78
  R1G23    2      B  RES         I77
  R1G24    2      B  RES         I58
  R1G25    2      B  RES         I114
  R1G26    2      B  RES         I112
  R1L3     2      B  RES          I5
  R1M23    2      B  RES         I199
  R1M25    2      B  RES         I111
  R1R6     2      B  RES         I14
  R1R12    2      B  RES         I213
  R1T1     2      B  RES         I214
  R1T10    2      B  RES          I5
  R1T11    2      B  RES          I7
  R1T12    2      B  RES          I6
  R1T23    2      B  RES         I184
  R1T25    2      B  RES         I461
  R1T27    2      B  RES         I32
  R1T29    2      B  RES         I61
  R1U1     2      B  RES         I144
  R1U2     2      B  RES         I145
  R1U3     1      A  RES         I114
  R1U4     2      B  RES         I149
  R1U5     2      B  RES         I148
  R1U6     2      B  RES         I128
  R1U7     1      A  RES         I127
  R1U15    2      B  RES         I22
  R1U16    2      B  RES         I20
  R1U17    2      B  RES         I21
  R1U18    2      B  RES         I19
  R1U27    2      B  RES         I149
  R1U28    2      B  RES         I142
  R1U30    2      B  RES          I2
  R1U33    2      B  RES         I83
  R1U37    2      B  RES         I26
  R1U38    2      B  RES         I114
  R1U44    2      B  RES         I116
  R1U45    2      B  RES         I55
  R1U48    2      B  RES         I56
  R1U51    1      A  RES         I112
  R1U63    2      B  RES         I15
  R1U64    2      B  RES         I69
  R2L9     2      B  RES         I176
  R2L10    2      B  RES         I166
  R2L18    2      B  RES         I266
  R2L19    2      B  RES         I80
  R2L22    2      B  RES         I264
  R2N12    1      A  RES         I122
  R2N13    2      B  RES         I142
  R2N18    2      B  RES         I32
  R2N24    2      B  RES         I113
  R2P11    2      B  RES         I63
  R2R8     2      B  RES         I18
  R2R11    2      B  RES         I11
  R2T1     2      B  RES         I15
  R2T4     2      B  RES         I152
  R2T12    2      B  RES         I205
  R2T15    2      B  RES         I532
  R2T25    2      B  RES         I48
  R2T39    2      B  RES         I98
  R2T50    2      B  RES         I127
  R3D1     2      B  RES         I116
  R3D2     2      B  RES         I117
  R3D3     2      B  RES         I118
  R3D4     2      B  RES         I155
  R3D9     2      B  RES         I88
  R3D12    1      A  RES         I11
  R3D13    1      A  RES         I12
  R3D19    2      B  RES         I125
  R3D27    2      B  RES         I43
  R3D28    2      B  RES         I101
  R3L14    2      B  RES         I120
  R3L15    2      B  RES         I118
  R3M8     2      B  RES         I235
  R3M9     2      B  RES         I234
  R3M10    2      B  RES         I85
  R3N1     2      B  RES         I149
  R3N3     1      A  RES         I120
  R3N14    2      B  RES         I67
  R3N20    2      B  RES         I68
  R3N22    2      B  RES         I65
  R3N29    2      B  RES         I156
  R3N31    2      B  RES         I52
  R3P16    2      B  RES         I32
  R3P32    1      A  RES         I71
  R3P49    2      B  RES         I38
  R3P51    2      B  RES         I75
  R3P56    2      B  RES         I333
  R3P64    2      B  RES         I23
  R3R1     2      B  RES         I46
  R3R2     2      B  RES         I75
  R3R11    2      B  RES         I45
  R3T9     2      B  RES         I179
  R3T14    2      B  RES         I156
  R3U4     2      B  RES         I58
  R4A1     1      A  RES         I52
  R4A7     2      B  RES         I162
  R4B2     2      B  RES         I183
  R4B14    1      A  RES         I29
  R4C1     2      B  RES         I29
  R4C9     1      A  RES         I69
  R4C11    2      B  RES         I170
  R4C12    2      B  RES         I169
  R4C13    2      B  RES         I62
  R4D18    2      B  RES         I163
  R4D24    2      B  RES         I161
  R4D32    2      B  RES         I55
  R4D57    2      B  RES         I32
  R4D64    2      B  RES         I42
  R4D68    2      B  RES         I83
  R4D71    2      B  RES         I91
  R4D72    2      B  RES         I89
  R4E2     2      B  RES         I65
  R4E13    2      B  RES         I67
  R4E18    2      B  RES         I64
  R4E19    2      B  RES         I67
  R4E21    2      B  RES         I127
  R4E22    2      B  RES         I65
  R4F5     2      B  RES          I4
  R4F6     2      B  RES         I208
  R4G3     2      B  RES         I40
  R4G5     2      B  RES         I182
  R4G6     2      B  RES         I211
  R4G22    2      B  RES         I48
  R4G25    1      A  RES         I157
  R4L4     2      B  RES         I58
  R4P1     1      A  RES          I4
  R4P2     2      B  RES         I188
  R4P3     2      B  RES         I186
  R4P4     2      B  RES         I189
  R4P5     1      A  RES         I80
  R4P6     1      A  RES         I68
  R4P7     1      A  RES         I72
  R4P8     2      B  RES         I180
  R4P10    2      B  RES         I181
  R4P11    2      B  RES         I182
  R4U4     2      B  RES         I104
  R5D1     2      B  RES         I177
  R5D2     2      B  RES         I178
  R5D5     2      B  RES         I303
  R5P2     2      B  RES         I79
  R5P3     2      B  RES         I80
  R5P4     2      B  RES         I190
  R5R1     2      B  RES         I188
  R6D1     2      B  RES         I179
  R6D2     2      B  RES         I204
  R6D5     2      B  RES         I81
  R6D6     1      A  RES          I3
  R6D11    2      B  RES         I184
  R6L1     2      B  RES         I64
  R6L7     1      A  RES         I52
  R6L12    2      B  RES         I56
  R6L16    2      B  RES         I12
  R6N4     2      B  RES         I45
  R6N13    1      A  RES         I303
  R6N14    1      A  RES         I302
  R6N15    1      A  RES         I304
  R6P1     2      B  RES         I149
  R6P2     2      B  RES         I151
  R6P3     2      B  RES         I145
  R6P4     2      B  RES         I147
  R6P5     2      B  RES         I141
  R6P6     2      B  RES         I143
  R6P7     2      B  RES         I137
  R6P8     2      B  RES         I139
  R6P9     2      B  RES         I155
  R6P11    2      B  RES         I153
  R6P12    2      B  RES         I159
  R6P13    2      B  RES         I157
  R6P15    2      B  RES         I167
  R6P17    2      B  RES         I165
  R6P20    2      B  RES         I81
  R6P21    2      B  RES         I80
  R6P22    2      B  RES         I47
  R6P23    2      B  RES         I46
  R6P27    2      B  RES         I120
  R6P28    2      B  RES         I121
  R6T5     2      B  RES         I62
  R6U8     1      A  RES         I52
  R6U16    1      A  RES         I55
  R7A8     2      B  RES         I37
  R7A10    2      B  RES         I40
  R7A15    2      B  RES         I218
  R7A16    2      B  RES         I54
  R7A18    1      A  RES         I92
  R7A20    2      B  RES         I108
  R7A21    2      B  RES         I110
  R7B7     2      B  RES         I230
  R7B8     2      B  RES         I229
  R7B10    2      B  RES         I227
  R7B20    1      A  RES         I150
  R7C3     2      B  RES         I78
  R7C11    1      A  RES         I11
  R7C20    2      B  RES         I73
  R7C24    2      B  RES         I155
  R7C25    2      B  RES         I103
  R7D1     2      B  RES         I70
  R7D15    2      B  RES         I32
  R7D19    2      B  RES          I6
  R7D26    2      B  RES         I54
  R7D32    2      B  RES         I48
  R7E13    1      A  RES         I58
  R7E20    2      B  RES         I59
  R7F7     2      B  RES         I174
  R7F10    2      B  RES         I177
  R7F14    2      B  RES         I136
  R7F30    2      B  RES         I170
  R7F35    1      A  RES         I170
  R7G3     2      B  RES         I337
  R7G8     2      B  RES         I321
  R7G10    2      B  RES         I317
  R7G25    2      B  RES         I104
  R7G28    2      B  RES         I102
  R7G29    2      B  RES         I148
  R7G30    2      B  RES         I106
  R7P1     2      B  RES         I133
  R7P2     2      B  RES         I135
  R7P3     2      B  RES         I129
  R7P4     2      B  RES         I131
  R7P6     2      B  RES         I125
  R7P7     2      B  RES         I127
  R7P8     2      B  RES         I123
  R7P9     2      B  RES         I121
  R7P10    2      B  RES         I124
  R7P11    2      B  RES         I126
  R7P12    2      B  RES         I123
  R7P13    1      A  RES         I81
  R7P14    1      A  RES         I70
  R7P15    1      A  RES         I74
  R7P16    2      B  RES         I119
  R7P17    2      B  RES         I140
  R7P19    2      B  RES         I115
  R7P29    2      B  RES         I61
  R7R1     2      B  RES         I109
  R8A2     2      B  RES         I217
  R8A12    2      B  RES         I15
  R8B1     2      B  RES         I95
  R8B2     2      B  RES         I94
  R8B4     2      B  RES         I83
  R8B9     2      B  RES         I90
  R8B12    2      B  RES         I59
  R8B21    2      B  RES         I124
  R8B32    2      B  RES         I114
  R8C17    2      B  RES         I41
  R8C21    2      B  RES         I148
  R8C26    2      B  RES         I35
  R8D5     2      B  RES         I50
  R8D27    2      B  RES         I50
  R8D37    2      B  RES         I115
  R8D40    2      B  RES         I113
  R8E4     2      B  RES         I24
  R8E16    2      B  RES         I140
  R8E18    2      B  RES          I9
  R8F1     2      B  RES         I111
  R8F3     2      B  RES         I148
  R8F11    1      A  RES         I146
  R8F25    2      B  RES         I28
  R8F35    2      B  RES         I24
  R8G23    2      B  RES         I56
  R8P1     2      B  RES         I85
  R8P2     2      B  RES         I86
  R8P3     2      B  RES         I173
  R8R1     2      B  RES         I174
  R9B7     1      A  RES         I222
  R9B8     2      B  RES         I10
  R9B9     2      B  RES         I179
  R9E13    2      B  RES         I212
  R9E23    2      B  RES         I174
  R9F4     2      B  RES         I208
  R9F8     1      A  RES         I14
  R9F20    2      B  RES         I133
  R9F32    1      A  RES         I15
  R9F42    2      B  RES         I214
  R9F43    2      B  RES         I216
  R9F44    2      B  RES         I211
  R9F45    2      B  RES         I210
  R9F46    2      B  RES         I218
  R9F50    2      B  RES         I11
  R9F51    2      B  RES         I12
  R9G5     2      B  RES         I516
  R9G6     2      B  RES         I517
  R9G7     2      B  RES         I78
  R9G8     2      B  RES         I457
  R9G26    2      B  RES         I106
  R9L1     2      B  RES         I40
  R9L6     2      B  RES         I24
  R9L11    2      B  RES          I4
  R9N4     2      B  RES         I45
  R9N7     2      B  RES         I111
  R9N8     2      B  RES         I112
  R9T3     2      B  RES         I185
  R9T8     2      B  RES         I249
  RM1E1    1    IO1  CONN3_G98259001_PIP  I26
  RM1E1    2    IO2  CONN3_G98259001_PIP  I26
  RM1E1    3    IO3  CONN3_G98259001_PIP  I26
  RM8D1    1    IO1  STANDOFF_TH1  I104
  RTI2     1      1  3D01R5F-GP_SMD-RG5  I75
  RTI4     1      1  3D01R5F-GP_SMD-RG5  I83
  RTI6     2      2  3D01R5F-GP_SMD-RG5  I125
  RTI7     2      2  3D01R5F-GP_SMD-RG5  I124
  RTI10    1      1  3D01R5F-GP_SMD-RG5  I66
  RTI12    1      1  3D01R5F-GP_SMD-RG5  I86
  RTI13    1      1  3D01R5F-GP_SMD-RG5  I94
  RTI16    1      1  3D01R5F-GP_SMD-RG5  I76
  RTI18    1      1  3D01R5F-GP_SMD-RG5  I85
  RTI20    1      1  3D01R5F-GP_SMD-RG5  I119
  RTI22    1      1  3D01R5F-GP_SMD-RG5  I129
  RTI24    1      1  3D01R5F-GP_SMD-RG5  I91
  RTI26    1      1  3D01R5F-GP_SMD-RG5  I102
  RTI27    1      1  3D01R5F-GP_SMD-RG5  I105
  RTI29    1      1  3D01R5F-GP_SMD-RG5  I126
  RTI32    1      1  3D01R5F-GP_SMD-RG5  I123
  RTI34    1      1  3D01R5F-GP_SMD-RG5  I114
  RTI35    1      1  3D01R5F-GP_SMD-RG5  I123
  RTI38    1      1  3D01R5F-GP_SMD-RG5  I59
  RTI39    1      1  3D01R5F-GP_SMD-RG5  I68
  RTI42    1      1  3D01R5F-GP_SMD-RG5  I132
  RTI43    1      1  3D01R5F-GP_SMD-RG5  I132
  RTI45    1      1  3D01R5F-GP_SMD-RG5  I137
  RTI48    1      1  3D01R5F-GP_SMD-RG5  I112
  S8E1     1      A  SWITCH_D90553001_SMLF  I351
  S9A1     3   PIN3  SWITCH_D37771002_SM  I78
  S9A1     4   PIN4  SWITCH_D37771002_SM  I78
  S9A2     3    IO3  SW_H67881001_SM  I84
  S9A2     4    IO4  SW_H67881001_SM  I84
  SH4L1    2      B  SHUNT       I240
  SH4U1    2      B  SHUNT       I259
  SH7L1    2      B  SHUNT       I246
  SH7U2    2      B  SHUNT       I244
  TC1A1    1    GND  RCC_DFX1940   I7
  TC1G1    1    GND  RCC_DFX1940   I3
  TC9A1    1    GND  RCC_DFX1940   I9
  TC9F1    1    GND  RCC_DFX1940   I1
  TH1A1    1      1  MTG_KEYHOLE_TH  I56
  TH4A1    1      1  MTG_KEYHOLE_TH  I62
  TH4G1    1      1  MTG_KEYHOLE_TH  I49
  TH7A1    1      1  MTG_KEYHOLE_TH  I65
  TH7G1    1      1  MTG_KEYHOLE_TH  I67
  TH9A1    1      1  MTG_KEYHOLE_TH  I54
  TH9G1    1      1  MTG_KEYHOLE_TH  I52
  U1B1     1  GND<1>  MAX9634_SOT  I144
  U1B1     2  GND<0>  MAX9634_SOT  I144
  U1B3     1  GND<0>  ADM4073_SM  I52
  U1B3     2  GND<1>  ADM4073_SM  I52
  U1D2     5    GND  TPS3700_SM  I170
  U1E1     5    GND  TMP421_TSSOP  I30
  U1F1     1  GND<1>  MAX9634_SOT  I133
  U1F1     2  GND<0>  MAX9634_SOT  I133
  U1M2     2    GND  NC7SB3157   I107
  U1M3     2    GND  TPS2061_SM  I100
  U1M7     2    GND  NC7SB3157   I40
  U2D1   A26  VSS<1185>  SKX_EXT_B_BGA1  I20
  U2D1   A30  VSS<1184>  SKX_EXT_B_BGA1  I20
  U2D1   A32  VSS<1183>  SKX_EXT_B_BGA1  I20
  U2D1   A36  VSS<1182>  SKX_EXT_B_BGA1  I20
  U2D1   A38  VSS<1181>  SKX_EXT_B_BGA1  I20
  U2D1   A42  VSS<1252>  SKX_EXT_B_BGA1  I20
  U2D1   AA4  VSS<935>  SKX_EXT_B_BGA1  I21
  U2D1   AA16  VSS<934>  SKX_EXT_B_BGA1  I21
  U2D1   AA18  VSS<933>  SKX_EXT_B_BGA1  I22
  U2D1   AA22  VSS<932>  SKX_EXT_B_BGA1  I22
  U2D1   AA24  VSS<931>  SKX_EXT_B_BGA1  I22
  U2D1   AA30  VSS<930>  SKX_EXT_B_BGA1  I22
  U2D1   AA36  VSS<929>  SKX_EXT_B_BGA1  I22
  U2D1   AA42  VSS<928>  SKX_EXT_B_BGA1  I22
  U2D1   AA64  VSS<927>  SKX_EXT_B_BGA1  I22
  U2D1   AA66  VSS<926>  SKX_EXT_B_BGA1  I22
  U2D1   AA68  VSS<925>  SKX_EXT_B_BGA1  I22
  U2D1   AA76  VSS<924>  SKX_EXT_B_BGA1  I22
  U2D1   AA78  VSS<923>  SKX_EXT_B_BGA1  I22
  U2D1   AA80  VSS<922>  SKX_EXT_B_BGA1  I22
  U2D1   AA82  VSS<921>  SKX_EXT_B_BGA1  I22
  U2D1   AB1  VSS<920>  SKX_EXT_B_BGA1  I22
  U2D1   AB5  VSS<919>  SKX_EXT_B_BGA1  I22
  U2D1   AB11  VSS<918>  SKX_EXT_B_BGA1  I22
  U2D1   AB21  VSS<917>  SKX_EXT_B_BGA1  I22
  U2D1   AB23  VSS<916>  SKX_EXT_B_BGA1  I22
  U2D1   AB25  VSS<915>  SKX_EXT_B_BGA1  I22
  U2D1   AB29  VSS<914>  SKX_EXT_B_BGA1  I22
  U2D1   AB31  VSS<913>  SKX_EXT_B_BGA1  I22
  U2D1   AB35  VSS<912>  SKX_EXT_B_BGA1  I22
  U2D1   AB37  VSS<911>  SKX_EXT_B_BGA1  I22
  U2D1   AB41  VSS<910>  SKX_EXT_B_BGA1  I22
  U2D1   AB65  VSS<909>  SKX_EXT_B_BGA1  I22
  U2D1   AB69  VSS<908>  SKX_EXT_B_BGA1  I22
  U2D1   AB73  VSS<907>  SKX_EXT_B_BGA1  I22
  U2D1   AB79  VSS<906>  SKX_EXT_B_BGA1  I22
  U2D1   AB83  VSS<905>  SKX_EXT_B_BGA1  I22
  U2D1   AB85  VSS<904>  SKX_EXT_B_BGA1  I22
  U2D1   AC18  VSS<903>  SKX_EXT_B_BGA1  I22
  U2D1   AC22  VSS<902>  SKX_EXT_B_BGA1  I22
  U2D1   AC26  VSS<901>  SKX_EXT_B_BGA1  I22
  U2D1   AC28  VSS<900>  SKX_EXT_B_BGA1  I22
  U2D1   AC32  VSS<899>  SKX_EXT_B_BGA1  I22
  U2D1   AC34  VSS<898>  SKX_EXT_B_BGA1  I22
  U2D1   AC38  VSS<897>  SKX_EXT_B_BGA1  I22
  U2D1   AC40  VSS<896>  SKX_EXT_B_BGA1  I22
  U2D1   AC48  VSS<733>  SKX_EXT_B_BGA1  I23
  U2D1   AC50  VSS<767>  SKX_EXT_B_BGA1  I23
  U2D1   AC52  VSS<858>  SKX_EXT_B_BGA1  I22
  U2D1   AC54  VSS<869>  SKX_EXT_B_BGA1  I22
  U2D1   AC56  VSS<964>  SKX_EXT_B_BGA1  I21
  U2D1   AC58  VSS<1186>  SKX_EXT_B_BGA1  I20
  U2D1   AC60  VSS<1187>  SKX_EXT_B_BGA1  I20
  U2D1   AC62  VSS<1188>  SKX_EXT_B_BGA1  I20
  U2D1   AC64  VSS<895>  SKX_EXT_B_BGA1  I22
  U2D1   AC70  VSS<894>  SKX_EXT_B_BGA1  I22
  U2D1   AC72  VSS<893>  SKX_EXT_B_BGA1  I22
  U2D1   AC78  VSS<892>  SKX_EXT_B_BGA1  I22
  U2D1   AC84  VSS<891>  SKX_EXT_B_BGA1  I22
  U2D1   AC86  VSS<890>  SKX_EXT_B_BGA1  I22
  U2D1   AD3  VSS<889>  SKX_EXT_B_BGA1  I22
  U2D1   AD7  VSS<888>  SKX_EXT_B_BGA1  I22
  U2D1   AD9  VSS<887>  SKX_EXT_B_BGA1  I22
  U2D1   AD11  VSS<886>  SKX_EXT_B_BGA1  I22
  U2D1   AD13  VSS<885>  SKX_EXT_B_BGA1  I22
  U2D1   AD15  VSS<884>  SKX_EXT_B_BGA1  I22
  U2D1   AD19  VSS<883>  SKX_EXT_B_BGA1  I22
  U2D1   AD21  VSS<882>  SKX_EXT_B_BGA1  I22
  U2D1   AD27  VSS<881>  SKX_EXT_B_BGA1  I22
  U2D1   AD33  VSS<880>  SKX_EXT_B_BGA1  I22
  U2D1   AD39  VSS<879>  SKX_EXT_B_BGA1  I22
  U2D1   AD43  VSS<878>  SKX_EXT_B_BGA1  I22
  U2D1   AD71  VSS<877>  SKX_EXT_B_BGA1  I22
  U2D1   AD73  VSS<876>  SKX_EXT_B_BGA1  I22
  U2D1   AD75  VSS<875>  SKX_EXT_B_BGA1  I22
  U2D1   AD81  VSS<874>  SKX_EXT_B_BGA1  I22
  U2D1   AD83  VSS<873>  SKX_EXT_B_BGA1  I22
  U2D1   AD85  VSS<872>  SKX_EXT_B_BGA1  I22
  U2D1   AE4  VSS<871>  SKX_EXT_B_BGA1  I22
  U2D1   AE8  VSS<870>  SKX_EXT_B_BGA1  I22
  U2D1   AE16  VSS<868>  SKX_EXT_B_BGA1  I22
  U2D1   AE38  VSS<867>  SKX_EXT_B_BGA1  I22
  U2D1   AE40  VSS<866>  SKX_EXT_B_BGA1  I22
  U2D1   AE42  VSS<865>  SKX_EXT_B_BGA1  I22
  U2D1   AE64  VSS<864>  SKX_EXT_B_BGA1  I22
  U2D1   AE66  VSS<863>  SKX_EXT_B_BGA1  I22
  U2D1   AE68  VSS<862>  SKX_EXT_B_BGA1  I22
  U2D1   AE70  VSS<861>  SKX_EXT_B_BGA1  I22
  U2D1   AE78  VSS<860>  SKX_EXT_B_BGA1  I22
  U2D1   AF1  VSS<859>  SKX_EXT_B_BGA1  I22
  U2D1   AF9  VSS<857>  SKX_EXT_B_BGA1  I22
  U2D1   AF21  VSS<856>  SKX_EXT_B_BGA1  I22
  U2D1   AF23  VSS<855>  SKX_EXT_B_BGA1  I22
  U2D1   AF25  VSS<854>  SKX_EXT_B_BGA1  I22
  U2D1   AF27  VSS<853>  SKX_EXT_B_BGA1  I22
  U2D1   AF29  VSS<852>  SKX_EXT_B_BGA1  I22
  U2D1   AF31  VSS<851>  SKX_EXT_B_BGA1  I22
  U2D1   AF33  VSS<850>  SKX_EXT_B_BGA1  I22
  U2D1   AF37  VSS<849>  SKX_EXT_B_BGA1  I22
  U2D1   AF39  VSS<848>  SKX_EXT_B_BGA1  I22
  U2D1   AF41  VSS<847>  SKX_EXT_B_BGA1  I22
  U2D1   AF73  VSS<846>  SKX_EXT_B_BGA1  I22
  U2D1   AF77  VSS<845>  SKX_EXT_B_BGA1  I22
  U2D1   AF83  VSS<844>  SKX_EXT_B_BGA1  I22
  U2D1   AF85  VSS<843>  SKX_EXT_B_BGA1  I22
  U2D1   AG12  VSS<842>  SKX_EXT_B_BGA1  I22
  U2D1   AG14  VSS<841>  SKX_EXT_B_BGA1  I22
  U2D1   AG18  VSS<840>  SKX_EXT_B_BGA1  I22
  U2D1   AG36  VSS<839>  SKX_EXT_B_BGA1  I22
  U2D1   AG64  VSS<838>  SKX_EXT_B_BGA1  I22
  U2D1   AG70  VSS<837>  SKX_EXT_B_BGA1  I22
  U2D1   AG74  VSS<836>  SKX_EXT_B_BGA1  I22
  U2D1   AG76  VSS<835>  SKX_EXT_B_BGA1  I22
  U2D1   AG78  VSS<834>  SKX_EXT_B_BGA1  I22
  U2D1   AG80  VSS<833>  SKX_EXT_B_BGA1  I22
  U2D1   AH1  VSS<832>  SKX_EXT_B_BGA1  I22
  U2D1   AH5  VSS<831>  SKX_EXT_B_BGA1  I22
  U2D1   AH21  VSS<830>  SKX_EXT_B_BGA1  I22
  U2D1   AH27  VSS<829>  SKX_EXT_B_BGA1  I22
  U2D1   AH33  VSS<828>  SKX_EXT_B_BGA1  I22
  U2D1   AH35  VSS<827>  SKX_EXT_B_BGA1  I22
  U2D1   AH45  VSS<826>  SKX_EXT_B_BGA1  I22
  U2D1   AH47  VSS<825>  SKX_EXT_B_BGA1  I22
  U2D1   AH49  VSS<824>  SKX_EXT_B_BGA1  I22
  U2D1   AH51  VSS<823>  SKX_EXT_B_BGA1  I22
  U2D1   AH53  VSS<822>  SKX_EXT_B_BGA1  I22
  U2D1   AH59  VSS<821>  SKX_EXT_B_BGA1  I22
  U2D1   AH61  VSS<820>  SKX_EXT_B_BGA1  I22
  U2D1   AH65  VSS<819>  SKX_EXT_B_BGA1  I22
  U2D1   AH69  VSS<818>  SKX_EXT_B_BGA1  I22
  U2D1   AH75  VSS<817>  SKX_EXT_B_BGA1  I22
  U2D1   AH77  VSS<816>  SKX_EXT_B_BGA1  I22
  U2D1   AH83  VSS<815>  SKX_EXT_B_BGA1  I22
  U2D1   AJ4  VSS<1189>  SKX_EXT_B_BGA1  I20
  U2D1   AJ8  VSS<814>  SKX_EXT_B_BGA1  I22
  U2D1   AJ22  VSS<813>  SKX_EXT_B_BGA1  I22
  U2D1   AJ26  VSS<812>  SKX_EXT_B_BGA1  I22
  U2D1   AJ28  VSS<811>  SKX_EXT_B_BGA1  I22
  U2D1   AJ32  VSS<810>  SKX_EXT_B_BGA1  I22
  U2D1   AJ34  VSS<809>  SKX_EXT_B_BGA1  I22
  U2D1   AJ46  VSS<808>  SKX_EXT_B_BGA1  I22
  U2D1   AJ48  VSS<807>  SKX_EXT_B_BGA1  I22
  U2D1   AJ50  VSS<806>  SKX_EXT_B_BGA1  I22
  U2D1   AJ52  VSS<805>  SKX_EXT_B_BGA1  I22
  U2D1   AJ54  VSS<804>  SKX_EXT_B_BGA1  I22
  U2D1   AJ66  VSS<803>  SKX_EXT_B_BGA1  I22
  U2D1   AJ68  VSS<802>  SKX_EXT_B_BGA1  I22
  U2D1   AJ74  VSS<801>  SKX_EXT_B_BGA1  I22
  U2D1   AJ78  VSS<800>  SKX_EXT_B_BGA1  I22
  U2D1   AJ82  VSS<799>  SKX_EXT_B_BGA1  I22
  U2D1   AJ86  VSS<798>  SKX_EXT_B_BGA1  I22
  U2D1   AK9  VSS<797>  SKX_EXT_B_BGA1  I22
  U2D1   AK13  VSS<796>  SKX_EXT_B_BGA1  I22
  U2D1   AK19  VSS<795>  SKX_EXT_B_BGA1  I22
  U2D1   AK23  VSS<794>  SKX_EXT_B_BGA1  I22
  U2D1   AK25  VSS<793>  SKX_EXT_B_BGA1  I22
  U2D1   AK29  VSS<792>  SKX_EXT_B_BGA1  I22
  U2D1   AK31  VSS<791>  SKX_EXT_B_BGA1  I22
  U2D1   AK33  VSS<790>  SKX_EXT_B_BGA1  I22
  U2D1   AK55  VSS<789>  SKX_EXT_B_BGA1  I22
  U2D1   AK65  VSS<788>  SKX_EXT_B_BGA1  I22
  U2D1   AK67  VSS<787>  SKX_EXT_B_BGA1  I22
  U2D1   AK73  VSS<786>  SKX_EXT_B_BGA1  I22
  U2D1   AK79  VSS<785>  SKX_EXT_B_BGA1  I22
  U2D1   AK81  VSS<784>  SKX_EXT_B_BGA1  I22
  U2D1   AK83  VSS<783>  SKX_EXT_B_BGA1  I22
  U2D1   AK85  VSS<782>  SKX_EXT_B_BGA1  I22
  U2D1   AL4  VSS<781>  SKX_EXT_B_BGA1  I22
  U2D1   AL10  VSS<780>  SKX_EXT_B_BGA1  I22
  U2D1   AL24  VSS<779>  SKX_EXT_B_BGA1  I22
  U2D1   AL30  VSS<778>  SKX_EXT_B_BGA1  I22
  U2D1   AL32  VSS<777>  SKX_EXT_B_BGA1  I22
  U2D1   AL56  VSS<776>  SKX_EXT_B_BGA1  I22
  U2D1   AL64  VSS<775>  SKX_EXT_B_BGA1  I22
  U2D1   AL68  VSS<774>  SKX_EXT_B_BGA1  I22
  U2D1   AL76  VSS<773>  SKX_EXT_B_BGA1  I23
  U2D1   AL78  VSS<772>  SKX_EXT_B_BGA1  I23
  U2D1   AL80  VSS<771>  SKX_EXT_B_BGA1  I23
  U2D1   AL82  VSS<770>  SKX_EXT_B_BGA1  I23
  U2D1   AL86  VSS<769>  SKX_EXT_B_BGA1  I23
  U2D1   AM1  VSS<768>  SKX_EXT_B_BGA1  I23
  U2D1   AM31  VSS<766>  SKX_EXT_B_BGA1  I23
  U2D1   AM57  VSS<765>  SKX_EXT_B_BGA1  I23
  U2D1   AM63  VSS<764>  SKX_EXT_B_BGA1  I23
  U2D1   AM69  VSS<763>  SKX_EXT_B_BGA1  I23
  U2D1   AM73  VSS<762>  SKX_EXT_B_BGA1  I23
  U2D1   AM79  VSS<761>  SKX_EXT_B_BGA1  I23
  U2D1   AM83  VSS<760>  SKX_EXT_B_BGA1  I23
  U2D1   AN2  VSS<759>  SKX_EXT_B_BGA1  I23
  U2D1   AN6  VSS<758>  SKX_EXT_B_BGA1  I23
  U2D1   AN28  VSS<757>  SKX_EXT_B_BGA1  I23
  U2D1   AN58  VSS<756>  SKX_EXT_B_BGA1  I23
  U2D1   AN78  VSS<755>  SKX_EXT_B_BGA1  I23
  U2D1   AP5  VSS<754>  SKX_EXT_B_BGA1  I23
  U2D1   AP9  VSS<753>  SKX_EXT_B_BGA1  I23
  U2D1   AP13  VSS<752>  SKX_EXT_B_BGA1  I23
  U2D1   AP19  VSS<751>  SKX_EXT_B_BGA1  I23
  U2D1   AP31  VSS<750>  SKX_EXT_B_BGA1  I23
  U2D1   AP59  VSS<749>  SKX_EXT_B_BGA1  I23
  U2D1   AP63  VSS<748>  SKX_EXT_B_BGA1  I23
  U2D1   AP65  VSS<747>  SKX_EXT_B_BGA1  I23
  U2D1   AP67  VSS<746>  SKX_EXT_B_BGA1  I23
  U2D1   AP69  VSS<745>  SKX_EXT_B_BGA1  I23
  U2D1   AP73  VSS<744>  SKX_EXT_B_BGA1  I23
  U2D1   AP75  VSS<743>  SKX_EXT_B_BGA1  I23
  U2D1   AP81  VSS<742>  SKX_EXT_B_BGA1  I23
  U2D1   AP83  VSS<741>  SKX_EXT_B_BGA1  I23
  U2D1   AP85  VSS<740>  SKX_EXT_B_BGA1  I23
  U2D1   AR6  VSS<1190>  SKX_EXT_B_BGA1  I20
  U2D1   AR10  VSS<739>  SKX_EXT_B_BGA1  I23
  U2D1   AR24  VSS<738>  SKX_EXT_B_BGA1  I23
  U2D1   AR30  VSS<737>  SKX_EXT_B_BGA1  I23
  U2D1   AR60  VSS<736>  SKX_EXT_B_BGA1  I23
  U2D1   AR72  VSS<735>  SKX_EXT_B_BGA1  I23
  U2D1   AR78  VSS<734>  SKX_EXT_B_BGA1  I23
  U2D1   AT15  VSS<731>  SKX_EXT_B_BGA1  I23
  U2D1   AT17  VSS<730>  SKX_EXT_B_BGA1  I23
  U2D1   AT21  VSS<729>  SKX_EXT_B_BGA1  I23
  U2D1   AT27  VSS<728>  SKX_EXT_B_BGA1  I23
  U2D1   AT61  VSS<727>  SKX_EXT_B_BGA1  I23
  U2D1   AT63  VSS<726>  SKX_EXT_B_BGA1  I23
  U2D1   AT69  VSS<725>  SKX_EXT_B_BGA1  I23
  U2D1   AT73  VSS<724>  SKX_EXT_B_BGA1  I23
  U2D1   AT77  VSS<723>  SKX_EXT_B_BGA1  I23
  U2D1   AT83  VSS<722>  SKX_EXT_B_BGA1  I23
  U2D1   AT85  VSS<721>  SKX_EXT_B_BGA1  I23
  U2D1   AU2  VSS<720>  SKX_EXT_B_BGA1  I23
  U2D1   AU6  VSS<719>  SKX_EXT_B_BGA1  I23
  U2D1   AU26  VSS<718>  SKX_EXT_B_BGA1  I23
  U2D1   AU28  VSS<717>  SKX_EXT_B_BGA1  I23
  U2D1   AU62  VSS<716>  SKX_EXT_B_BGA1  I23
  U2D1   AU64  VSS<715>  SKX_EXT_B_BGA1  I23
  U2D1   AU68  VSS<714>  SKX_EXT_B_BGA1  I23
  U2D1   AU74  VSS<713>  SKX_EXT_B_BGA1  I23
  U2D1   AU76  VSS<712>  SKX_EXT_B_BGA1  I23
  U2D1   AU78  VSS<711>  SKX_EXT_B_BGA1  I23
  U2D1   AU80  VSS<710>  SKX_EXT_B_BGA1  I23
  U2D1   AU84  VSS<709>  SKX_EXT_B_BGA1  I23
  U2D1   AU86  VSS<708>  SKX_EXT_B_BGA1  I23
  U2D1   AV1  VSS<707>  SKX_EXT_B_BGA1  I23
  U2D1   AV3  VSS<706>  SKX_EXT_B_BGA1  I23
  U2D1   AV7  VSS<705>  SKX_EXT_B_BGA1  I23
  U2D1   AV11  VSS<704>  SKX_EXT_B_BGA1  I23
  U2D1   AV13  VSS<703>  SKX_EXT_B_BGA1  I23
  U2D1   AV19  VSS<702>  SKX_EXT_B_BGA1  I23
  U2D1   AV23  VSS<701>  SKX_EXT_B_BGA1  I23
  U2D1   AV25  VSS<700>  SKX_EXT_B_BGA1  I23
  U2D1   AV63  VSS<699>  SKX_EXT_B_BGA1  I23
  U2D1   AV65  VSS<698>  SKX_EXT_B_BGA1  I23
  U2D1   AV67  VSS<697>  SKX_EXT_B_BGA1  I23
  U2D1   AV75  VSS<696>  SKX_EXT_B_BGA1  I23
  U2D1   AV83  VSS<695>  SKX_EXT_B_BGA1  I23
  U2D1   AW2  VSS<694>  SKX_EXT_B_BGA1  I23
  U2D1   AW10  VSS<693>  SKX_EXT_B_BGA1  I23
  U2D1   AW62  VSS<692>  SKX_EXT_B_BGA1  I23
  U2D1   AW66  VSS<691>  SKX_EXT_B_BGA1  I23
  U2D1   AW68  VSS<690>  SKX_EXT_B_BGA1  I23
  U2D1   AW70  VSS<689>  SKX_EXT_B_BGA1  I23
  U2D1   AW72  VSS<688>  SKX_EXT_B_BGA1  I23
  U2D1   AW74  VSS<687>  SKX_EXT_B_BGA1  I23
  U2D1   AW78  VSS<686>  SKX_EXT_B_BGA1  I23
  U2D1   AW82  VSS<685>  SKX_EXT_B_BGA1  I23
  U2D1   AW84  VSS<684>  SKX_EXT_B_BGA1  I23
  U2D1   AY5  VSS<683>  SKX_EXT_B_BGA1  I23
  U2D1   AY15  VSS<682>  SKX_EXT_B_BGA1  I23
  U2D1   AY17  VSS<681>  SKX_EXT_B_BGA1  I23
  U2D1   AY21  VSS<680>  SKX_EXT_B_BGA1  I23
  U2D1   AY23  VSS<679>  SKX_EXT_B_BGA1  I23
  U2D1   AY25  VSS<678>  SKX_EXT_B_BGA1  I23
  U2D1   AY63  VSS<677>  SKX_EXT_B_BGA1  I23
  U2D1   AY79  VSS<676>  SKX_EXT_B_BGA1  I23
  U2D1   AY81  VSS<675>  SKX_EXT_B_BGA1  I23
  U2D1    B5  VSS<1250>  SKX_EXT_B_BGA1  I20
  U2D1    B9  VSS<1253>  SKX_EXT_B_BGA1  I20
  U2D1   B25  VSS<1180>  SKX_EXT_B_BGA1  I20
  U2D1   B31  VSS<1179>  SKX_EXT_B_BGA1  I20
  U2D1   B37  VSS<1178>  SKX_EXT_B_BGA1  I20
  U2D1   B43  VSS<1251>  SKX_EXT_B_BGA1  I20
  U2D1   B71  VSS<1177>  SKX_EXT_B_BGA1  I20
  U2D1   B75  VSS<1176>  SKX_EXT_B_BGA1  I20
  U2D1   B79  VSS<1249>  SKX_EXT_B_BGA1  I20
  U2D1   BA2  VSS<674>  SKX_EXT_B_BGA1  I23
  U2D1   BA6  VSS<673>  SKX_EXT_B_BGA1  I23
  U2D1   BA12  VSS<672>  SKX_EXT_B_BGA1  I23
  U2D1   BA62  VSS<671>  SKX_EXT_B_BGA1  I23
  U2D1   BA68  VSS<670>  SKX_EXT_B_BGA1  I23
  U2D1   BA74  VSS<669>  SKX_EXT_B_BGA1  I23
  U2D1   BA80  VSS<668>  SKX_EXT_B_BGA1  I23
  U2D1   BA84  VSS<667>  SKX_EXT_B_BGA1  I23
  U2D1   BB19  VSS<666>  SKX_EXT_B_BGA1  I23
  U2D1   BB23  VSS<665>  SKX_EXT_B_BGA1  I23
  U2D1   BB63  VSS<664>  SKX_EXT_B_BGA1  I23
  U2D1   BB69  VSS<663>  SKX_EXT_B_BGA1  I23
  U2D1   BB73  VSS<662>  SKX_EXT_B_BGA1  I23
  U2D1   BB75  VSS<661>  SKX_EXT_B_BGA1  I23
  U2D1   BB77  VSS<660>  SKX_EXT_B_BGA1  I23
  U2D1   BB79  VSS<659>  SKX_EXT_B_BGA1  I23
  U2D1   BB81  VSS<658>  SKX_EXT_B_BGA1  I23
  U2D1   BB83  VSS<657>  SKX_EXT_B_BGA1  I23
  U2D1   BC4  VSS<656>  SKX_EXT_B_BGA1  I23
  U2D1   BC8  VSS<655>  SKX_EXT_B_BGA1  I23
  U2D1   BC12  VSS<654>  SKX_EXT_B_BGA1  I23
  U2D1   BC16  VSS<653>  SKX_EXT_B_BGA1  I23
  U2D1   BC70  VSS<652>  SKX_EXT_B_BGA1  I23
  U2D1   BC72  VSS<651>  SKX_EXT_B_BGA1  I23
  U2D1   BC74  VSS<650>  SKX_EXT_B_BGA1  I23
  U2D1   BC76  VSS<649>  SKX_EXT_B_BGA1  I23
  U2D1   BC78  VSS<648>  SKX_EXT_B_BGA1  I23
  U2D1   BC80  VSS<647>  SKX_EXT_B_BGA1  I23
  U2D1   BC82  VSS<646>  SKX_EXT_B_BGA1  I23
  U2D1   BD5  VSS<645>  SKX_EXT_B_BGA1  I23
  U2D1   BD11  VSS<644>  SKX_EXT_B_BGA1  I23
  U2D1   BD15  VSS<643>  SKX_EXT_B_BGA1  I23
  U2D1   BD21  VSS<642>  SKX_EXT_B_BGA1  I23
  U2D1   BD27  VSS<641>  SKX_EXT_B_BGA1  I23
  U2D1   BD63  VSS<640>  SKX_EXT_B_BGA1  I23
  U2D1   BD71  VSS<639>  SKX_EXT_B_BGA1  I23
  U2D1   BE4  VSS<638>  SKX_EXT_B_BGA1  I23
  U2D1   BE6  VSS<637>  SKX_EXT_B_BGA1  I23
  U2D1   BE8  VSS<636>  SKX_EXT_B_BGA1  I23
  U2D1   BE10  VSS<635>  SKX_EXT_B_BGA1  I23
  U2D1   BE26  VSS<634>  SKX_EXT_B_BGA1  I23
  U2D1   BE64  VSS<633>  SKX_EXT_B_BGA1  I23
  U2D1   BE66  VSS<632>  SKX_EXT_B_BGA1  I23
  U2D1   BE68  VSS<631>  SKX_EXT_B_BGA1  I23
  U2D1   BE70  VSS<630>  SKX_EXT_B_BGA1  I23
  U2D1   BF9  VSS<629>  SKX_EXT_B_BGA1  I23
  U2D1   BF15  VSS<628>  SKX_EXT_B_BGA1  I23
  U2D1   BF17  VSS<627>  SKX_EXT_B_BGA1  I23
  U2D1   BF19  VSS<626>  SKX_EXT_B_BGA1  I23
  U2D1   BF25  VSS<625>  SKX_EXT_B_BGA1  I23
  U2D1   BF63  VSS<624>  SKX_EXT_B_BGA1  I23
  U2D1   BF65  VSS<623>  SKX_EXT_B_BGA1  I23
  U2D1   BF67  VSS<622>  SKX_EXT_B_BGA1  I23
  U2D1   BF69  VSS<621>  SKX_EXT_B_BGA1  I23
  U2D1   BF71  VSS<620>  SKX_EXT_B_BGA1  I23
  U2D1   BG6  VSS<619>  SKX_EXT_B_BGA1  I23
  U2D1   BG8  VSS<618>  SKX_EXT_B_BGA1  I23
  U2D1   BG10  VSS<617>  SKX_EXT_B_BGA1  I23
  U2D1   BG22  VSS<616>  SKX_EXT_B_BGA1  I23
  U2D1   BG24  VSS<615>  SKX_EXT_B_BGA1  I23
  U2D1   BG72  VSS<614>  SKX_EXT_B_BGA1  I23
  U2D1   BG74  VSS<613>  SKX_EXT_B_BGA1  I17
  U2D1   BG76  VSS<612>  SKX_EXT_B_BGA1  I17
  U2D1   BG78  VSS<611>  SKX_EXT_B_BGA1  I17
  U2D1   BG80  VSS<610>  SKX_EXT_B_BGA1  I17
  U2D1   BG82  VSS<609>  SKX_EXT_B_BGA1  I17
  U2D1   BH7  VSS<608>  SKX_EXT_B_BGA1  I17
  U2D1   BH9  VSS<607>  SKX_EXT_B_BGA1  I17
  U2D1   BH11  VSS<606>  SKX_EXT_B_BGA1  I17
  U2D1   BH15  VSS<605>  SKX_EXT_B_BGA1  I17
  U2D1   BH17  VSS<141>  SKX_EXT_B_BGA1  I19
  U2D1   BH21  VSS<604>  SKX_EXT_B_BGA1  I17
  U2D1   BJ4  VSS<603>  SKX_EXT_B_BGA1  I17
  U2D1   BJ6  VSS<602>  SKX_EXT_B_BGA1  I17
  U2D1   BK3  VSS<601>  SKX_EXT_B_BGA1  I17
  U2D1   BK7  VSS<600>  SKX_EXT_B_BGA1  I17
  U2D1   BK11  VSS<599>  SKX_EXT_B_BGA1  I17
  U2D1   BK19  VSS<598>  SKX_EXT_B_BGA1  I17
  U2D1   BL6  VSS<597>  SKX_EXT_B_BGA1  I17
  U2D1   BL10  VSS<596>  SKX_EXT_B_BGA1  I17
  U2D1   BL12  VSS<595>  SKX_EXT_B_BGA1  I17
  U2D1   BL22  VSS<593>  SKX_EXT_B_BGA1  I17
  U2D1   BL24  VSS<592>  SKX_EXT_B_BGA1  I17
  U2D1   BL64  VSS<591>  SKX_EXT_B_BGA1  I17
  U2D1   BL66  VSS<590>  SKX_EXT_B_BGA1  I17
  U2D1   BL68  VSS<589>  SKX_EXT_B_BGA1  I17
  U2D1   BL70  VSS<588>  SKX_EXT_B_BGA1  I17
  U2D1   BL72  VSS<587>  SKX_EXT_B_BGA1  I17
  U2D1   BL74  VSS<586>  SKX_EXT_B_BGA1  I17
  U2D1   BL76  VSS<585>  SKX_EXT_B_BGA1  I17
  U2D1   BL78  VSS<584>  SKX_EXT_B_BGA1  I17
  U2D1   BL80  VSS<583>  SKX_EXT_B_BGA1  I17
  U2D1   BL82  VSS<582>  SKX_EXT_B_BGA1  I17
  U2D1   BM9  VSS<581>  SKX_EXT_B_BGA1  I17
  U2D1   BM13  VSS<580>  SKX_EXT_B_BGA1  I17
  U2D1   BM15  VSS<579>  SKX_EXT_B_BGA1  I17
  U2D1   BM25  VSS<577>  SKX_EXT_B_BGA1  I17
  U2D1   BN6  VSS<576>  SKX_EXT_B_BGA1  I17
  U2D1   BN10  VSS<575>  SKX_EXT_B_BGA1  I17
  U2D1   BN20  VSS<574>  SKX_EXT_B_BGA1  I17
  U2D1   BN26  VSS<573>  SKX_EXT_B_BGA1  I17
  U2D1   BP3  VSS<572>  SKX_EXT_B_BGA1  I17
  U2D1   BP27  VSS<571>  SKX_EXT_B_BGA1  I17
  U2D1   BR6  VSS<570>  SKX_EXT_B_BGA1  I17
  U2D1   BR10  VSS<569>  SKX_EXT_B_BGA1  I17
  U2D1   BR16  VSS<568>  SKX_EXT_B_BGA1  I17
  U2D1   BR18  VSS<34>  SKX_EXT_B_BGA1  I20
  U2D1   BR26  VSS<127>  SKX_EXT_B_BGA1  I20
  U2D1   BR64  VSS<566>  SKX_EXT_B_BGA1  I17
  U2D1   BR66  VSS<565>  SKX_EXT_B_BGA1  I17
  U2D1   BR68  VSS<564>  SKX_EXT_B_BGA1  I17
  U2D1   BR70  VSS<563>  SKX_EXT_B_BGA1  I17
  U2D1   BR72  VSS<562>  SKX_EXT_B_BGA1  I17
  U2D1   BR74  VSS<561>  SKX_EXT_B_BGA1  I17
  U2D1   BR76  VSS<560>  SKX_EXT_B_BGA1  I17
  U2D1   BR78  VSS<559>  SKX_EXT_B_BGA1  I17
  U2D1   BR80  VSS<558>  SKX_EXT_B_BGA1  I17
  U2D1   BR82  VSS<557>  SKX_EXT_B_BGA1  I17
  U2D1   BT3  VSS<556>  SKX_EXT_B_BGA1  I17
  U2D1   BT5  VSS<555>  SKX_EXT_B_BGA1  I17
  U2D1   BT9  VSS<1064>  SKX_EXT_B_BGA1  I21
  U2D1   BT21  VSS<554>  SKX_EXT_B_BGA1  I17
  U2D1   BT23  VSS<553>  SKX_EXT_B_BGA1  I17
  U2D1   BT25  VSS<552>  SKX_EXT_B_BGA1  I17
  U2D1   BU8  VSS<551>  SKX_EXT_B_BGA1  I17
  U2D1   BU10  VSS<549>  SKX_EXT_B_BGA1  I17
  U2D1   BV5  VSS<550>  SKX_EXT_B_BGA1  I17
  U2D1   BV17  VSS<548>  SKX_EXT_B_BGA1  I17
  U2D1   BV25  VSS<547>  SKX_EXT_B_BGA1  I17
  U2D1   BW6  VSS<546>  SKX_EXT_B_BGA1  I17
  U2D1   BW12  VSS<544>  SKX_EXT_B_BGA1  I17
  U2D1   BW14  VSS<543>  SKX_EXT_B_BGA1  I17
  U2D1   BW16  VSS<542>  SKX_EXT_B_BGA1  I17
  U2D1   BW18  VSS<541>  SKX_EXT_B_BGA1  I17
  U2D1   BW26  VSS<540>  SKX_EXT_B_BGA1  I17
  U2D1   BW72  VSS<539>  SKX_EXT_B_BGA1  I17
  U2D1   BW74  VSS<538>  SKX_EXT_B_BGA1  I17
  U2D1   BW76  VSS<537>  SKX_EXT_B_BGA1  I17
  U2D1   BW78  VSS<536>  SKX_EXT_B_BGA1  I17
  U2D1   BW80  VSS<535>  SKX_EXT_B_BGA1  I17
  U2D1   BW82  VSS<534>  SKX_EXT_B_BGA1  I17
  U2D1   BY11  VSS<533>  SKX_EXT_B_BGA1  I17
  U2D1   BY13  VSS<532>  SKX_EXT_B_BGA1  I17
  U2D1   BY15  UPI2_RX_DP<18>  SKX_EXT_B_BGA1   I1
  U2D1   BY17  UPI2_RX_DN<19>  SKX_EXT_B_BGA1   I1
  U2D1   BY23  VSS<531>  SKX_EXT_B_BGA1  I17
  U2D1   BY63  VSS<530>  SKX_EXT_B_BGA1  I17
  U2D1   BY65  VSS<529>  SKX_EXT_B_BGA1  I17
  U2D1   BY67  VSS<528>  SKX_EXT_B_BGA1  I17
  U2D1   BY69  VSS<527>  SKX_EXT_B_BGA1  I17
  U2D1   BY71  VSS<526>  SKX_EXT_B_BGA1  I17
  U2D1    C4  VSS<1248>  SKX_EXT_B_BGA1  I20
  U2D1    C8  VSS<1175>  SKX_EXT_B_BGA1  I20
  U2D1   C10  VSS<1174>  SKX_EXT_B_BGA1  I20
  U2D1   C12  VSS<1173>  SKX_EXT_B_BGA1  I20
  U2D1   C14  VSS<1172>  SKX_EXT_B_BGA1  I20
  U2D1   C16  VSS<1171>  SKX_EXT_B_BGA1  I20
  U2D1   C76  VSS<1170>  SKX_EXT_B_BGA1  I20
  U2D1   C78  VSS<1169>  SKX_EXT_B_BGA1  I20
  U2D1   C80  VSS<1247>  SKX_EXT_B_BGA1  I20
  U2D1   CA2  VSS<525>  SKX_EXT_B_BGA1  I17
  U2D1   CA6  VSS<524>  SKX_EXT_B_BGA1  I17
  U2D1   CA8  VSS<523>  SKX_EXT_B_BGA1  I17
  U2D1   CA10  VSS<522>  SKX_EXT_B_BGA1  I17
  U2D1   CA14  VSS<521>  SKX_EXT_B_BGA1  I17
  U2D1   CA16  UPI2_RX_DP<19>  SKX_EXT_B_BGA1   I1
  U2D1   CA18  VSS<520>  SKX_EXT_B_BGA1  I17
  U2D1   CA20  VSS<125>  SKX_EXT_B_BGA1  I20
  U2D1   CA26  VSS<519>  SKX_EXT_B_BGA1  I17
  U2D1   CA64  VSS<518>  SKX_EXT_B_BGA1  I17
  U2D1   CA66  VSS<517>  SKX_EXT_B_BGA1  I17
  U2D1   CA68  VSS<516>  SKX_EXT_B_BGA1  I17
  U2D1   CA70  VSS<515>  SKX_EXT_B_BGA1  I17
  U2D1   CB7  VSS<514>  SKX_EXT_B_BGA1  I17
  U2D1   CB9  VSS<513>  SKX_EXT_B_BGA1  I17
  U2D1   CB15  UPI2_RX_DN<18>  SKX_EXT_B_BGA1   I1
  U2D1   CB27  VSS<512>  SKX_EXT_B_BGA1  I17
  U2D1   CB63  VSS<511>  SKX_EXT_B_BGA1  I17
  U2D1   CB71  VSS<510>  SKX_EXT_B_BGA1  I17
  U2D1   CC4  VSS<509>  SKX_EXT_B_BGA1  I17
  U2D1   CC14  UPI2_RX_DP<16>  SKX_EXT_B_BGA1   I1
  U2D1   CC16  VSS<508>  SKX_EXT_B_BGA1  I17
  U2D1   CC18  VSS<507>  SKX_EXT_B_BGA1  I17
  U2D1   CC24  VSS<506>  SKX_EXT_B_BGA1  I17
  U2D1   CC64  VSS<505>  SKX_EXT_B_BGA1  I17
  U2D1   CC72  VSS<504>  SKX_EXT_B_BGA1  I17
  U2D1   CC74  VSS<503>  SKX_EXT_B_BGA1  I17
  U2D1   CC76  VSS<502>  SKX_EXT_B_BGA1  I17
  U2D1   CC78  VSS<501>  SKX_EXT_B_BGA1  I17
  U2D1   CC80  VSS<500>  SKX_EXT_B_BGA1  I17
  U2D1   CC82  VSS<499>  SKX_EXT_B_BGA1  I17
  U2D1   CD5  VSS<498>  SKX_EXT_B_BGA1  I17
  U2D1   CD13  VSS<497>  SKX_EXT_B_BGA1  I17
  U2D1   CD15  UPI2_RX_DN<16>  SKX_EXT_B_BGA1   I1
  U2D1   CD17  UPI2_RX_DP<17>  SKX_EXT_B_BGA1   I1
  U2D1   CD63  VSS<496>  SKX_EXT_B_BGA1  I17
  U2D1   CD73  VSS<495>  SKX_EXT_B_BGA1  I17
  U2D1   CD75  VSS<494>  SKX_EXT_B_BGA1  I17
  U2D1   CD77  VSS<493>  SKX_EXT_B_BGA1  I17
  U2D1   CD79  VSS<492>  SKX_EXT_B_BGA1  I17
  U2D1   CD81  VSS<491>  SKX_EXT_B_BGA1  I17
  U2D1   CE10  VSS<490>  SKX_EXT_B_BGA1  I17
  U2D1   CE14  VSS<489>  SKX_EXT_B_BGA1  I17
  U2D1   CE16  UPI2_RX_DN<15>  SKX_EXT_B_BGA1   I1
  U2D1   CE20  VSS<488>  SKX_EXT_B_BGA1  I17
  U2D1   CE26  VSS<487>  SKX_EXT_B_BGA1  I17
  U2D1   CE62  VSS<486>  SKX_EXT_B_BGA1  I17
  U2D1   CE70  VSS<485>  SKX_EXT_B_BGA1  I17
  U2D1   CE82  VSS<484>  SKX_EXT_B_BGA1  I17
  U2D1   CF9  VSS<482>  SKX_EXT_B_BGA1  I17
  U2D1   CF15  UPI2_RX_DP<15>  SKX_EXT_B_BGA1   I1
  U2D1   CF17  UPI2_RX_DN<17>  SKX_EXT_B_BGA1   I1
  U2D1   CF63  VSS<481>  SKX_EXT_B_BGA1  I17
  U2D1   CF69  VSS<480>  SKX_EXT_B_BGA1  I17
  U2D1   CF71  VSS<479>  SKX_EXT_B_BGA1  I17
  U2D1   CF77  VSS<478>  SKX_EXT_B_BGA1  I17
  U2D1   CF83  VSS<477>  SKX_EXT_B_BGA1  I17
  U2D1   CG6  VSS<1191>  SKX_EXT_B_BGA1  I20
  U2D1   CG16  UPI2_RX_DP<14>  SKX_EXT_B_BGA1   I1
  U2D1   CG18  VSS<475>  SKX_EXT_B_BGA1  I17
  U2D1   CG22  VSS<474>  SKX_EXT_B_BGA1  I17
  U2D1   CG62  VSS<473>  SKX_EXT_B_BGA1  I17
  U2D1   CG68  VSS<472>  SKX_EXT_B_BGA1  I17
  U2D1   CG72  VSS<471>  SKX_EXT_B_BGA1  I17
  U2D1   CG80  VSS<470>  SKX_EXT_B_BGA1  I17
  U2D1   CH1  VSS<469>  SKX_EXT_B_BGA1  I17
  U2D1   CH3  VSS<468>  SKX_EXT_B_BGA1  I17
  U2D1   CH15  VSS<467>  SKX_EXT_B_BGA1  I17
  U2D1   CH17  UPI2_RX_DN<14>  SKX_EXT_B_BGA1   I1
  U2D1   CH19  VSS<466>  SKX_EXT_B_BGA1  I17
  U2D1   CH63  VSS<465>  SKX_EXT_B_BGA1  I17
  U2D1   CH67  VSS<464>  SKX_EXT_B_BGA1  I17
  U2D1   CH73  VSS<463>  SKX_EXT_B_BGA1  I17
  U2D1   CH79  VSS<462>  SKX_EXT_B_BGA1  I17
  U2D1   CH81  VSS<461>  SKX_EXT_B_BGA1  I17
  U2D1   CH83  VSS<460>  SKX_EXT_B_BGA1  I17
  U2D1   CJ2  VSS<459>  SKX_EXT_B_BGA1  I17
  U2D1   CJ6  VSS<458>  SKX_EXT_B_BGA1  I17
  U2D1   CJ8  VSS<457>  SKX_EXT_B_BGA1  I17
  U2D1   CJ10  VSS<456>  SKX_EXT_B_BGA1  I17
  U2D1   CJ12  VSS<455>  SKX_EXT_B_BGA1  I17
  U2D1   CJ16  UPI2_RX_DP<12>  SKX_EXT_B_BGA1   I1
  U2D1   CJ18  UPI2_RX_DN<13>  SKX_EXT_B_BGA1   I1
  U2D1   CJ62  VSS<452>  SKX_EXT_B_BGA1  I18
  U2D1   CJ74  VSS<451>  SKX_EXT_B_BGA1  I18
  U2D1   CJ76  VSS<450>  SKX_EXT_B_BGA1  I18
  U2D1   CJ78  VSS<449>  SKX_EXT_B_BGA1  I18
  U2D1   CJ82  VSS<448>  SKX_EXT_B_BGA1  I18
  U2D1   CJ84  VSS<447>  SKX_EXT_B_BGA1  I18
  U2D1   CJ86  VSS<446>  SKX_EXT_B_BGA1  I18
  U2D1   CK11  VSS<445>  SKX_EXT_B_BGA1  I18
  U2D1   CK15  VSS<444>  SKX_EXT_B_BGA1  I18
  U2D1   CK17  UPI2_RX_DP<13>  SKX_EXT_B_BGA1   I1
  U2D1   CK21  VSS<443>  SKX_EXT_B_BGA1  I18
  U2D1   CK27  VSS<442>  SKX_EXT_B_BGA1  I18
  U2D1   CK63  VSS<441>  SKX_EXT_B_BGA1  I18
  U2D1   CK65  VSS<440>  SKX_EXT_B_BGA1  I18
  U2D1   CK67  VSS<439>  SKX_EXT_B_BGA1  I18
  U2D1   CK69  VSS<438>  SKX_EXT_B_BGA1  I18
  U2D1   CK71  VSS<437>  SKX_EXT_B_BGA1  I18
  U2D1   CK73  VSS<436>  SKX_EXT_B_BGA1  I18
  U2D1   CK75  VSS<435>  SKX_EXT_B_BGA1  I18
  U2D1   CK83  VSS<434>  SKX_EXT_B_BGA1  I18
  U2D1   CK85  VSS<433>  SKX_EXT_B_BGA1  I18
  U2D1   CL8  VSS<432>  SKX_EXT_B_BGA1  I18
  U2D1   CL14  VSS<431>  SKX_EXT_B_BGA1  I18
  U2D1   CL16  UPI2_RX_DN<12>  SKX_EXT_B_BGA1   I1
  U2D1   CL18  VSS<430>  SKX_EXT_B_BGA1  I18
  U2D1   CL22  VSS<124>  SKX_EXT_B_BGA1  I20
  U2D1   CL62  VSS<427>  SKX_EXT_B_BGA1  I18
  U2D1   CL64  VSS<426>  SKX_EXT_B_BGA1  I18
  U2D1   CL66  VSS<425>  SKX_EXT_B_BGA1  I18
  U2D1   CL74  VSS<424>  SKX_EXT_B_BGA1  I18
  U2D1   CL76  VSS<423>  SKX_EXT_B_BGA1  I18
  U2D1   CL78  VSS<422>  SKX_EXT_B_BGA1  I18
  U2D1   CL80  VSS<421>  SKX_EXT_B_BGA1  I18
  U2D1   CM5  VSS<418>  SKX_EXT_B_BGA1  I18
  U2D1   CM19  VSS<420>  SKX_EXT_B_BGA1  I18
  U2D1   CM21  UPI2_RX_DP<11>  SKX_EXT_B_BGA1   I1
  U2D1   CM27  VSS<1168>  SKX_EXT_B_BGA1  I20
  U2D1   CM29  VSS<419>  SKX_EXT_B_BGA1  I18
  U2D1   CM31  VSS<417>  SKX_EXT_B_BGA1  I18
  U2D1   CM61  VSS<416>  SKX_EXT_B_BGA1  I18
  U2D1   CM63  VSS<415>  SKX_EXT_B_BGA1  I18
  U2D1   CM67  VSS<414>  SKX_EXT_B_BGA1  I18
  U2D1   CM73  VSS<413>  SKX_EXT_B_BGA1  I18
  U2D1   CM77  VSS<412>  SKX_EXT_B_BGA1  I18
  U2D1   CM83  VSS<411>  SKX_EXT_B_BGA1  I18
  U2D1   CM85  VSS<410>  SKX_EXT_B_BGA1  I18
  U2D1   CN2  VSS<409>  SKX_EXT_B_BGA1  I18
  U2D1   CN12  VSS<408>  SKX_EXT_B_BGA1  I18
  U2D1   CN14  VSS<94>  SKX_EXT_B_BGA1  I20
  U2D1   CN18  UPI2_RX_DP<9>  SKX_EXT_B_BGA1   I1
  U2D1   CN20  UPI2_RX_DN<10>  SKX_EXT_B_BGA1   I1
  U2D1   CN26  VSS<406>  SKX_EXT_B_BGA1  I18
  U2D1   CN32  VSS<405>  SKX_EXT_B_BGA1  I18
  U2D1   CN60  VSS<404>  SKX_EXT_B_BGA1  I18
  U2D1   CN62  VSS<403>  SKX_EXT_B_BGA1  I18
  U2D1   CN68  VSS<402>  SKX_EXT_B_BGA1  I18
  U2D1   CN78  VSS<401>  SKX_EXT_B_BGA1  I18
  U2D1   CP1  VSS<400>  SKX_EXT_B_BGA1  I18
  U2D1   CP19  UPI2_RX_DP<10>  SKX_EXT_B_BGA1   I1
  U2D1   CP21  UPI2_RX_DN<11>  SKX_EXT_B_BGA1   I1
  U2D1   CP25  VSS<398>  SKX_EXT_B_BGA1  I18
  U2D1   CP59  VSS<397>  SKX_EXT_B_BGA1  I18
  U2D1   CP69  VSS<396>  SKX_EXT_B_BGA1  I18
  U2D1   CP73  VSS<395>  SKX_EXT_B_BGA1  I18
  U2D1   CP75  VSS<394>  SKX_EXT_B_BGA1  I18
  U2D1   CP81  VSS<393>  SKX_EXT_B_BGA1  I18
  U2D1   CP83  VSS<392>  SKX_EXT_B_BGA1  I18
  U2D1   CR6  VSS<391>  SKX_EXT_B_BGA1  I18
  U2D1   CR10  VSS<390>  SKX_EXT_B_BGA1  I18
  U2D1   CR18  UPI2_RX_DN<9>  SKX_EXT_B_BGA1   I1
  U2D1   CR20  UPI2_RX_DP<8>  SKX_EXT_B_BGA1   I1
  U2D1   CR22  VSS<389>  SKX_EXT_B_BGA1  I18
  U2D1   CR24  VSS<388>  SKX_EXT_B_BGA1  I18
  U2D1   CR32  VSS<387>  SKX_EXT_B_BGA1  I18
  U2D1   CR58  VSS<386>  SKX_EXT_B_BGA1  I18
  U2D1   CR62  VSS<385>  SKX_EXT_B_BGA1  I18
  U2D1   CR64  VSS<384>  SKX_EXT_B_BGA1  I18
  U2D1   CR66  VSS<383>  SKX_EXT_B_BGA1  I18
  U2D1   CR68  VSS<382>  SKX_EXT_B_BGA1  I18
  U2D1   CR78  VSS<381>  SKX_EXT_B_BGA1  I18
  U2D1   CR86  VSS<380>  SKX_EXT_B_BGA1  I18
  U2D1   CT7  VSS<1063>  SKX_EXT_B_BGA1  I21
  U2D1   CT13  VSS<378>  SKX_EXT_B_BGA1  I18
  U2D1   CT19  VSS<377>  SKX_EXT_B_BGA1  I18
  U2D1   CT21  UPI2_RX_DN<8>  SKX_EXT_B_BGA1   I1
  U2D1   CT27  VSS<376>  SKX_EXT_B_BGA1  I18
  U2D1   CT29  VSS<375>  SKX_EXT_B_BGA1  I18
  U2D1   CT33  VSS<374>  SKX_EXT_B_BGA1  I18
  U2D1   CT35  VSS<373>  SKX_EXT_B_BGA1  I18
  U2D1   CT57  VSS<372>  SKX_EXT_B_BGA1  I18
  U2D1   CT73  VSS<371>  SKX_EXT_B_BGA1  I18
  U2D1   CT79  VSS<370>  SKX_EXT_B_BGA1  I18
  U2D1   CT83  VSS<369>  SKX_EXT_B_BGA1  I18
  U2D1   CT85  VSS<368>  SKX_EXT_B_BGA1  I18
  U2D1   CU4  VSS<367>  SKX_EXT_B_BGA1  I18
  U2D1   CU20  UPI2_RX_DP<6>  SKX_EXT_B_BGA1   I1
  U2D1   CU22  VSS<366>  SKX_EXT_B_BGA1  I18
  U2D1   CU28  VSS<365>  SKX_EXT_B_BGA1  I18
  U2D1   CU30  VSS<364>  SKX_EXT_B_BGA1  I18
  U2D1   CU34  VSS<363>  SKX_EXT_B_BGA1  I18
  U2D1   CU36  VSS<362>  SKX_EXT_B_BGA1  I18
  U2D1   CU56  VSS<361>  SKX_EXT_B_BGA1  I18
  U2D1   CU62  VSS<360>  SKX_EXT_B_BGA1  I18
  U2D1   CU68  VSS<359>  SKX_EXT_B_BGA1  I18
  U2D1   CU76  VSS<358>  SKX_EXT_B_BGA1  I18
  U2D1   CU78  VSS<357>  SKX_EXT_B_BGA1  I18
  U2D1   CU80  VSS<356>  SKX_EXT_B_BGA1  I18
  U2D1   CU82  VSS<355>  SKX_EXT_B_BGA1  I18
  U2D1   CU86  VSS<354>  SKX_EXT_B_BGA1  I18
  U2D1   CV1  VSS<353>  SKX_EXT_B_BGA1  I18
  U2D1   CV17  VSS<351>  SKX_EXT_B_BGA1  I18
  U2D1   CV19  UPI2_RX_DN<7>  SKX_EXT_B_BGA1   I1
  U2D1   CV25  VSS<350>  SKX_EXT_B_BGA1  I18
  U2D1   CV27  VSS<349>  SKX_EXT_B_BGA1  I18
  U2D1   CV31  VSS<348>  SKX_EXT_B_BGA1  I18
  U2D1   CV33  VSS<347>  SKX_EXT_B_BGA1  I18
  U2D1   CV37  VSS<346>  SKX_EXT_B_BGA1  I18
  U2D1   CV39  VSS<345>  SKX_EXT_B_BGA1  I18
  U2D1   CV41  VSS<344>  SKX_EXT_B_BGA1  I18
  U2D1   CV53  VSS<343>  SKX_EXT_B_BGA1  I18
  U2D1   CV55  VSS<342>  SKX_EXT_B_BGA1  I18
  U2D1   CV63  VSS<341>  SKX_EXT_B_BGA1  I18
  U2D1   CV67  VSS<340>  SKX_EXT_B_BGA1  I18
  U2D1   CV73  VSS<339>  SKX_EXT_B_BGA1  I18
  U2D1   CV79  VSS<338>  SKX_EXT_B_BGA1  I18
  U2D1   CV81  VSS<337>  SKX_EXT_B_BGA1  I18
  U2D1   CV83  VSS<336>  SKX_EXT_B_BGA1  I18
  U2D1   CW6  VSS<1192>  SKX_EXT_B_BGA1  I20
  U2D1   CW12  VSS<335>  SKX_EXT_B_BGA1  I18
  U2D1   CW18  UPI2_RX_DP<7>  SKX_EXT_B_BGA1   I1
  U2D1   CW20  UPI2_RX_DN<6>  SKX_EXT_B_BGA1   I1
  U2D1   CW26  VSS<334>  SKX_EXT_B_BGA1  I18
  U2D1   CW32  VSS<333>  SKX_EXT_B_BGA1  I18
  U2D1   CW38  VSS<332>  SKX_EXT_B_BGA1  I18
  U2D1   CW40  VSS<331>  SKX_EXT_B_BGA1  I18
  U2D1   CW42  VSS<330>  SKX_EXT_B_BGA1  I18
  U2D1   CW52  VSS<329>  SKX_EXT_B_BGA1  I18
  U2D1   CW54  VSS<328>  SKX_EXT_B_BGA1  I18
  U2D1   CW64  VSS<327>  SKX_EXT_B_BGA1  I18
  U2D1   CW66  VSS<326>  SKX_EXT_B_BGA1  I18
  U2D1   CW68  VSS<325>  SKX_EXT_B_BGA1  I18
  U2D1   CW74  VSS<324>  SKX_EXT_B_BGA1  I18
  U2D1   CW78  VSS<323>  SKX_EXT_B_BGA1  I18
  U2D1   CW82  VSS<322>  SKX_EXT_B_BGA1  I18
  U2D1   CY1  VSS<321>  SKX_EXT_B_BGA1  I18
  U2D1   CY9  VSS<320>  SKX_EXT_B_BGA1  I18
  U2D1   CY13  VSS<319>  SKX_EXT_B_BGA1  I18
  U2D1   CY15  VSS<318>  SKX_EXT_B_BGA1  I18
  U2D1   CY19  UPI2_RX_DP<5>  SKX_EXT_B_BGA1   I1
  U2D1   CY21  VSS<317>  SKX_EXT_B_BGA1  I18
  U2D1   CY41  VSS<316>  SKX_EXT_B_BGA1  I18
  U2D1   CY45  VSS<315>  SKX_EXT_B_BGA1  I18
  U2D1   CY51  VSS<314>  SKX_EXT_B_BGA1  I18
  U2D1   CY59  VSS<313>  SKX_EXT_B_BGA1  I18
  U2D1   CY61  VSS<312>  SKX_EXT_B_BGA1  I18
  U2D1   CY65  VSS<311>  SKX_EXT_B_BGA1  I18
  U2D1   CY69  VSS<310>  SKX_EXT_B_BGA1  I18
  U2D1   CY75  VSS<309>  SKX_EXT_B_BGA1  I18
  U2D1   CY77  VSS<308>  SKX_EXT_B_BGA1  I18
  U2D1   CY83  VSS<307>  SKX_EXT_B_BGA1  I18
  U2D1   CY85  VSS<306>  SKX_EXT_B_BGA1  I18
  U2D1    D3  VSS<1246>  SKX_EXT_B_BGA1  I20
  U2D1   D11  VSS<1167>  SKX_EXT_B_BGA1  I20
  U2D1   D13  VSS<1166>  SKX_EXT_B_BGA1  I20
  U2D1   D25  VSS<1165>  SKX_EXT_B_BGA1  I20
  U2D1   D27  VSS<1164>  SKX_EXT_B_BGA1  I20
  U2D1   D29  VSS<1163>  SKX_EXT_B_BGA1  I20
  U2D1   D31  VSS<1162>  SKX_EXT_B_BGA1  I20
  U2D1   D33  VSS<1161>  SKX_EXT_B_BGA1  I20
  U2D1   D35  VSS<1160>  SKX_EXT_B_BGA1  I20
  U2D1   D37  VSS<1159>  SKX_EXT_B_BGA1  I20
  U2D1   D39  VSS<1158>  SKX_EXT_B_BGA1  I20
  U2D1   D41  VSS<1157>  SKX_EXT_B_BGA1  I20
  U2D1   D43  VSS<1156>  SKX_EXT_B_BGA1  I20
  U2D1   D77  VSS<1155>  SKX_EXT_B_BGA1  I20
  U2D1   D81  VSS<1245>  SKX_EXT_B_BGA1  I20
  U2D1   DA6  VSS<305>  SKX_EXT_B_BGA1  I18
  U2D1   DA18  VSS<303>  SKX_EXT_B_BGA1  I18
  U2D1   DA20  UPI2_RX_DN<5>  SKX_EXT_B_BGA1   I1
  U2D1   DA22  UPI2_RX_DP<2>  SKX_EXT_B_BGA1   I1
  U2D1   DA26  VSS<302>  SKX_EXT_B_BGA1  I18
  U2D1   DA28  VSS<301>  SKX_EXT_B_BGA1  I18
  U2D1   DA30  VSS<300>  SKX_EXT_B_BGA1  I18
  U2D1   DA32  VSS<299>  SKX_EXT_B_BGA1  I18
  U2D1   DA34  VSS<298>  SKX_EXT_B_BGA1  I18
  U2D1   DA36  VSS<297>  SKX_EXT_B_BGA1  I18
  U2D1   DA38  VSS<296>  SKX_EXT_B_BGA1  I18
  U2D1   DA44  VSS<295>  SKX_EXT_B_BGA1  I18
  U2D1   DA46  VSS<294>  SKX_EXT_B_BGA1  I18
  U2D1   DA48  VSS<293>  SKX_EXT_B_BGA1  I19
  U2D1   DA50  VSS<292>  SKX_EXT_B_BGA1  I19
  U2D1   DA64  VSS<291>  SKX_EXT_B_BGA1  I19
  U2D1   DA70  VSS<290>  SKX_EXT_B_BGA1  I19
  U2D1   DA74  VSS<289>  SKX_EXT_B_BGA1  I19
  U2D1   DA76  VSS<288>  SKX_EXT_B_BGA1  I19
  U2D1   DA78  VSS<287>  SKX_EXT_B_BGA1  I19
  U2D1   DA80  VSS<286>  SKX_EXT_B_BGA1  I19
  U2D1   DB3  VSS<285>  SKX_EXT_B_BGA1  I19
  U2D1   DB7  VSS<1086>  SKX_EXT_B_BGA1  I21
  U2D1   DB13  VSS<284>  SKX_EXT_B_BGA1  I19
  U2D1   DB17  VSS<283>  SKX_EXT_B_BGA1  I19
  U2D1   DB19  UPI2_RX_DP<4>  SKX_EXT_B_BGA1   I1
  U2D1   DB21  UPI2_RX_DN<3>  SKX_EXT_B_BGA1   I1
  U2D1   DB23  VSS<282>  SKX_EXT_B_BGA1  I19
  U2D1   DB25  VSS<281>  SKX_EXT_B_BGA1  I19
  U2D1   DB39  VSS<280>  SKX_EXT_B_BGA1  I19
  U2D1   DB41  VSS<279>  SKX_EXT_B_BGA1  I19
  U2D1   DB47  VSS<278>  SKX_EXT_B_BGA1  I19
  U2D1   DB49  VSS<277>  SKX_EXT_B_BGA1  I19
  U2D1   DB73  VSS<276>  SKX_EXT_B_BGA1  I19
  U2D1   DB77  VSS<275>  SKX_EXT_B_BGA1  I19
  U2D1   DB83  VSS<274>  SKX_EXT_B_BGA1  I19
  U2D1   DB85  VSS<273>  SKX_EXT_B_BGA1  I19
  U2D1   DC14  VSS<272>  SKX_EXT_B_BGA1  I19
  U2D1   DC20  UPI2_RX_DP<3>  SKX_EXT_B_BGA1   I1
  U2D1   DC22  UPI2_RX_DN<2>  SKX_EXT_B_BGA1   I1
  U2D1   DC24  VSS<271>  SKX_EXT_B_BGA1  I19
  U2D1   DC26  VSS<270>  SKX_EXT_B_BGA1  I19
  U2D1   DC32  VSS<269>  SKX_EXT_B_BGA1  I19
  U2D1   DC38  VSS<268>  SKX_EXT_B_BGA1  I19
  U2D1   DC42  VSS<267>  SKX_EXT_B_BGA1  I19
  U2D1   DC64  VSS<266>  SKX_EXT_B_BGA1  I19
  U2D1   DC66  VSS<265>  SKX_EXT_B_BGA1  I19
  U2D1   DC68  VSS<264>  SKX_EXT_B_BGA1  I19
  U2D1   DC70  VSS<263>  SKX_EXT_B_BGA1  I19
  U2D1   DC78  VSS<262>  SKX_EXT_B_BGA1  I19
  U2D1   DC84  VSS<261>  SKX_EXT_B_BGA1  I19
  U2D1   DC86  VSS<260>  SKX_EXT_B_BGA1  I19
  U2D1   DD11  VSS<259>  SKX_EXT_B_BGA1  I19
  U2D1   DD19  UPI2_RX_DN<4>  SKX_EXT_B_BGA1   I1
  U2D1   DD21  UPI2_RX_DP<1>  SKX_EXT_B_BGA1   I1
  U2D1   DD23  VSS<258>  SKX_EXT_B_BGA1  I19
  U2D1   DD27  VSS<257>  SKX_EXT_B_BGA1  I19
  U2D1   DD31  VSS<256>  SKX_EXT_B_BGA1  I19
  U2D1   DD33  VSS<255>  SKX_EXT_B_BGA1  I19
  U2D1   DD37  VSS<254>  SKX_EXT_B_BGA1  I19
  U2D1   DD71  VSS<253>  SKX_EXT_B_BGA1  I19
  U2D1   DD73  VSS<252>  SKX_EXT_B_BGA1  I19
  U2D1   DD75  VSS<251>  SKX_EXT_B_BGA1  I19
  U2D1   DD81  VSS<250>  SKX_EXT_B_BGA1  I19
  U2D1   DD83  VSS<249>  SKX_EXT_B_BGA1  I19
  U2D1   DE6  VSS<248>  SKX_EXT_B_BGA1  I19
  U2D1   DE8  VSS<247>  SKX_EXT_B_BGA1  I19
  U2D1   DE18  VSS<246>  SKX_EXT_B_BGA1  I19
  U2D1   DE20  VSS<245>  SKX_EXT_B_BGA1  I19
  U2D1   DE22  UPI2_RX_DN<1>  SKX_EXT_B_BGA1   I1
  U2D1   DE24  VSS<244>  SKX_EXT_B_BGA1  I19
  U2D1   DE28  VSS<243>  SKX_EXT_B_BGA1  I19
  U2D1   DE30  VSS<242>  SKX_EXT_B_BGA1  I19
  U2D1   DE34  VSS<241>  SKX_EXT_B_BGA1  I19
  U2D1   DE36  VSS<240>  SKX_EXT_B_BGA1  I19
  U2D1   DE48  VSS<1193>  SKX_EXT_B_BGA1  I20
  U2D1   DE50  VSS<1194>  SKX_EXT_B_BGA1  I20
  U2D1   DE52  VSS<1195>  SKX_EXT_B_BGA1  I20
  U2D1   DE54  VSS<1196>  SKX_EXT_B_BGA1  I20
  U2D1   DE56  VSS<1197>  SKX_EXT_B_BGA1  I20
  U2D1   DE58  VSS<1198>  SKX_EXT_B_BGA1  I20
  U2D1   DE60  VSS<1199>  SKX_EXT_B_BGA1  I20
  U2D1   DE62  VSS<1200>  SKX_EXT_B_BGA1  I20
  U2D1   DE64  VSS<239>  SKX_EXT_B_BGA1  I19
  U2D1   DE70  VSS<238>  SKX_EXT_B_BGA1  I19
  U2D1   DE72  VSS<237>  SKX_EXT_B_BGA1  I19
  U2D1   DE78  VSS<236>  SKX_EXT_B_BGA1  I19
  U2D1   DF5  VSS<235>  SKX_EXT_B_BGA1  I19
  U2D1   DF7  VSS<234>  SKX_EXT_B_BGA1  I19
  U2D1   DF19  VSS<232>  SKX_EXT_B_BGA1  I19
  U2D1   DF23  UPI2_RX_DN<0>  SKX_EXT_B_BGA1   I1
  U2D1   DF29  VSS<231>  SKX_EXT_B_BGA1  I19
  U2D1   DF35  VSS<230>  SKX_EXT_B_BGA1  I19
  U2D1   DF37  VSS<229>  SKX_EXT_B_BGA1  I19
  U2D1   DF39  VSS<228>  SKX_EXT_B_BGA1  I19
  U2D1   DF41  VSS<227>  SKX_EXT_B_BGA1  I19
  U2D1   DF65  VSS<226>  SKX_EXT_B_BGA1  I19
  U2D1   DF69  VSS<225>  SKX_EXT_B_BGA1  I19
  U2D1   DF73  VSS<224>  SKX_EXT_B_BGA1  I19
  U2D1   DF79  VSS<223>  SKX_EXT_B_BGA1  I19
  U2D1   DF83  VSS<222>  SKX_EXT_B_BGA1  I19
  U2D1   DF85  VSS<221>  SKX_EXT_B_BGA1  I19
  U2D1   DG2  VSS<220>  SKX_EXT_B_BGA1  I19
  U2D1   DG14  VSS<218>  SKX_EXT_B_BGA1  I19
  U2D1   DG16  VSS<217>  SKX_EXT_B_BGA1  I19
  U2D1   DG22  UPI2_RX_DP<0>  SKX_EXT_B_BGA1   I1
  U2D1   DG24  VSS<216>  SKX_EXT_B_BGA1  I19
  U2D1   DG66  VSS<215>  SKX_EXT_B_BGA1  I19
  U2D1   DG68  VSS<214>  SKX_EXT_B_BGA1  I19
  U2D1   DG76  VSS<213>  SKX_EXT_B_BGA1  I19
  U2D1   DG78  VSS<212>  SKX_EXT_B_BGA1  I19
  U2D1   DG80  VSS<211>  SKX_EXT_B_BGA1  I19
  U2D1   DG82  VSS<210>  SKX_EXT_B_BGA1  I19
  U2D1   DH13  VSS<209>  SKX_EXT_B_BGA1  I19
  U2D1   DH15  VSS<208>  SKX_EXT_B_BGA1  I19
  U2D1   DH21  VSS<102>  SKX_EXT_B_BGA1  I20
  U2D1   DH23  VSS<207>  SKX_EXT_B_BGA1  I19
  U2D1   DH25  VSS<206>  SKX_EXT_B_BGA1  I19
  U2D1   DH27  VSS<205>  SKX_EXT_B_BGA1  I19
  U2D1   DH29  VSS<204>  SKX_EXT_B_BGA1  I19
  U2D1   DH31  VSS<203>  SKX_EXT_B_BGA1  I19
  U2D1   DH33  VSS<202>  SKX_EXT_B_BGA1  I19
  U2D1   DH35  VSS<201>  SKX_EXT_B_BGA1  I19
  U2D1   DH37  VSS<200>  SKX_EXT_B_BGA1  I19
  U2D1   DH41  VSS<199>  SKX_EXT_B_BGA1  I19
  U2D1   DH67  VSS<198>  SKX_EXT_B_BGA1  I19
  U2D1   DH71  VSS<197>  SKX_EXT_B_BGA1  I19
  U2D1   DH73  VSS<196>  SKX_EXT_B_BGA1  I19
  U2D1   DH79  VSS<195>  SKX_EXT_B_BGA1  I19
  U2D1   DH81  VSS<194>  SKX_EXT_B_BGA1  I19
  U2D1   DH83  VSS<193>  SKX_EXT_B_BGA1  I19
  U2D1   DJ2  VSS<192>  SKX_EXT_B_BGA1  I19
  U2D1   DJ10  VSS<191>  SKX_EXT_B_BGA1  I19
  U2D1   DJ22  VSS<189>  SKX_EXT_B_BGA1  I19
  U2D1   DJ38  VSS<188>  SKX_EXT_B_BGA1  I19
  U2D1   DJ42  VSS<187>  SKX_EXT_B_BGA1  I19
  U2D1   DJ68  VSS<186>  SKX_EXT_B_BGA1  I19
  U2D1   DJ74  VSS<185>  SKX_EXT_B_BGA1  I19
  U2D1   DJ78  VSS<184>  SKX_EXT_B_BGA1  I19
  U2D1   DJ82  VSS<183>  SKX_EXT_B_BGA1  I19
  U2D1   DJ84  VSS<182>  SKX_EXT_B_BGA1  I19
  U2D1   DK7  VSS<181>  SKX_EXT_B_BGA1  I19
  U2D1   DK23  VSS<180>  SKX_EXT_B_BGA1  I19
  U2D1   DK29  VSS<179>  SKX_EXT_B_BGA1  I19
  U2D1   DK35  VSS<178>  SKX_EXT_B_BGA1  I19
  U2D1   DK39  VSS<177>  SKX_EXT_B_BGA1  I19
  U2D1   DK41  VSS<176>  SKX_EXT_B_BGA1  I19
  U2D1   DK73  VSS<175>  SKX_EXT_B_BGA1  I19
  U2D1   DK75  VSS<174>  SKX_EXT_B_BGA1  I19
  U2D1   DK77  VSS<173>  SKX_EXT_B_BGA1  I19
  U2D1   DK83  VSS<172>  SKX_EXT_B_BGA1  I19
  U2D1   DK85  VSS<171>  SKX_EXT_B_BGA1  I19
  U2D1   DL4  VSS<168>  SKX_EXT_B_BGA1  I19
  U2D1   DL8  VSS<1201>  SKX_EXT_B_BGA1  I20
  U2D1   DL16  VSS<170>  SKX_EXT_B_BGA1  I19
  U2D1   DL18  VSS<169>  SKX_EXT_B_BGA1  I19
  U2D1   DL22  VSS<167>  SKX_EXT_B_BGA1  I19
  U2D1   DL24  VSS<166>  SKX_EXT_B_BGA1  I19
  U2D1   DL28  VSS<165>  SKX_EXT_B_BGA1  I19
  U2D1   DL30  VSS<164>  SKX_EXT_B_BGA1  I19
  U2D1   DL34  VSS<163>  SKX_EXT_B_BGA1  I19
  U2D1   DL36  VSS<162>  SKX_EXT_B_BGA1  I19
  U2D1   DL40  VSS<161>  SKX_EXT_B_BGA1  I19
  U2D1   DL68  VSS<160>  SKX_EXT_B_BGA1  I19
  U2D1   DL70  VSS<159>  SKX_EXT_B_BGA1  I19
  U2D1   DL74  VSS<158>  SKX_EXT_B_BGA1  I19
  U2D1   DL76  VSS<157>  SKX_EXT_B_BGA1  I19
  U2D1   DL78  VSS<156>  SKX_EXT_B_BGA1  I19
  U2D1   DL80  VSS<155>  SKX_EXT_B_BGA1  I19
  U2D1   DM15  VSS<154>  SKX_EXT_B_BGA1  I19
  U2D1   DM19  VSS<1043>  SKX_EXT_B_BGA1  I21
  U2D1   DM25  VSS<152>  SKX_EXT_B_BGA1  I19
  U2D1   DM27  VSS<151>  SKX_EXT_B_BGA1  I19
  U2D1   DM31  VSS<150>  SKX_EXT_B_BGA1  I19
  U2D1   DM33  VSS<149>  SKX_EXT_B_BGA1  I19
  U2D1   DM37  VSS<148>  SKX_EXT_B_BGA1  I19
  U2D1   DM39  VSS<147>  SKX_EXT_B_BGA1  I19
  U2D1   DM65  VSS<146>  SKX_EXT_B_BGA1  I19
  U2D1   DM73  VSS<145>  SKX_EXT_B_BGA1  I19
  U2D1   DM77  VSS<144>  SKX_EXT_B_BGA1  I19
  U2D1   DM83  VSS<143>  SKX_EXT_B_BGA1  I19
  U2D1   DN2  VSS<142>  SKX_EXT_B_BGA1  I19
  U2D1   DN12  VSS<140>  SKX_EXT_B_BGA1  I19
  U2D1   DN18  VSS<1202>  SKX_EXT_B_BGA1  I20
  U2D1   DN22  VSS<139>  SKX_EXT_B_BGA1  I19
  U2D1   DN26  VSS<138>  SKX_EXT_B_BGA1  I19
  U2D1   DN32  VSS<137>  SKX_EXT_B_BGA1  I19
  U2D1   DN38  VSS<136>  SKX_EXT_B_BGA1  I19
  U2D1   DN44  VSS<1106>  SKX_EXT_B_BGA1  I20
  U2D1   DN68  VSS<135>  SKX_EXT_B_BGA1  I19
  U2D1   DN72  VSS<134>  SKX_EXT_B_BGA1  I19
  U2D1   DN78  VSS<133>  SKX_EXT_B_BGA1  I20
  U2D1   DP9  VSS<1213>  SKX_EXT_B_BGA1  I20
  U2D1   DP45  VSS<1203>  SKX_EXT_B_BGA1  I20
  U2D1   DP47  VSS<1204>  SKX_EXT_B_BGA1  I20
  U2D1   DP49  VSS<1205>  SKX_EXT_B_BGA1  I20
  U2D1   DP51  VSS<1206>  SKX_EXT_B_BGA1  I20
  U2D1   DP53  VSS<1207>  SKX_EXT_B_BGA1  I20
  U2D1   DP55  VSS<1208>  SKX_EXT_B_BGA1  I20
  U2D1   DP57  VSS<1209>  SKX_EXT_B_BGA1  I20
  U2D1   DP59  VSS<1210>  SKX_EXT_B_BGA1  I20
  U2D1   DP61  VSS<1211>  SKX_EXT_B_BGA1  I20
  U2D1   DP63  VSS<1212>  SKX_EXT_B_BGA1  I20
  U2D1   DP67  VSS<132>  SKX_EXT_B_BGA1  I20
  U2D1   DP69  VSS<131>  SKX_EXT_B_BGA1  I20
  U2D1   DP71  VSS<130>  SKX_EXT_B_BGA1  I20
  U2D1   DP81  VSS<129>  SKX_EXT_B_BGA1  I20
  U2D1   DP83  VSS<128>  SKX_EXT_B_BGA1  I20
  U2D1   DR6  VSS<126>  SKX_EXT_B_BGA1  I20
  U2D1   DR20  VSS<123>  SKX_EXT_B_BGA1  I20
  U2D1   DR22  VSS<122>  SKX_EXT_B_BGA1  I20
  U2D1   DR24  VSS<121>  SKX_EXT_B_BGA1  I20
  U2D1   DR26  VSS<120>  SKX_EXT_B_BGA1  I20
  U2D1   DR28  VSS<119>  SKX_EXT_B_BGA1  I20
  U2D1   DR30  VSS<118>  SKX_EXT_B_BGA1  I20
  U2D1   DR32  VSS<117>  SKX_EXT_B_BGA1  I20
  U2D1   DR34  VSS<116>  SKX_EXT_B_BGA1  I20
  U2D1   DR36  VSS<115>  SKX_EXT_B_BGA1  I20
  U2D1   DR38  VSS<114>  SKX_EXT_B_BGA1  I20
  U2D1   DR40  VSS<113>  SKX_EXT_B_BGA1  I20
  U2D1   DR42  VSS<112>  SKX_EXT_B_BGA1  I20
  U2D1   DR66  VSS<111>  SKX_EXT_B_BGA1  I20
  U2D1   DR68  VSS<110>  SKX_EXT_B_BGA1  I20
  U2D1   DR70  VSS<109>  SKX_EXT_B_BGA1  I20
  U2D1   DR72  VSS<108>  SKX_EXT_B_BGA1  I20
  U2D1   DR74  VSS<107>  SKX_EXT_B_BGA1  I20
  U2D1   DR76  VSS<106>  SKX_EXT_B_BGA1  I20
  U2D1   DR78  VSS<105>  SKX_EXT_B_BGA1  I20
  U2D1   DT3  VSS<104>  SKX_EXT_B_BGA1  I20
  U2D1   DT17  VSS<103>  SKX_EXT_B_BGA1  I20
  U2D1   DT65  VSS<101>  SKX_EXT_B_BGA1  I20
  U2D1   DT69  VSS<100>  SKX_EXT_B_BGA1  I20
  U2D1   DT79  VSS<99>  SKX_EXT_B_BGA1  I20
  U2D1   DT83  VSS<98>  SKX_EXT_B_BGA1  I20
  U2D1   DT85  VSS<97>  SKX_EXT_B_BGA1  I20
  U2D1   DU10  VSS<96>  SKX_EXT_B_BGA1  I20
  U2D1   DU14  VSS<95>  SKX_EXT_B_BGA1  I20
  U2D1   DU22  VSS<93>  SKX_EXT_B_BGA1  I20
  U2D1   DU26  VSS<92>  SKX_EXT_B_BGA1  I20
  U2D1   DU32  VSS<91>  SKX_EXT_B_BGA1  I20
  U2D1   DU38  VSS<90>  SKX_EXT_B_BGA1  I20
  U2D1   DU70  VSS<89>  SKX_EXT_B_BGA1  I20
  U2D1   DU72  VSS<88>  SKX_EXT_B_BGA1  I20
  U2D1   DU78  VSS<87>  SKX_EXT_B_BGA1  I20
  U2D1   DU80  VSS<86>  SKX_EXT_B_BGA1  I20
  U2D1   DU82  VSS<85>  SKX_EXT_B_BGA1  I20
  U2D1   DU84  VSS<84>  SKX_EXT_B_BGA1  I20
  U2D1   DV19  VSS<1214>  SKX_EXT_B_BGA1  I20
  U2D1   DV21  VSS<83>  SKX_EXT_B_BGA1  I20
  U2D1   DV25  VSS<82>  SKX_EXT_B_BGA1  I20
  U2D1   DV27  VSS<81>  SKX_EXT_B_BGA1  I20
  U2D1   DV31  VSS<80>  SKX_EXT_B_BGA1  I20
  U2D1   DV33  VSS<79>  SKX_EXT_B_BGA1  I20
  U2D1   DV37  VSS<78>  SKX_EXT_B_BGA1  I20
  U2D1   DV39  VSS<77>  SKX_EXT_B_BGA1  I20
  U2D1   DV73  VSS<76>  SKX_EXT_B_BGA1  I20
  U2D1   DV77  VSS<75>  SKX_EXT_B_BGA1  I20
  U2D1   DV81  VSS<74>  SKX_EXT_B_BGA1  I20
  U2D1   DW2  VSS<1239>  SKX_EXT_B_BGA1  I20
  U2D1   DW8  VSS<58>  SKX_EXT_B_BGA1  I20
  U2D1   DW12  VSS<73>  SKX_EXT_B_BGA1  I20
  U2D1   DW20  VSS<72>  SKX_EXT_B_BGA1  I20
  U2D1   DW24  VSS<71>  SKX_EXT_B_BGA1  I20
  U2D1   DW28  VSS<70>  SKX_EXT_B_BGA1  I20
  U2D1   DW30  VSS<69>  SKX_EXT_B_BGA1  I20
  U2D1   DW34  VSS<68>  SKX_EXT_B_BGA1  I20
  U2D1   DW36  VSS<67>  SKX_EXT_B_BGA1  I20
  U2D1   DW40  VSS<66>  SKX_EXT_B_BGA1  I20
  U2D1   DW64  VSS<65>  SKX_EXT_B_BGA1  I20
  U2D1   DW66  VSS<64>  SKX_EXT_B_BGA1  I20
  U2D1   DW68  VSS<63>  SKX_EXT_B_BGA1  I20
  U2D1   DW70  VSS<62>  SKX_EXT_B_BGA1  I20
  U2D1   DW72  VSS<61>  SKX_EXT_B_BGA1  I20
  U2D1   DW74  VSS<60>  SKX_EXT_B_BGA1  I20
  U2D1   DW76  VSS<59>  SKX_EXT_B_BGA1  I20
  U2D1   DW82  VSS<57>  SKX_EXT_B_BGA1  I20
  U2D1   DW84  VSS<56>  SKX_EXT_B_BGA1  I20
  U2D1   DY5  VSS<55>  SKX_EXT_B_BGA1  I20
  U2D1   DY19  VSS<54>  SKX_EXT_B_BGA1  I20
  U2D1   DY23  VSS<53>  SKX_EXT_B_BGA1  I20
  U2D1   DY29  VSS<52>  SKX_EXT_B_BGA1  I20
  U2D1   DY35  VSS<51>  SKX_EXT_B_BGA1  I20
  U2D1   DY41  VSS<50>  SKX_EXT_B_BGA1  I20
  U2D1   DY45  VSS<1215>  SKX_EXT_B_BGA1  I20
  U2D1   DY47  VSS<1216>  SKX_EXT_B_BGA1  I20
  U2D1   DY49  VSS<1217>  SKX_EXT_B_BGA1  I20
  U2D1   DY51  VSS<1218>  SKX_EXT_B_BGA1  I20
  U2D1   DY53  VSS<1219>  SKX_EXT_B_BGA1  I20
  U2D1   DY55  VSS<1220>  SKX_EXT_B_BGA1  I20
  U2D1   DY57  VSS<1221>  SKX_EXT_B_BGA1  I20
  U2D1   DY59  VSS<1222>  SKX_EXT_B_BGA1  I20
  U2D1   DY61  VSS<1223>  SKX_EXT_B_BGA1  I20
  U2D1   DY63  VSS<1224>  SKX_EXT_B_BGA1  I20
  U2D1   DY71  VSS<49>  SKX_EXT_B_BGA1  I20
  U2D1   DY75  VSS<48>  SKX_EXT_B_BGA1  I20
  U2D1   DY85  VSS<1242>  SKX_EXT_B_BGA1  I20
  U2D1    E6  VSS<1154>  SKX_EXT_B_BGA1  I20
  U2D1    E8  VSS<1153>  SKX_EXT_B_BGA1  I20
  U2D1   E16  VSS<1152>  SKX_EXT_B_BGA1  I20
  U2D1   E18  VSS<1151>  SKX_EXT_B_BGA1  I20
  U2D1   E20  VSS<1150>  SKX_EXT_B_BGA1  I20
  U2D1   E22  VSS<1149>  SKX_EXT_B_BGA1  I20
  U2D1   E66  VSS<1228>  SKX_EXT_B_BGA1  I20
  U2D1   E72  VSS<1148>  SKX_EXT_B_BGA1  I20
  U2D1   E74  VSS<1147>  SKX_EXT_B_BGA1  I20
  U2D1   E76  VSS<1146>  SKX_EXT_B_BGA1  I20
  U2D1   E82  VSS<1244>  SKX_EXT_B_BGA1  I20
  U2D1   EA6  VSS<47>  SKX_EXT_B_BGA1  I20
  U2D1   EA14  VSS<1225>  SKX_EXT_B_BGA1  I20
  U2D1   EA16  VSS<45>  SKX_EXT_B_BGA1  I20
  U2D1   EA20  VSS<44>  SKX_EXT_B_BGA1  I20
  U2D1   EA22  VSS<43>  SKX_EXT_B_BGA1  I20
  U2D1   EA42  VSS<42>  SKX_EXT_B_BGA1  I20
  U2D1   EA64  VSS<41>  SKX_EXT_B_BGA1  I20
  U2D1   EA70  VSS<40>  SKX_EXT_B_BGA1  I20
  U2D1   EA76  VSS<39>  SKX_EXT_B_BGA1  I20
  U2D1   EA78  VSS<38>  SKX_EXT_B_BGA1  I20
  U2D1   EA80  VSS<37>  SKX_EXT_B_BGA1  I20
  U2D1   EA82  VSS<36>  SKX_EXT_B_BGA1  I20
  U2D1   EA84  VSS<1241>  SKX_EXT_B_BGA1  I20
  U2D1   EB13  VSS<35>  SKX_EXT_B_BGA1  I20
  U2D1   EB23  VSS<33>  SKX_EXT_B_BGA1  I20
  U2D1   EB25  VSS<32>  SKX_EXT_B_BGA1  I20
  U2D1   EB27  VSS<31>  SKX_EXT_B_BGA1  I20
  U2D1   EB29  VSS<30>  SKX_EXT_B_BGA1  I20
  U2D1   EB31  VSS<29>  SKX_EXT_B_BGA1  I20
  U2D1   EB33  VSS<28>  SKX_EXT_B_BGA1  I20
  U2D1   EB35  VSS<27>  SKX_EXT_B_BGA1  I20
  U2D1   EB37  VSS<26>  SKX_EXT_B_BGA1  I20
  U2D1   EB39  VSS<25>  SKX_EXT_B_BGA1  I20
  U2D1   EB41  VSS<24>  SKX_EXT_B_BGA1  I20
  U2D1   EB65  VSS<23>  SKX_EXT_B_BGA1  I20
  U2D1   EB69  VSS<22>  SKX_EXT_B_BGA1  I20
  U2D1   EB83  VSS<1240>  SKX_EXT_B_BGA1  I20
  U2D1   EC6  VSS<1237>  SKX_EXT_B_BGA1  I20
  U2D1   EC10  VSS<21>  SKX_EXT_B_BGA1  I20
  U2D1   EC42  VSS<1238>  SKX_EXT_B_BGA1  I20
  U2D1   EC70  VSS<20>  SKX_EXT_B_BGA1  I20
  U2D1   EC72  VSS<19>  SKX_EXT_B_BGA1  I20
  U2D1   EC74  VSS<18>  SKX_EXT_B_BGA1  I20
  U2D1   EC76  VSS<17>  SKX_EXT_B_BGA1  I20
  U2D1   EC82  VSS<1236>  SKX_EXT_B_BGA1  I20
  U2D1   ED7  VSS<1234>  SKX_EXT_B_BGA1  I20
  U2D1   ED11  VSS<16>  SKX_EXT_B_BGA1  I20
  U2D1   ED15  VSS<15>  SKX_EXT_B_BGA1  I20
  U2D1   ED23  VSS<14>  SKX_EXT_B_BGA1  I20
  U2D1   ED29  VSS<13>  SKX_EXT_B_BGA1  I20
  U2D1   ED35  VSS<12>  SKX_EXT_B_BGA1  I20
  U2D1   ED41  VSS<1235>  SKX_EXT_B_BGA1  I20
  U2D1   ED69  VSS<1229>  SKX_EXT_B_BGA1  I20
  U2D1   ED77  VSS<11>  SKX_EXT_B_BGA1  I20
  U2D1   ED81  VSS<1233>  SKX_EXT_B_BGA1  I20
  U2D1   EE8  VSS<1231>  SKX_EXT_B_BGA1  I20
  U2D1   EE24  VSS<10>  SKX_EXT_B_BGA1  I20
  U2D1   EE28  VSS<9>  SKX_EXT_B_BGA1  I20
  U2D1   EE30  VSS<8>  SKX_EXT_B_BGA1  I20
  U2D1   EE34  VSS<7>  SKX_EXT_B_BGA1  I20
  U2D1   EE36  VSS<6>  SKX_EXT_B_BGA1  I20
  U2D1   EE40  VSS<1232>  SKX_EXT_B_BGA1  I20
  U2D1   EE70  VSS<5>  SKX_EXT_B_BGA1  I20
  U2D1   EE76  VSS<4>  SKX_EXT_B_BGA1  I20
  U2D1   EE78  VSS<3>  SKX_EXT_B_BGA1  I20
  U2D1   EE80  VSS<1230>  SKX_EXT_B_BGA1  I20
  U2D1   EF71  VSS<2>  SKX_EXT_B_BGA1  I20
  U2D1   EF75  VSS<1>  SKX_EXT_B_BGA1  I20
  U2D1   EF79  VSS<0>  SKX_EXT_B_BGA1  I20
  U2D1    F5  VSS<1145>  SKX_EXT_B_BGA1  I20
  U2D1   F17  VSS<1144>  SKX_EXT_B_BGA1  I20
  U2D1   F19  VSS<1143>  SKX_EXT_B_BGA1  I20
  U2D1   F25  VSS<1142>  SKX_EXT_B_BGA1  I20
  U2D1   F31  VSS<1141>  SKX_EXT_B_BGA1  I20
  U2D1   F37  VSS<1140>  SKX_EXT_B_BGA1  I20
  U2D1   F43  VSS<1139>  SKX_EXT_B_BGA1  I20
  U2D1   F67  VSS<1138>  SKX_EXT_B_BGA1  I20
  U2D1   F69  VSS<1137>  SKX_EXT_B_BGA1  I20
  U2D1    G4  VSS<1136>  SKX_EXT_B_BGA1  I20
  U2D1    G8  VSS<1135>  SKX_EXT_B_BGA1  I20
  U2D1   G22  VSS<1134>  SKX_EXT_B_BGA1  I20
  U2D1   G24  VSS<1133>  SKX_EXT_B_BGA1  I20
  U2D1   G26  VSS<1132>  SKX_EXT_B_BGA1  I20
  U2D1   G30  VSS<1131>  SKX_EXT_B_BGA1  I20
  U2D1   G32  VSS<1130>  SKX_EXT_B_BGA1  I20
  U2D1   G36  VSS<1129>  SKX_EXT_B_BGA1  I20
  U2D1   G38  VSS<1128>  SKX_EXT_B_BGA1  I20
  U2D1   G42  VSS<1127>  SKX_EXT_B_BGA1  I20
  U2D1   G66  VSS<1126>  SKX_EXT_B_BGA1  I20
  U2D1   G70  VSS<1125>  SKX_EXT_B_BGA1  I20
  U2D1   G76  VSS<1124>  SKX_EXT_B_BGA1  I20
  U2D1   G78  VSS<1123>  SKX_EXT_B_BGA1  I20
  U2D1   G80  VSS<1122>  SKX_EXT_B_BGA1  I20
  U2D1   G82  VSS<1121>  SKX_EXT_B_BGA1  I20
  U2D1    H3  VSS<1120>  SKX_EXT_B_BGA1  I20
  U2D1   H11  VSS<1119>  SKX_EXT_B_BGA1  I20
  U2D1   H25  VSS<1118>  SKX_EXT_B_BGA1  I20
  U2D1   H27  VSS<1117>  SKX_EXT_B_BGA1  I20
  U2D1   H29  VSS<1116>  SKX_EXT_B_BGA1  I20
  U2D1   H31  VSS<1115>  SKX_EXT_B_BGA1  I20
  U2D1   H33  VSS<1114>  SKX_EXT_B_BGA1  I20
  U2D1   H35  VSS<1113>  SKX_EXT_B_BGA1  I20
  U2D1   H37  VSS<1112>  SKX_EXT_B_BGA1  I20
  U2D1   H39  VSS<1111>  SKX_EXT_B_BGA1  I20
  U2D1   H41  VSS<1110>  SKX_EXT_B_BGA1  I20
  U2D1   H45  VSS<153>  SKX_EXT_B_BGA1  I19
  U2D1   H47  VSS<190>  SKX_EXT_B_BGA1  I19
  U2D1   H49  VSS<219>  SKX_EXT_B_BGA1  I19
  U2D1   H51  VSS<233>  SKX_EXT_B_BGA1  I19
  U2D1   H53  VSS<304>  SKX_EXT_B_BGA1  I18
  U2D1   H55  VSS<352>  SKX_EXT_B_BGA1  I18
  U2D1   H57  VSS<379>  SKX_EXT_B_BGA1  I18
  U2D1   H59  VSS<399>  SKX_EXT_B_BGA1  I18
  U2D1   H61  VSS<407>  SKX_EXT_B_BGA1  I18
  U2D1   H63  VSS<428>  SKX_EXT_B_BGA1  I18
  U2D1   H65  VSS<1109>  SKX_EXT_B_BGA1  I20
  U2D1   H71  VSS<1108>  SKX_EXT_B_BGA1  I20
  U2D1   H75  VSS<1107>  SKX_EXT_B_BGA1  I20
  U2D1    J4  VSS<1105>  SKX_EXT_B_BGA1  I20
  U2D1   J12  VSS<1104>  SKX_EXT_B_BGA1  I20
  U2D1   J14  VSS<1103>  SKX_EXT_B_BGA1  I20
  U2D1   J16  VSS<46>  SKX_EXT_B_BGA1  I20
  U2D1   J22  VSS<1102>  SKX_EXT_B_BGA1  I20
  U2D1   J26  VSS<1101>  SKX_EXT_B_BGA1  I20
  U2D1   J28  VSS<1100>  SKX_EXT_B_BGA1  I20
  U2D1   J32  VSS<1099>  SKX_EXT_B_BGA1  I20
  U2D1   J34  VSS<1098>  SKX_EXT_B_BGA1  I20
  U2D1   J38  VSS<1097>  SKX_EXT_B_BGA1  I20
  U2D1   J40  VSS<1096>  SKX_EXT_B_BGA1  I20
  U2D1   J72  VSS<1095>  SKX_EXT_B_BGA1  I20
  U2D1   J74  VSS<1094>  SKX_EXT_B_BGA1  I20
  U2D1   J76  VSS<1093>  SKX_EXT_B_BGA1  I21
  U2D1   J82  VSS<1092>  SKX_EXT_B_BGA1  I21
  U2D1   J84  VSS<1091>  SKX_EXT_B_BGA1  I21
  U2D1   J86  VSS<1243>  SKX_EXT_B_BGA1  I20
  U2D1    K1  VSS<1090>  SKX_EXT_B_BGA1  I21
  U2D1   K11  VSS<1089>  SKX_EXT_B_BGA1  I21
  U2D1   K13  VSS<1088>  SKX_EXT_B_BGA1  I21
  U2D1   K17  VSS<1087>  SKX_EXT_B_BGA1  I21
  U2D1   K27  VSS<1085>  SKX_EXT_B_BGA1  I21
  U2D1   K33  VSS<1084>  SKX_EXT_B_BGA1  I21
  U2D1   K39  VSS<1083>  SKX_EXT_B_BGA1  I21
  U2D1   K65  VSS<1082>  SKX_EXT_B_BGA1  I21
  U2D1   K67  VSS<1081>  SKX_EXT_B_BGA1  I21
  U2D1   K69  VSS<1080>  SKX_EXT_B_BGA1  I21
  U2D1   K71  VSS<1079>  SKX_EXT_B_BGA1  I21
  U2D1   K73  VSS<1078>  SKX_EXT_B_BGA1  I21
  U2D1   K77  VSS<1077>  SKX_EXT_B_BGA1  I21
  U2D1   K81  VSS<1076>  SKX_EXT_B_BGA1  I21
  U2D1   K83  VSS<1075>  SKX_EXT_B_BGA1  I21
  U2D1   K85  VSS<1074>  SKX_EXT_B_BGA1  I21
  U2D1    L2  VSS<1072>  SKX_EXT_B_BGA1  I21
  U2D1    L6  VSS<1071>  SKX_EXT_B_BGA1  I21
  U2D1    L8  VSS<1226>  SKX_EXT_B_BGA1  I20
  U2D1   L10  VSS<1073>  SKX_EXT_B_BGA1  I21
  U2D1   L20  VSS<1070>  SKX_EXT_B_BGA1  I21
  U2D1   L22  VSS<1069>  SKX_EXT_B_BGA1  I21
  U2D1   L72  VSS<1068>  SKX_EXT_B_BGA1  I21
  U2D1   L78  VSS<1067>  SKX_EXT_B_BGA1  I21
  U2D1   L80  VSS<1066>  SKX_EXT_B_BGA1  I21
  U2D1   L82  VSS<1065>  SKX_EXT_B_BGA1  I21
  U2D1   M15  VSS<1062>  SKX_EXT_B_BGA1  I21
  U2D1   M17  VSS<1061>  SKX_EXT_B_BGA1  I21
  U2D1   M19  VSS<1060>  SKX_EXT_B_BGA1  I21
  U2D1   M23  VSS<1059>  SKX_EXT_B_BGA1  I21
  U2D1   M25  VSS<1058>  SKX_EXT_B_BGA1  I21
  U2D1   M27  VSS<1057>  SKX_EXT_B_BGA1  I21
  U2D1   M29  VSS<1056>  SKX_EXT_B_BGA1  I21
  U2D1   M31  VSS<1055>  SKX_EXT_B_BGA1  I21
  U2D1   M33  VSS<1054>  SKX_EXT_B_BGA1  I21
  U2D1   M35  VSS<1053>  SKX_EXT_B_BGA1  I21
  U2D1   M37  VSS<1052>  SKX_EXT_B_BGA1  I21
  U2D1   M39  VSS<1051>  SKX_EXT_B_BGA1  I21
  U2D1   M41  VSS<1050>  SKX_EXT_B_BGA1  I21
  U2D1   M43  VSS<1049>  SKX_EXT_B_BGA1  I21
  U2D1   M65  VSS<1048>  SKX_EXT_B_BGA1  I21
  U2D1   M71  VSS<1047>  SKX_EXT_B_BGA1  I21
  U2D1   M79  VSS<1046>  SKX_EXT_B_BGA1  I21
  U2D1   M83  VSS<1045>  SKX_EXT_B_BGA1  I21
  U2D1   M85  VSS<1044>  SKX_EXT_B_BGA1  I21
  U2D1    N4  VSS<1033>  SKX_EXT_B_BGA1  I21
  U2D1    N6  VSS<1040>  SKX_EXT_B_BGA1  I21
  U2D1    N8  VSS<1032>  SKX_EXT_B_BGA1  I21
  U2D1   N20  VSS<1042>  SKX_EXT_B_BGA1  I21
  U2D1   N22  VSS<1041>  SKX_EXT_B_BGA1  I21
  U2D1   N66  VSS<1039>  SKX_EXT_B_BGA1  I21
  U2D1   N70  VSS<1038>  SKX_EXT_B_BGA1  I21
  U2D1   N72  VSS<1037>  SKX_EXT_B_BGA1  I21
  U2D1   N74  VSS<1036>  SKX_EXT_B_BGA1  I21
  U2D1   N76  VSS<1035>  SKX_EXT_B_BGA1  I21
  U2D1   N78  VSS<1034>  SKX_EXT_B_BGA1  I21
  U2D1   P11  VSS<1031>  SKX_EXT_B_BGA1  I21
  U2D1   P15  VSS<1030>  SKX_EXT_B_BGA1  I21
  U2D1   P27  VSS<1029>  SKX_EXT_B_BGA1  I21
  U2D1   P33  VSS<1028>  SKX_EXT_B_BGA1  I21
  U2D1   P39  VSS<1027>  SKX_EXT_B_BGA1  I21
  U2D1   P45  VSS<429>  SKX_EXT_B_BGA1  I18
  U2D1   P47  VSS<453>  SKX_EXT_B_BGA1  I18
  U2D1   P49  VSS<454>  SKX_EXT_B_BGA1  I17
  U2D1   P51  VSS<476>  SKX_EXT_B_BGA1  I17
  U2D1   P53  VSS<483>  SKX_EXT_B_BGA1  I17
  U2D1   P55  VSS<545>  SKX_EXT_B_BGA1  I17
  U2D1   P57  VSS<567>  SKX_EXT_B_BGA1  I17
  U2D1   P59  VSS<578>  SKX_EXT_B_BGA1  I17
  U2D1   P61  VSS<594>  SKX_EXT_B_BGA1  I17
  U2D1   P63  VSS<732>  SKX_EXT_B_BGA1  I23
  U2D1   P67  VSS<1026>  SKX_EXT_B_BGA1  I21
  U2D1   P69  VSS<1025>  SKX_EXT_B_BGA1  I21
  U2D1   P71  VSS<1024>  SKX_EXT_B_BGA1  I21
  U2D1   P81  VSS<1023>  SKX_EXT_B_BGA1  I21
  U2D1   P83  VSS<1022>  SKX_EXT_B_BGA1  I21
  U2D1    R2  VSS<1019>  SKX_EXT_B_BGA1  I21
  U2D1    R4  VSS<1018>  SKX_EXT_B_BGA1  I21
  U2D1   R14  VSS<1021>  SKX_EXT_B_BGA1  I21
  U2D1   R18  VSS<1020>  SKX_EXT_B_BGA1  I21
  U2D1   R22  VSS<1017>  SKX_EXT_B_BGA1  I21
  U2D1   R26  VSS<1016>  SKX_EXT_B_BGA1  I21
  U2D1   R28  VSS<1015>  SKX_EXT_B_BGA1  I21
  U2D1   R32  VSS<1014>  SKX_EXT_B_BGA1  I21
  U2D1   R34  VSS<1013>  SKX_EXT_B_BGA1  I21
  U2D1   R38  VSS<1012>  SKX_EXT_B_BGA1  I21
  U2D1   R40  VSS<1011>  SKX_EXT_B_BGA1  I21
  U2D1   R68  VSS<1010>  SKX_EXT_B_BGA1  I21
  U2D1   R72  VSS<1009>  SKX_EXT_B_BGA1  I21
  U2D1   R78  VSS<1008>  SKX_EXT_B_BGA1  I21
  U2D1   R86  VSS<1007>  SKX_EXT_B_BGA1  I21
  U2D1   T13  VSS<1006>  SKX_EXT_B_BGA1  I21
  U2D1   T17  VSS<1005>  SKX_EXT_B_BGA1  I21
  U2D1   T25  VSS<1004>  SKX_EXT_B_BGA1  I21
  U2D1   T29  VSS<1003>  SKX_EXT_B_BGA1  I21
  U2D1   T31  VSS<1002>  SKX_EXT_B_BGA1  I21
  U2D1   T35  VSS<1001>  SKX_EXT_B_BGA1  I21
  U2D1   T37  VSS<1000>  SKX_EXT_B_BGA1  I21
  U2D1   T41  VSS<999>  SKX_EXT_B_BGA1  I21
  U2D1   T65  VSS<998>  SKX_EXT_B_BGA1  I21
  U2D1   T73  VSS<997>  SKX_EXT_B_BGA1  I21
  U2D1   T77  VSS<996>  SKX_EXT_B_BGA1  I21
  U2D1   T83  VSS<995>  SKX_EXT_B_BGA1  I21
  U2D1   T85  VSS<994>  SKX_EXT_B_BGA1  I21
  U2D1    U2  VSS<993>  SKX_EXT_B_BGA1  I21
  U2D1    U4  VSS<992>  SKX_EXT_B_BGA1  I21
  U2D1    U6  VSS<991>  SKX_EXT_B_BGA1  I21
  U2D1   U20  VSS<990>  SKX_EXT_B_BGA1  I21
  U2D1   U22  VSS<989>  SKX_EXT_B_BGA1  I21
  U2D1   U24  VSS<988>  SKX_EXT_B_BGA1  I21
  U2D1   U30  VSS<987>  SKX_EXT_B_BGA1  I21
  U2D1   U36  VSS<986>  SKX_EXT_B_BGA1  I21
  U2D1   U42  VSS<985>  SKX_EXT_B_BGA1  I21
  U2D1   U68  VSS<984>  SKX_EXT_B_BGA1  I21
  U2D1   U70  VSS<983>  SKX_EXT_B_BGA1  I21
  U2D1   U74  VSS<982>  SKX_EXT_B_BGA1  I21
  U2D1   U76  VSS<981>  SKX_EXT_B_BGA1  I21
  U2D1   U78  VSS<980>  SKX_EXT_B_BGA1  I21
  U2D1   U80  VSS<979>  SKX_EXT_B_BGA1  I21
  U2D1   U86  VSS<978>  SKX_EXT_B_BGA1  I21
  U2D1    V1  VSS<977>  SKX_EXT_B_BGA1  I21
  U2D1    V5  VSS<976>  SKX_EXT_B_BGA1  I21
  U2D1    V9  VSS<975>  SKX_EXT_B_BGA1  I21
  U2D1   V11  VSS<1227>  SKX_EXT_B_BGA1  I20
  U2D1   V13  VSS<974>  SKX_EXT_B_BGA1  I21
  U2D1   V15  VSS<973>  SKX_EXT_B_BGA1  I21
  U2D1   V21  VSS<972>  SKX_EXT_B_BGA1  I21
  U2D1   V23  VSS<971>  SKX_EXT_B_BGA1  I21
  U2D1   V43  VSS<970>  SKX_EXT_B_BGA1  I21
  U2D1   V73  VSS<969>  SKX_EXT_B_BGA1  I21
  U2D1   V75  VSS<968>  SKX_EXT_B_BGA1  I21
  U2D1   V77  VSS<967>  SKX_EXT_B_BGA1  I21
  U2D1   V83  VSS<966>  SKX_EXT_B_BGA1  I21
  U2D1    W8  VSS<965>  SKX_EXT_B_BGA1  I21
  U2D1   W12  VSS<963>  SKX_EXT_B_BGA1  I21
  U2D1   W22  VSS<962>  SKX_EXT_B_BGA1  I21
  U2D1   W24  VSS<961>  SKX_EXT_B_BGA1  I21
  U2D1   W26  VSS<960>  SKX_EXT_B_BGA1  I21
  U2D1   W28  VSS<959>  SKX_EXT_B_BGA1  I21
  U2D1   W30  VSS<958>  SKX_EXT_B_BGA1  I21
  U2D1   W32  VSS<957>  SKX_EXT_B_BGA1  I21
  U2D1   W34  VSS<956>  SKX_EXT_B_BGA1  I21
  U2D1   W36  VSS<955>  SKX_EXT_B_BGA1  I21
  U2D1   W38  VSS<954>  SKX_EXT_B_BGA1  I21
  U2D1   W40  VSS<953>  SKX_EXT_B_BGA1  I21
  U2D1   W42  VSS<952>  SKX_EXT_B_BGA1  I21
  U2D1   W68  VSS<951>  SKX_EXT_B_BGA1  I21
  U2D1   W74  VSS<950>  SKX_EXT_B_BGA1  I21
  U2D1   W78  VSS<949>  SKX_EXT_B_BGA1  I21
  U2D1   W82  VSS<948>  SKX_EXT_B_BGA1  I21
  U2D1    Y5  VSS<945>  SKX_EXT_B_BGA1  I21
  U2D1    Y7  VSS<943>  SKX_EXT_B_BGA1  I21
  U2D1    Y9  VSS<942>  SKX_EXT_B_BGA1  I21
  U2D1   Y15  VSS<947>  SKX_EXT_B_BGA1  I21
  U2D1   Y17  VSS<946>  SKX_EXT_B_BGA1  I21
  U2D1   Y67  VSS<944>  SKX_EXT_B_BGA1  I21
  U2D1   Y71  VSS<941>  SKX_EXT_B_BGA1  I21
  U2D1   Y73  VSS<940>  SKX_EXT_B_BGA1  I21
  U2D1   Y79  VSS<939>  SKX_EXT_B_BGA1  I21
  U2D1   Y81  VSS<938>  SKX_EXT_B_BGA1  I21
  U2D1   Y83  VSS<937>  SKX_EXT_B_BGA1  I21
  U2D1   Y85  VSS<936>  SKX_EXT_B_BGA1  I21
  U2M1     2    GND  NC7SB3157   I255
  U2T1     8    GND  PI3B3257A_TSSOPLF  I75
  U2T1    15     EN  PI3B3257A_TSSOPLF  I75
  U2T4     7  GND<0>  GTL2014_SM  I30
  U2T4     8  GND<1>  GTL2014_SM  I30
  U2T4    11  GND<2>  GTL2014_SM  I30
  U3P1     7  GND<0>  GTL2014_SM  I42
  U3P1     8  GND<1>  GTL2014_SM  I42
  U3P1    11  GND<2>  GTL2014_SM  I42
  U3P2     7  GND<0>  GTL2014_SM   I1
  U3P2     8  GND<1>  GTL2014_SM   I1
  U3P2    11  GND<2>  GTL2014_SM   I1
  U3T1    10    GND  W25Q256_XSOI  I165
  U4B1     1  GND<1>  MAX9634_SOT  I120
  U4B1     2  GND<0>  MAX9634_SOT  I120
  U4C1     1  GND<0>  ADM4073_SM  I53
  U4C1     2  GND<1>  ADM4073_SM  I53
  U4C2     7  GND<0>  GTL2014_SM  I46
  U4C2     8  GND<1>  GTL2014_SM  I46
  U4C2    11  GND<2>  GTL2014_SM  I46
  U4F1     1  GND<1>  MAX9634_SOT  I97
  U4F1     2  GND<0>  MAX9634_SOT  I97
  U5D1   A26  VSS<1185>  SKX_EXT_B_BGA1  I20
  U5D1   A30  VSS<1184>  SKX_EXT_B_BGA1  I20
  U5D1   A32  VSS<1183>  SKX_EXT_B_BGA1  I20
  U5D1   A36  VSS<1182>  SKX_EXT_B_BGA1  I20
  U5D1   A38  VSS<1181>  SKX_EXT_B_BGA1  I20
  U5D1   A42  VSS<1252>  SKX_EXT_B_BGA1  I20
  U5D1   AA4  VSS<935>  SKX_EXT_B_BGA1  I21
  U5D1   AA16  VSS<934>  SKX_EXT_B_BGA1  I21
  U5D1   AA18  VSS<933>  SKX_EXT_B_BGA1  I22
  U5D1   AA22  VSS<932>  SKX_EXT_B_BGA1  I22
  U5D1   AA24  VSS<931>  SKX_EXT_B_BGA1  I22
  U5D1   AA30  VSS<930>  SKX_EXT_B_BGA1  I22
  U5D1   AA36  VSS<929>  SKX_EXT_B_BGA1  I22
  U5D1   AA42  VSS<928>  SKX_EXT_B_BGA1  I22
  U5D1   AA64  VSS<927>  SKX_EXT_B_BGA1  I22
  U5D1   AA66  VSS<926>  SKX_EXT_B_BGA1  I22
  U5D1   AA68  VSS<925>  SKX_EXT_B_BGA1  I22
  U5D1   AA76  VSS<924>  SKX_EXT_B_BGA1  I22
  U5D1   AA78  VSS<923>  SKX_EXT_B_BGA1  I22
  U5D1   AA80  VSS<922>  SKX_EXT_B_BGA1  I22
  U5D1   AA82  VSS<921>  SKX_EXT_B_BGA1  I22
  U5D1   AB1  VSS<920>  SKX_EXT_B_BGA1  I22
  U5D1   AB5  VSS<919>  SKX_EXT_B_BGA1  I22
  U5D1   AB11  VSS<918>  SKX_EXT_B_BGA1  I22
  U5D1   AB21  VSS<917>  SKX_EXT_B_BGA1  I22
  U5D1   AB23  VSS<916>  SKX_EXT_B_BGA1  I22
  U5D1   AB25  VSS<915>  SKX_EXT_B_BGA1  I22
  U5D1   AB29  VSS<914>  SKX_EXT_B_BGA1  I22
  U5D1   AB31  VSS<913>  SKX_EXT_B_BGA1  I22
  U5D1   AB35  VSS<912>  SKX_EXT_B_BGA1  I22
  U5D1   AB37  VSS<911>  SKX_EXT_B_BGA1  I22
  U5D1   AB41  VSS<910>  SKX_EXT_B_BGA1  I22
  U5D1   AB65  VSS<909>  SKX_EXT_B_BGA1  I22
  U5D1   AB69  VSS<908>  SKX_EXT_B_BGA1  I22
  U5D1   AB73  VSS<907>  SKX_EXT_B_BGA1  I22
  U5D1   AB79  VSS<906>  SKX_EXT_B_BGA1  I22
  U5D1   AB83  VSS<905>  SKX_EXT_B_BGA1  I22
  U5D1   AB85  VSS<904>  SKX_EXT_B_BGA1  I22
  U5D1   AC18  VSS<903>  SKX_EXT_B_BGA1  I22
  U5D1   AC22  VSS<902>  SKX_EXT_B_BGA1  I22
  U5D1   AC26  VSS<901>  SKX_EXT_B_BGA1  I22
  U5D1   AC28  VSS<900>  SKX_EXT_B_BGA1  I22
  U5D1   AC32  VSS<899>  SKX_EXT_B_BGA1  I22
  U5D1   AC34  VSS<898>  SKX_EXT_B_BGA1  I22
  U5D1   AC38  VSS<897>  SKX_EXT_B_BGA1  I22
  U5D1   AC40  VSS<896>  SKX_EXT_B_BGA1  I22
  U5D1   AC48  VSS<733>  SKX_EXT_B_BGA1  I23
  U5D1   AC50  VSS<767>  SKX_EXT_B_BGA1  I23
  U5D1   AC52  VSS<858>  SKX_EXT_B_BGA1  I22
  U5D1   AC54  VSS<869>  SKX_EXT_B_BGA1  I22
  U5D1   AC56  VSS<964>  SKX_EXT_B_BGA1  I21
  U5D1   AC58  VSS<1186>  SKX_EXT_B_BGA1  I20
  U5D1   AC60  VSS<1187>  SKX_EXT_B_BGA1  I20
  U5D1   AC62  VSS<1188>  SKX_EXT_B_BGA1  I20
  U5D1   AC64  VSS<895>  SKX_EXT_B_BGA1  I22
  U5D1   AC70  VSS<894>  SKX_EXT_B_BGA1  I22
  U5D1   AC72  VSS<893>  SKX_EXT_B_BGA1  I22
  U5D1   AC78  VSS<892>  SKX_EXT_B_BGA1  I22
  U5D1   AC84  VSS<891>  SKX_EXT_B_BGA1  I22
  U5D1   AC86  VSS<890>  SKX_EXT_B_BGA1  I22
  U5D1   AD3  VSS<889>  SKX_EXT_B_BGA1  I22
  U5D1   AD7  VSS<888>  SKX_EXT_B_BGA1  I22
  U5D1   AD9  VSS<887>  SKX_EXT_B_BGA1  I22
  U5D1   AD11  VSS<886>  SKX_EXT_B_BGA1  I22
  U5D1   AD13  VSS<885>  SKX_EXT_B_BGA1  I22
  U5D1   AD15  VSS<884>  SKX_EXT_B_BGA1  I22
  U5D1   AD19  VSS<883>  SKX_EXT_B_BGA1  I22
  U5D1   AD21  VSS<882>  SKX_EXT_B_BGA1  I22
  U5D1   AD27  VSS<881>  SKX_EXT_B_BGA1  I22
  U5D1   AD33  VSS<880>  SKX_EXT_B_BGA1  I22
  U5D1   AD39  VSS<879>  SKX_EXT_B_BGA1  I22
  U5D1   AD43  VSS<878>  SKX_EXT_B_BGA1  I22
  U5D1   AD71  VSS<877>  SKX_EXT_B_BGA1  I22
  U5D1   AD73  VSS<876>  SKX_EXT_B_BGA1  I22
  U5D1   AD75  VSS<875>  SKX_EXT_B_BGA1  I22
  U5D1   AD81  VSS<874>  SKX_EXT_B_BGA1  I22
  U5D1   AD83  VSS<873>  SKX_EXT_B_BGA1  I22
  U5D1   AD85  VSS<872>  SKX_EXT_B_BGA1  I22
  U5D1   AE4  VSS<871>  SKX_EXT_B_BGA1  I22
  U5D1   AE8  VSS<870>  SKX_EXT_B_BGA1  I22
  U5D1   AE16  VSS<868>  SKX_EXT_B_BGA1  I22
  U5D1   AE38  VSS<867>  SKX_EXT_B_BGA1  I22
  U5D1   AE40  VSS<866>  SKX_EXT_B_BGA1  I22
  U5D1   AE42  VSS<865>  SKX_EXT_B_BGA1  I22
  U5D1   AE64  VSS<864>  SKX_EXT_B_BGA1  I22
  U5D1   AE66  VSS<863>  SKX_EXT_B_BGA1  I22
  U5D1   AE68  VSS<862>  SKX_EXT_B_BGA1  I22
  U5D1   AE70  VSS<861>  SKX_EXT_B_BGA1  I22
  U5D1   AE78  VSS<860>  SKX_EXT_B_BGA1  I22
  U5D1   AF1  VSS<859>  SKX_EXT_B_BGA1  I22
  U5D1   AF9  VSS<857>  SKX_EXT_B_BGA1  I22
  U5D1   AF21  VSS<856>  SKX_EXT_B_BGA1  I22
  U5D1   AF23  VSS<855>  SKX_EXT_B_BGA1  I22
  U5D1   AF25  VSS<854>  SKX_EXT_B_BGA1  I22
  U5D1   AF27  VSS<853>  SKX_EXT_B_BGA1  I22
  U5D1   AF29  VSS<852>  SKX_EXT_B_BGA1  I22
  U5D1   AF31  VSS<851>  SKX_EXT_B_BGA1  I22
  U5D1   AF33  VSS<850>  SKX_EXT_B_BGA1  I22
  U5D1   AF37  VSS<849>  SKX_EXT_B_BGA1  I22
  U5D1   AF39  VSS<848>  SKX_EXT_B_BGA1  I22
  U5D1   AF41  VSS<847>  SKX_EXT_B_BGA1  I22
  U5D1   AF73  VSS<846>  SKX_EXT_B_BGA1  I22
  U5D1   AF77  VSS<845>  SKX_EXT_B_BGA1  I22
  U5D1   AF83  VSS<844>  SKX_EXT_B_BGA1  I22
  U5D1   AF85  VSS<843>  SKX_EXT_B_BGA1  I22
  U5D1   AG12  VSS<842>  SKX_EXT_B_BGA1  I22
  U5D1   AG14  VSS<841>  SKX_EXT_B_BGA1  I22
  U5D1   AG18  VSS<840>  SKX_EXT_B_BGA1  I22
  U5D1   AG36  VSS<839>  SKX_EXT_B_BGA1  I22
  U5D1   AG64  VSS<838>  SKX_EXT_B_BGA1  I22
  U5D1   AG70  VSS<837>  SKX_EXT_B_BGA1  I22
  U5D1   AG74  VSS<836>  SKX_EXT_B_BGA1  I22
  U5D1   AG76  VSS<835>  SKX_EXT_B_BGA1  I22
  U5D1   AG78  VSS<834>  SKX_EXT_B_BGA1  I22
  U5D1   AG80  VSS<833>  SKX_EXT_B_BGA1  I22
  U5D1   AH1  VSS<832>  SKX_EXT_B_BGA1  I22
  U5D1   AH5  VSS<831>  SKX_EXT_B_BGA1  I22
  U5D1   AH21  VSS<830>  SKX_EXT_B_BGA1  I22
  U5D1   AH27  VSS<829>  SKX_EXT_B_BGA1  I22
  U5D1   AH33  VSS<828>  SKX_EXT_B_BGA1  I22
  U5D1   AH35  VSS<827>  SKX_EXT_B_BGA1  I22
  U5D1   AH45  VSS<826>  SKX_EXT_B_BGA1  I22
  U5D1   AH47  VSS<825>  SKX_EXT_B_BGA1  I22
  U5D1   AH49  VSS<824>  SKX_EXT_B_BGA1  I22
  U5D1   AH51  VSS<823>  SKX_EXT_B_BGA1  I22
  U5D1   AH53  VSS<822>  SKX_EXT_B_BGA1  I22
  U5D1   AH59  VSS<821>  SKX_EXT_B_BGA1  I22
  U5D1   AH61  VSS<820>  SKX_EXT_B_BGA1  I22
  U5D1   AH65  VSS<819>  SKX_EXT_B_BGA1  I22
  U5D1   AH69  VSS<818>  SKX_EXT_B_BGA1  I22
  U5D1   AH75  VSS<817>  SKX_EXT_B_BGA1  I22
  U5D1   AH77  VSS<816>  SKX_EXT_B_BGA1  I22
  U5D1   AH83  VSS<815>  SKX_EXT_B_BGA1  I22
  U5D1   AJ4  VSS<1189>  SKX_EXT_B_BGA1  I20
  U5D1   AJ8  VSS<814>  SKX_EXT_B_BGA1  I22
  U5D1   AJ22  VSS<813>  SKX_EXT_B_BGA1  I22
  U5D1   AJ26  VSS<812>  SKX_EXT_B_BGA1  I22
  U5D1   AJ28  VSS<811>  SKX_EXT_B_BGA1  I22
  U5D1   AJ32  VSS<810>  SKX_EXT_B_BGA1  I22
  U5D1   AJ34  VSS<809>  SKX_EXT_B_BGA1  I22
  U5D1   AJ46  VSS<808>  SKX_EXT_B_BGA1  I22
  U5D1   AJ48  VSS<807>  SKX_EXT_B_BGA1  I22
  U5D1   AJ50  VSS<806>  SKX_EXT_B_BGA1  I22
  U5D1   AJ52  VSS<805>  SKX_EXT_B_BGA1  I22
  U5D1   AJ54  VSS<804>  SKX_EXT_B_BGA1  I22
  U5D1   AJ66  VSS<803>  SKX_EXT_B_BGA1  I22
  U5D1   AJ68  VSS<802>  SKX_EXT_B_BGA1  I22
  U5D1   AJ74  VSS<801>  SKX_EXT_B_BGA1  I22
  U5D1   AJ78  VSS<800>  SKX_EXT_B_BGA1  I22
  U5D1   AJ82  VSS<799>  SKX_EXT_B_BGA1  I22
  U5D1   AJ86  VSS<798>  SKX_EXT_B_BGA1  I22
  U5D1   AK9  VSS<797>  SKX_EXT_B_BGA1  I22
  U5D1   AK13  VSS<796>  SKX_EXT_B_BGA1  I22
  U5D1   AK19  VSS<795>  SKX_EXT_B_BGA1  I22
  U5D1   AK23  VSS<794>  SKX_EXT_B_BGA1  I22
  U5D1   AK25  VSS<793>  SKX_EXT_B_BGA1  I22
  U5D1   AK29  VSS<792>  SKX_EXT_B_BGA1  I22
  U5D1   AK31  VSS<791>  SKX_EXT_B_BGA1  I22
  U5D1   AK33  VSS<790>  SKX_EXT_B_BGA1  I22
  U5D1   AK55  VSS<789>  SKX_EXT_B_BGA1  I22
  U5D1   AK65  VSS<788>  SKX_EXT_B_BGA1  I22
  U5D1   AK67  VSS<787>  SKX_EXT_B_BGA1  I22
  U5D1   AK73  VSS<786>  SKX_EXT_B_BGA1  I22
  U5D1   AK79  VSS<785>  SKX_EXT_B_BGA1  I22
  U5D1   AK81  VSS<784>  SKX_EXT_B_BGA1  I22
  U5D1   AK83  VSS<783>  SKX_EXT_B_BGA1  I22
  U5D1   AK85  VSS<782>  SKX_EXT_B_BGA1  I22
  U5D1   AL4  VSS<781>  SKX_EXT_B_BGA1  I22
  U5D1   AL10  VSS<780>  SKX_EXT_B_BGA1  I22
  U5D1   AL24  VSS<779>  SKX_EXT_B_BGA1  I22
  U5D1   AL30  VSS<778>  SKX_EXT_B_BGA1  I22
  U5D1   AL32  VSS<777>  SKX_EXT_B_BGA1  I22
  U5D1   AL56  VSS<776>  SKX_EXT_B_BGA1  I22
  U5D1   AL64  VSS<775>  SKX_EXT_B_BGA1  I22
  U5D1   AL68  VSS<774>  SKX_EXT_B_BGA1  I22
  U5D1   AL76  VSS<773>  SKX_EXT_B_BGA1  I23
  U5D1   AL78  VSS<772>  SKX_EXT_B_BGA1  I23
  U5D1   AL80  VSS<771>  SKX_EXT_B_BGA1  I23
  U5D1   AL82  VSS<770>  SKX_EXT_B_BGA1  I23
  U5D1   AL86  VSS<769>  SKX_EXT_B_BGA1  I23
  U5D1   AM1  VSS<768>  SKX_EXT_B_BGA1  I23
  U5D1   AM31  VSS<766>  SKX_EXT_B_BGA1  I23
  U5D1   AM57  VSS<765>  SKX_EXT_B_BGA1  I23
  U5D1   AM63  VSS<764>  SKX_EXT_B_BGA1  I23
  U5D1   AM69  VSS<763>  SKX_EXT_B_BGA1  I23
  U5D1   AM73  VSS<762>  SKX_EXT_B_BGA1  I23
  U5D1   AM79  VSS<761>  SKX_EXT_B_BGA1  I23
  U5D1   AM83  VSS<760>  SKX_EXT_B_BGA1  I23
  U5D1   AN2  VSS<759>  SKX_EXT_B_BGA1  I23
  U5D1   AN6  VSS<758>  SKX_EXT_B_BGA1  I23
  U5D1   AN28  VSS<757>  SKX_EXT_B_BGA1  I23
  U5D1   AN58  VSS<756>  SKX_EXT_B_BGA1  I23
  U5D1   AN78  VSS<755>  SKX_EXT_B_BGA1  I23
  U5D1   AP5  VSS<754>  SKX_EXT_B_BGA1  I23
  U5D1   AP9  VSS<753>  SKX_EXT_B_BGA1  I23
  U5D1   AP13  VSS<752>  SKX_EXT_B_BGA1  I23
  U5D1   AP19  VSS<751>  SKX_EXT_B_BGA1  I23
  U5D1   AP31  VSS<750>  SKX_EXT_B_BGA1  I23
  U5D1   AP59  VSS<749>  SKX_EXT_B_BGA1  I23
  U5D1   AP63  VSS<748>  SKX_EXT_B_BGA1  I23
  U5D1   AP65  VSS<747>  SKX_EXT_B_BGA1  I23
  U5D1   AP67  VSS<746>  SKX_EXT_B_BGA1  I23
  U5D1   AP69  VSS<745>  SKX_EXT_B_BGA1  I23
  U5D1   AP73  VSS<744>  SKX_EXT_B_BGA1  I23
  U5D1   AP75  VSS<743>  SKX_EXT_B_BGA1  I23
  U5D1   AP81  VSS<742>  SKX_EXT_B_BGA1  I23
  U5D1   AP83  VSS<741>  SKX_EXT_B_BGA1  I23
  U5D1   AP85  VSS<740>  SKX_EXT_B_BGA1  I23
  U5D1   AR6  VSS<1190>  SKX_EXT_B_BGA1  I20
  U5D1   AR10  VSS<739>  SKX_EXT_B_BGA1  I23
  U5D1   AR24  VSS<738>  SKX_EXT_B_BGA1  I23
  U5D1   AR30  VSS<737>  SKX_EXT_B_BGA1  I23
  U5D1   AR60  VSS<736>  SKX_EXT_B_BGA1  I23
  U5D1   AR72  VSS<735>  SKX_EXT_B_BGA1  I23
  U5D1   AR78  VSS<734>  SKX_EXT_B_BGA1  I23
  U5D1   AT15  VSS<731>  SKX_EXT_B_BGA1  I23
  U5D1   AT17  VSS<730>  SKX_EXT_B_BGA1  I23
  U5D1   AT21  VSS<729>  SKX_EXT_B_BGA1  I23
  U5D1   AT27  VSS<728>  SKX_EXT_B_BGA1  I23
  U5D1   AT61  VSS<727>  SKX_EXT_B_BGA1  I23
  U5D1   AT63  VSS<726>  SKX_EXT_B_BGA1  I23
  U5D1   AT69  VSS<725>  SKX_EXT_B_BGA1  I23
  U5D1   AT73  VSS<724>  SKX_EXT_B_BGA1  I23
  U5D1   AT77  VSS<723>  SKX_EXT_B_BGA1  I23
  U5D1   AT83  VSS<722>  SKX_EXT_B_BGA1  I23
  U5D1   AT85  VSS<721>  SKX_EXT_B_BGA1  I23
  U5D1   AU2  VSS<720>  SKX_EXT_B_BGA1  I23
  U5D1   AU6  VSS<719>  SKX_EXT_B_BGA1  I23
  U5D1   AU26  VSS<718>  SKX_EXT_B_BGA1  I23
  U5D1   AU28  VSS<717>  SKX_EXT_B_BGA1  I23
  U5D1   AU62  VSS<716>  SKX_EXT_B_BGA1  I23
  U5D1   AU64  VSS<715>  SKX_EXT_B_BGA1  I23
  U5D1   AU68  VSS<714>  SKX_EXT_B_BGA1  I23
  U5D1   AU74  VSS<713>  SKX_EXT_B_BGA1  I23
  U5D1   AU76  VSS<712>  SKX_EXT_B_BGA1  I23
  U5D1   AU78  VSS<711>  SKX_EXT_B_BGA1  I23
  U5D1   AU80  VSS<710>  SKX_EXT_B_BGA1  I23
  U5D1   AU84  VSS<709>  SKX_EXT_B_BGA1  I23
  U5D1   AU86  VSS<708>  SKX_EXT_B_BGA1  I23
  U5D1   AV1  VSS<707>  SKX_EXT_B_BGA1  I23
  U5D1   AV3  VSS<706>  SKX_EXT_B_BGA1  I23
  U5D1   AV7  VSS<705>  SKX_EXT_B_BGA1  I23
  U5D1   AV11  VSS<704>  SKX_EXT_B_BGA1  I23
  U5D1   AV13  VSS<703>  SKX_EXT_B_BGA1  I23
  U5D1   AV19  VSS<702>  SKX_EXT_B_BGA1  I23
  U5D1   AV23  VSS<701>  SKX_EXT_B_BGA1  I23
  U5D1   AV25  VSS<700>  SKX_EXT_B_BGA1  I23
  U5D1   AV63  VSS<699>  SKX_EXT_B_BGA1  I23
  U5D1   AV65  VSS<698>  SKX_EXT_B_BGA1  I23
  U5D1   AV67  VSS<697>  SKX_EXT_B_BGA1  I23
  U5D1   AV75  VSS<696>  SKX_EXT_B_BGA1  I23
  U5D1   AV83  VSS<695>  SKX_EXT_B_BGA1  I23
  U5D1   AW2  VSS<694>  SKX_EXT_B_BGA1  I23
  U5D1   AW10  VSS<693>  SKX_EXT_B_BGA1  I23
  U5D1   AW62  VSS<692>  SKX_EXT_B_BGA1  I23
  U5D1   AW66  VSS<691>  SKX_EXT_B_BGA1  I23
  U5D1   AW68  VSS<690>  SKX_EXT_B_BGA1  I23
  U5D1   AW70  VSS<689>  SKX_EXT_B_BGA1  I23
  U5D1   AW72  VSS<688>  SKX_EXT_B_BGA1  I23
  U5D1   AW74  VSS<687>  SKX_EXT_B_BGA1  I23
  U5D1   AW78  VSS<686>  SKX_EXT_B_BGA1  I23
  U5D1   AW82  VSS<685>  SKX_EXT_B_BGA1  I23
  U5D1   AW84  VSS<684>  SKX_EXT_B_BGA1  I23
  U5D1   AY5  VSS<683>  SKX_EXT_B_BGA1  I23
  U5D1   AY15  VSS<682>  SKX_EXT_B_BGA1  I23
  U5D1   AY17  VSS<681>  SKX_EXT_B_BGA1  I23
  U5D1   AY21  VSS<680>  SKX_EXT_B_BGA1  I23
  U5D1   AY23  VSS<679>  SKX_EXT_B_BGA1  I23
  U5D1   AY25  VSS<678>  SKX_EXT_B_BGA1  I23
  U5D1   AY63  VSS<677>  SKX_EXT_B_BGA1  I23
  U5D1   AY79  VSS<676>  SKX_EXT_B_BGA1  I23
  U5D1   AY81  VSS<675>  SKX_EXT_B_BGA1  I23
  U5D1    B5  VSS<1250>  SKX_EXT_B_BGA1  I20
  U5D1    B9  VSS<1253>  SKX_EXT_B_BGA1  I20
  U5D1   B25  VSS<1180>  SKX_EXT_B_BGA1  I20
  U5D1   B31  VSS<1179>  SKX_EXT_B_BGA1  I20
  U5D1   B37  VSS<1178>  SKX_EXT_B_BGA1  I20
  U5D1   B43  VSS<1251>  SKX_EXT_B_BGA1  I20
  U5D1   B71  VSS<1177>  SKX_EXT_B_BGA1  I20
  U5D1   B75  VSS<1176>  SKX_EXT_B_BGA1  I20
  U5D1   B79  VSS<1249>  SKX_EXT_B_BGA1  I20
  U5D1   BA2  VSS<674>  SKX_EXT_B_BGA1  I23
  U5D1   BA6  VSS<673>  SKX_EXT_B_BGA1  I23
  U5D1   BA12  VSS<672>  SKX_EXT_B_BGA1  I23
  U5D1   BA62  VSS<671>  SKX_EXT_B_BGA1  I23
  U5D1   BA68  VSS<670>  SKX_EXT_B_BGA1  I23
  U5D1   BA74  VSS<669>  SKX_EXT_B_BGA1  I23
  U5D1   BA80  VSS<668>  SKX_EXT_B_BGA1  I23
  U5D1   BA84  VSS<667>  SKX_EXT_B_BGA1  I23
  U5D1   BB19  VSS<666>  SKX_EXT_B_BGA1  I23
  U5D1   BB23  VSS<665>  SKX_EXT_B_BGA1  I23
  U5D1   BB63  VSS<664>  SKX_EXT_B_BGA1  I23
  U5D1   BB69  VSS<663>  SKX_EXT_B_BGA1  I23
  U5D1   BB73  VSS<662>  SKX_EXT_B_BGA1  I23
  U5D1   BB75  VSS<661>  SKX_EXT_B_BGA1  I23
  U5D1   BB77  VSS<660>  SKX_EXT_B_BGA1  I23
  U5D1   BB79  VSS<659>  SKX_EXT_B_BGA1  I23
  U5D1   BB81  VSS<658>  SKX_EXT_B_BGA1  I23
  U5D1   BB83  VSS<657>  SKX_EXT_B_BGA1  I23
  U5D1   BC4  VSS<656>  SKX_EXT_B_BGA1  I23
  U5D1   BC8  VSS<655>  SKX_EXT_B_BGA1  I23
  U5D1   BC12  VSS<654>  SKX_EXT_B_BGA1  I23
  U5D1   BC16  VSS<653>  SKX_EXT_B_BGA1  I23
  U5D1   BC70  VSS<652>  SKX_EXT_B_BGA1  I23
  U5D1   BC72  VSS<651>  SKX_EXT_B_BGA1  I23
  U5D1   BC74  VSS<650>  SKX_EXT_B_BGA1  I23
  U5D1   BC76  VSS<649>  SKX_EXT_B_BGA1  I23
  U5D1   BC78  VSS<648>  SKX_EXT_B_BGA1  I23
  U5D1   BC80  VSS<647>  SKX_EXT_B_BGA1  I23
  U5D1   BC82  VSS<646>  SKX_EXT_B_BGA1  I23
  U5D1   BD5  VSS<645>  SKX_EXT_B_BGA1  I23
  U5D1   BD11  VSS<644>  SKX_EXT_B_BGA1  I23
  U5D1   BD15  VSS<643>  SKX_EXT_B_BGA1  I23
  U5D1   BD21  VSS<642>  SKX_EXT_B_BGA1  I23
  U5D1   BD27  VSS<641>  SKX_EXT_B_BGA1  I23
  U5D1   BD63  VSS<640>  SKX_EXT_B_BGA1  I23
  U5D1   BD71  VSS<639>  SKX_EXT_B_BGA1  I23
  U5D1   BE4  VSS<638>  SKX_EXT_B_BGA1  I23
  U5D1   BE6  VSS<637>  SKX_EXT_B_BGA1  I23
  U5D1   BE8  VSS<636>  SKX_EXT_B_BGA1  I23
  U5D1   BE10  VSS<635>  SKX_EXT_B_BGA1  I23
  U5D1   BE26  VSS<634>  SKX_EXT_B_BGA1  I23
  U5D1   BE64  VSS<633>  SKX_EXT_B_BGA1  I23
  U5D1   BE66  VSS<632>  SKX_EXT_B_BGA1  I23
  U5D1   BE68  VSS<631>  SKX_EXT_B_BGA1  I23
  U5D1   BE70  VSS<630>  SKX_EXT_B_BGA1  I23
  U5D1   BF9  VSS<629>  SKX_EXT_B_BGA1  I23
  U5D1   BF15  VSS<628>  SKX_EXT_B_BGA1  I23
  U5D1   BF17  VSS<627>  SKX_EXT_B_BGA1  I23
  U5D1   BF19  VSS<626>  SKX_EXT_B_BGA1  I23
  U5D1   BF25  VSS<625>  SKX_EXT_B_BGA1  I23
  U5D1   BF63  VSS<624>  SKX_EXT_B_BGA1  I23
  U5D1   BF65  VSS<623>  SKX_EXT_B_BGA1  I23
  U5D1   BF67  VSS<622>  SKX_EXT_B_BGA1  I23
  U5D1   BF69  VSS<621>  SKX_EXT_B_BGA1  I23
  U5D1   BF71  VSS<620>  SKX_EXT_B_BGA1  I23
  U5D1   BG6  VSS<619>  SKX_EXT_B_BGA1  I23
  U5D1   BG8  VSS<618>  SKX_EXT_B_BGA1  I23
  U5D1   BG10  VSS<617>  SKX_EXT_B_BGA1  I23
  U5D1   BG22  VSS<616>  SKX_EXT_B_BGA1  I23
  U5D1   BG24  VSS<615>  SKX_EXT_B_BGA1  I23
  U5D1   BG72  VSS<614>  SKX_EXT_B_BGA1  I23
  U5D1   BG74  VSS<613>  SKX_EXT_B_BGA1  I283
  U5D1   BG76  VSS<612>  SKX_EXT_B_BGA1  I283
  U5D1   BG78  VSS<611>  SKX_EXT_B_BGA1  I283
  U5D1   BG80  VSS<610>  SKX_EXT_B_BGA1  I283
  U5D1   BG82  VSS<609>  SKX_EXT_B_BGA1  I283
  U5D1   BH7  VSS<608>  SKX_EXT_B_BGA1  I283
  U5D1   BH9  VSS<607>  SKX_EXT_B_BGA1  I283
  U5D1   BH11  VSS<606>  SKX_EXT_B_BGA1  I283
  U5D1   BH15  VSS<605>  SKX_EXT_B_BGA1  I283
  U5D1   BH17  VSS<141>  SKX_EXT_B_BGA1  I285
  U5D1   BH21  VSS<604>  SKX_EXT_B_BGA1  I283
  U5D1   BJ4  VSS<603>  SKX_EXT_B_BGA1  I283
  U5D1   BJ6  VSS<602>  SKX_EXT_B_BGA1  I283
  U5D1   BK3  VSS<601>  SKX_EXT_B_BGA1  I283
  U5D1   BK7  VSS<600>  SKX_EXT_B_BGA1  I283
  U5D1   BK11  VSS<599>  SKX_EXT_B_BGA1  I283
  U5D1   BK19  VSS<598>  SKX_EXT_B_BGA1  I283
  U5D1   BL6  VSS<597>  SKX_EXT_B_BGA1  I283
  U5D1   BL10  VSS<596>  SKX_EXT_B_BGA1  I283
  U5D1   BL12  VSS<595>  SKX_EXT_B_BGA1  I283
  U5D1   BL22  VSS<593>  SKX_EXT_B_BGA1  I283
  U5D1   BL24  VSS<592>  SKX_EXT_B_BGA1  I283
  U5D1   BL64  VSS<591>  SKX_EXT_B_BGA1  I283
  U5D1   BL66  VSS<590>  SKX_EXT_B_BGA1  I283
  U5D1   BL68  VSS<589>  SKX_EXT_B_BGA1  I283
  U5D1   BL70  VSS<588>  SKX_EXT_B_BGA1  I283
  U5D1   BL72  VSS<587>  SKX_EXT_B_BGA1  I283
  U5D1   BL74  VSS<586>  SKX_EXT_B_BGA1  I283
  U5D1   BL76  VSS<585>  SKX_EXT_B_BGA1  I283
  U5D1   BL78  VSS<584>  SKX_EXT_B_BGA1  I283
  U5D1   BL80  VSS<583>  SKX_EXT_B_BGA1  I283
  U5D1   BL82  VSS<582>  SKX_EXT_B_BGA1  I283
  U5D1   BM9  VSS<581>  SKX_EXT_B_BGA1  I283
  U5D1   BM13  VSS<580>  SKX_EXT_B_BGA1  I283
  U5D1   BM15  VSS<579>  SKX_EXT_B_BGA1  I283
  U5D1   BM25  VSS<577>  SKX_EXT_B_BGA1  I283
  U5D1   BN6  VSS<576>  SKX_EXT_B_BGA1  I283
  U5D1   BN10  VSS<575>  SKX_EXT_B_BGA1  I283
  U5D1   BN20  VSS<574>  SKX_EXT_B_BGA1  I283
  U5D1   BN26  VSS<573>  SKX_EXT_B_BGA1  I283
  U5D1   BP3  VSS<572>  SKX_EXT_B_BGA1  I283
  U5D1   BP27  VSS<571>  SKX_EXT_B_BGA1  I283
  U5D1   BR6  VSS<570>  SKX_EXT_B_BGA1  I283
  U5D1   BR10  VSS<569>  SKX_EXT_B_BGA1  I283
  U5D1   BR16  VSS<568>  SKX_EXT_B_BGA1  I283
  U5D1   BR18  VSS<34>  SKX_EXT_B_BGA1  I286
  U5D1   BR26  VSS<127>  SKX_EXT_B_BGA1  I286
  U5D1   BR64  VSS<566>  SKX_EXT_B_BGA1  I283
  U5D1   BR66  VSS<565>  SKX_EXT_B_BGA1  I283
  U5D1   BR68  VSS<564>  SKX_EXT_B_BGA1  I283
  U5D1   BR70  VSS<563>  SKX_EXT_B_BGA1  I283
  U5D1   BR72  VSS<562>  SKX_EXT_B_BGA1  I283
  U5D1   BR74  VSS<561>  SKX_EXT_B_BGA1  I283
  U5D1   BR76  VSS<560>  SKX_EXT_B_BGA1  I283
  U5D1   BR78  VSS<559>  SKX_EXT_B_BGA1  I283
  U5D1   BR80  VSS<558>  SKX_EXT_B_BGA1  I283
  U5D1   BR82  VSS<557>  SKX_EXT_B_BGA1  I283
  U5D1   BT3  VSS<556>  SKX_EXT_B_BGA1  I283
  U5D1   BT5  VSS<555>  SKX_EXT_B_BGA1  I283
  U5D1   BT9  VSS<1064>  SKX_EXT_B_BGA1  I21
  U5D1   BT21  VSS<554>  SKX_EXT_B_BGA1  I283
  U5D1   BT23  VSS<553>  SKX_EXT_B_BGA1  I283
  U5D1   BT25  VSS<552>  SKX_EXT_B_BGA1  I283
  U5D1   BU8  VSS<551>  SKX_EXT_B_BGA1  I283
  U5D1   BU10  VSS<549>  SKX_EXT_B_BGA1  I283
  U5D1   BV5  VSS<550>  SKX_EXT_B_BGA1  I283
  U5D1   BV17  VSS<548>  SKX_EXT_B_BGA1  I283
  U5D1   BV25  VSS<547>  SKX_EXT_B_BGA1  I283
  U5D1   BW6  VSS<546>  SKX_EXT_B_BGA1  I283
  U5D1   BW12  VSS<544>  SKX_EXT_B_BGA1  I283
  U5D1   BW14  VSS<543>  SKX_EXT_B_BGA1  I283
  U5D1   BW16  VSS<542>  SKX_EXT_B_BGA1  I283
  U5D1   BW18  VSS<541>  SKX_EXT_B_BGA1  I283
  U5D1   BW26  VSS<540>  SKX_EXT_B_BGA1  I283
  U5D1   BW72  VSS<539>  SKX_EXT_B_BGA1  I283
  U5D1   BW74  VSS<538>  SKX_EXT_B_BGA1  I283
  U5D1   BW76  VSS<537>  SKX_EXT_B_BGA1  I283
  U5D1   BW78  VSS<536>  SKX_EXT_B_BGA1  I283
  U5D1   BW80  VSS<535>  SKX_EXT_B_BGA1  I283
  U5D1   BW82  VSS<534>  SKX_EXT_B_BGA1  I283
  U5D1   BY11  VSS<533>  SKX_EXT_B_BGA1  I283
  U5D1   BY13  VSS<532>  SKX_EXT_B_BGA1  I283
  U5D1   BY15  UPI2_RX_DP<18>  SKX_EXT_B_BGA1   I3
  U5D1   BY17  UPI2_RX_DN<19>  SKX_EXT_B_BGA1   I3
  U5D1   BY23  VSS<531>  SKX_EXT_B_BGA1  I283
  U5D1   BY63  VSS<530>  SKX_EXT_B_BGA1  I283
  U5D1   BY65  VSS<529>  SKX_EXT_B_BGA1  I283
  U5D1   BY67  VSS<528>  SKX_EXT_B_BGA1  I283
  U5D1   BY69  VSS<527>  SKX_EXT_B_BGA1  I283
  U5D1   BY71  VSS<526>  SKX_EXT_B_BGA1  I283
  U5D1    C4  VSS<1248>  SKX_EXT_B_BGA1  I20
  U5D1    C8  VSS<1175>  SKX_EXT_B_BGA1  I20
  U5D1   C10  VSS<1174>  SKX_EXT_B_BGA1  I20
  U5D1   C12  VSS<1173>  SKX_EXT_B_BGA1  I20
  U5D1   C14  VSS<1172>  SKX_EXT_B_BGA1  I20
  U5D1   C16  VSS<1171>  SKX_EXT_B_BGA1  I20
  U5D1   C76  VSS<1170>  SKX_EXT_B_BGA1  I20
  U5D1   C78  VSS<1169>  SKX_EXT_B_BGA1  I20
  U5D1   C80  VSS<1247>  SKX_EXT_B_BGA1  I20
  U5D1   CA2  VSS<525>  SKX_EXT_B_BGA1  I283
  U5D1   CA6  VSS<524>  SKX_EXT_B_BGA1  I283
  U5D1   CA8  VSS<523>  SKX_EXT_B_BGA1  I283
  U5D1   CA10  VSS<522>  SKX_EXT_B_BGA1  I283
  U5D1   CA14  VSS<521>  SKX_EXT_B_BGA1  I283
  U5D1   CA16  UPI2_RX_DP<19>  SKX_EXT_B_BGA1   I3
  U5D1   CA18  VSS<520>  SKX_EXT_B_BGA1  I283
  U5D1   CA20  VSS<125>  SKX_EXT_B_BGA1  I286
  U5D1   CA26  VSS<519>  SKX_EXT_B_BGA1  I283
  U5D1   CA64  VSS<518>  SKX_EXT_B_BGA1  I283
  U5D1   CA66  VSS<517>  SKX_EXT_B_BGA1  I283
  U5D1   CA68  VSS<516>  SKX_EXT_B_BGA1  I283
  U5D1   CA70  VSS<515>  SKX_EXT_B_BGA1  I283
  U5D1   CB7  VSS<514>  SKX_EXT_B_BGA1  I283
  U5D1   CB9  VSS<513>  SKX_EXT_B_BGA1  I283
  U5D1   CB15  UPI2_RX_DN<18>  SKX_EXT_B_BGA1   I3
  U5D1   CB27  VSS<512>  SKX_EXT_B_BGA1  I283
  U5D1   CB63  VSS<511>  SKX_EXT_B_BGA1  I283
  U5D1   CB71  VSS<510>  SKX_EXT_B_BGA1  I283
  U5D1   CC4  VSS<509>  SKX_EXT_B_BGA1  I283
  U5D1   CC14  UPI2_RX_DP<16>  SKX_EXT_B_BGA1   I3
  U5D1   CC16  VSS<508>  SKX_EXT_B_BGA1  I283
  U5D1   CC18  VSS<507>  SKX_EXT_B_BGA1  I283
  U5D1   CC24  VSS<506>  SKX_EXT_B_BGA1  I283
  U5D1   CC64  VSS<505>  SKX_EXT_B_BGA1  I283
  U5D1   CC72  VSS<504>  SKX_EXT_B_BGA1  I283
  U5D1   CC74  VSS<503>  SKX_EXT_B_BGA1  I283
  U5D1   CC76  VSS<502>  SKX_EXT_B_BGA1  I283
  U5D1   CC78  VSS<501>  SKX_EXT_B_BGA1  I283
  U5D1   CC80  VSS<500>  SKX_EXT_B_BGA1  I283
  U5D1   CC82  VSS<499>  SKX_EXT_B_BGA1  I283
  U5D1   CD5  VSS<498>  SKX_EXT_B_BGA1  I283
  U5D1   CD13  VSS<497>  SKX_EXT_B_BGA1  I283
  U5D1   CD15  UPI2_RX_DN<16>  SKX_EXT_B_BGA1   I3
  U5D1   CD17  UPI2_RX_DP<17>  SKX_EXT_B_BGA1   I3
  U5D1   CD63  VSS<496>  SKX_EXT_B_BGA1  I283
  U5D1   CD73  VSS<495>  SKX_EXT_B_BGA1  I283
  U5D1   CD75  VSS<494>  SKX_EXT_B_BGA1  I283
  U5D1   CD77  VSS<493>  SKX_EXT_B_BGA1  I283
  U5D1   CD79  VSS<492>  SKX_EXT_B_BGA1  I283
  U5D1   CD81  VSS<491>  SKX_EXT_B_BGA1  I283
  U5D1   CE10  VSS<490>  SKX_EXT_B_BGA1  I283
  U5D1   CE14  VSS<489>  SKX_EXT_B_BGA1  I283
  U5D1   CE16  UPI2_RX_DN<15>  SKX_EXT_B_BGA1   I3
  U5D1   CE20  VSS<488>  SKX_EXT_B_BGA1  I283
  U5D1   CE26  VSS<487>  SKX_EXT_B_BGA1  I283
  U5D1   CE62  VSS<486>  SKX_EXT_B_BGA1  I283
  U5D1   CE70  VSS<485>  SKX_EXT_B_BGA1  I283
  U5D1   CE82  VSS<484>  SKX_EXT_B_BGA1  I283
  U5D1   CF9  VSS<482>  SKX_EXT_B_BGA1  I283
  U5D1   CF15  UPI2_RX_DP<15>  SKX_EXT_B_BGA1   I3
  U5D1   CF17  UPI2_RX_DN<17>  SKX_EXT_B_BGA1   I3
  U5D1   CF63  VSS<481>  SKX_EXT_B_BGA1  I283
  U5D1   CF69  VSS<480>  SKX_EXT_B_BGA1  I283
  U5D1   CF71  VSS<479>  SKX_EXT_B_BGA1  I283
  U5D1   CF77  VSS<478>  SKX_EXT_B_BGA1  I283
  U5D1   CF83  VSS<477>  SKX_EXT_B_BGA1  I283
  U5D1   CG6  VSS<1191>  SKX_EXT_B_BGA1  I20
  U5D1   CG16  UPI2_RX_DP<14>  SKX_EXT_B_BGA1   I3
  U5D1   CG18  VSS<475>  SKX_EXT_B_BGA1  I283
  U5D1   CG22  VSS<474>  SKX_EXT_B_BGA1  I283
  U5D1   CG62  VSS<473>  SKX_EXT_B_BGA1  I283
  U5D1   CG68  VSS<472>  SKX_EXT_B_BGA1  I283
  U5D1   CG72  VSS<471>  SKX_EXT_B_BGA1  I283
  U5D1   CG80  VSS<470>  SKX_EXT_B_BGA1  I283
  U5D1   CH1  VSS<469>  SKX_EXT_B_BGA1  I283
  U5D1   CH3  VSS<468>  SKX_EXT_B_BGA1  I283
  U5D1   CH15  VSS<467>  SKX_EXT_B_BGA1  I283
  U5D1   CH17  UPI2_RX_DN<14>  SKX_EXT_B_BGA1   I3
  U5D1   CH19  VSS<466>  SKX_EXT_B_BGA1  I283
  U5D1   CH63  VSS<465>  SKX_EXT_B_BGA1  I283
  U5D1   CH67  VSS<464>  SKX_EXT_B_BGA1  I283
  U5D1   CH73  VSS<463>  SKX_EXT_B_BGA1  I283
  U5D1   CH79  VSS<462>  SKX_EXT_B_BGA1  I283
  U5D1   CH81  VSS<461>  SKX_EXT_B_BGA1  I283
  U5D1   CH83  VSS<460>  SKX_EXT_B_BGA1  I283
  U5D1   CJ2  VSS<459>  SKX_EXT_B_BGA1  I283
  U5D1   CJ6  VSS<458>  SKX_EXT_B_BGA1  I283
  U5D1   CJ8  VSS<457>  SKX_EXT_B_BGA1  I283
  U5D1   CJ10  VSS<456>  SKX_EXT_B_BGA1  I283
  U5D1   CJ12  VSS<455>  SKX_EXT_B_BGA1  I283
  U5D1   CJ16  UPI2_RX_DP<12>  SKX_EXT_B_BGA1   I3
  U5D1   CJ18  UPI2_RX_DN<13>  SKX_EXT_B_BGA1   I3
  U5D1   CJ62  VSS<452>  SKX_EXT_B_BGA1  I284
  U5D1   CJ74  VSS<451>  SKX_EXT_B_BGA1  I284
  U5D1   CJ76  VSS<450>  SKX_EXT_B_BGA1  I284
  U5D1   CJ78  VSS<449>  SKX_EXT_B_BGA1  I284
  U5D1   CJ82  VSS<448>  SKX_EXT_B_BGA1  I284
  U5D1   CJ84  VSS<447>  SKX_EXT_B_BGA1  I284
  U5D1   CJ86  VSS<446>  SKX_EXT_B_BGA1  I284
  U5D1   CK11  VSS<445>  SKX_EXT_B_BGA1  I284
  U5D1   CK15  VSS<444>  SKX_EXT_B_BGA1  I284
  U5D1   CK17  UPI2_RX_DP<13>  SKX_EXT_B_BGA1   I3
  U5D1   CK21  VSS<443>  SKX_EXT_B_BGA1  I284
  U5D1   CK27  VSS<442>  SKX_EXT_B_BGA1  I284
  U5D1   CK63  VSS<441>  SKX_EXT_B_BGA1  I284
  U5D1   CK65  VSS<440>  SKX_EXT_B_BGA1  I284
  U5D1   CK67  VSS<439>  SKX_EXT_B_BGA1  I284
  U5D1   CK69  VSS<438>  SKX_EXT_B_BGA1  I284
  U5D1   CK71  VSS<437>  SKX_EXT_B_BGA1  I284
  U5D1   CK73  VSS<436>  SKX_EXT_B_BGA1  I284
  U5D1   CK75  VSS<435>  SKX_EXT_B_BGA1  I284
  U5D1   CK83  VSS<434>  SKX_EXT_B_BGA1  I284
  U5D1   CK85  VSS<433>  SKX_EXT_B_BGA1  I284
  U5D1   CL8  VSS<432>  SKX_EXT_B_BGA1  I284
  U5D1   CL14  VSS<431>  SKX_EXT_B_BGA1  I284
  U5D1   CL16  UPI2_RX_DN<12>  SKX_EXT_B_BGA1   I3
  U5D1   CL18  VSS<430>  SKX_EXT_B_BGA1  I284
  U5D1   CL22  VSS<124>  SKX_EXT_B_BGA1  I286
  U5D1   CL62  VSS<427>  SKX_EXT_B_BGA1  I284
  U5D1   CL64  VSS<426>  SKX_EXT_B_BGA1  I284
  U5D1   CL66  VSS<425>  SKX_EXT_B_BGA1  I284
  U5D1   CL74  VSS<424>  SKX_EXT_B_BGA1  I284
  U5D1   CL76  VSS<423>  SKX_EXT_B_BGA1  I284
  U5D1   CL78  VSS<422>  SKX_EXT_B_BGA1  I284
  U5D1   CL80  VSS<421>  SKX_EXT_B_BGA1  I284
  U5D1   CM5  VSS<418>  SKX_EXT_B_BGA1  I284
  U5D1   CM19  VSS<420>  SKX_EXT_B_BGA1  I284
  U5D1   CM21  UPI2_RX_DP<11>  SKX_EXT_B_BGA1   I3
  U5D1   CM27  VSS<1168>  SKX_EXT_B_BGA1  I20
  U5D1   CM29  VSS<419>  SKX_EXT_B_BGA1  I284
  U5D1   CM31  VSS<417>  SKX_EXT_B_BGA1  I284
  U5D1   CM61  VSS<416>  SKX_EXT_B_BGA1  I284
  U5D1   CM63  VSS<415>  SKX_EXT_B_BGA1  I284
  U5D1   CM67  VSS<414>  SKX_EXT_B_BGA1  I284
  U5D1   CM73  VSS<413>  SKX_EXT_B_BGA1  I284
  U5D1   CM77  VSS<412>  SKX_EXT_B_BGA1  I284
  U5D1   CM83  VSS<411>  SKX_EXT_B_BGA1  I284
  U5D1   CM85  VSS<410>  SKX_EXT_B_BGA1  I284
  U5D1   CN2  VSS<409>  SKX_EXT_B_BGA1  I284
  U5D1   CN12  VSS<408>  SKX_EXT_B_BGA1  I284
  U5D1   CN14  VSS<94>  SKX_EXT_B_BGA1  I286
  U5D1   CN18  UPI2_RX_DP<9>  SKX_EXT_B_BGA1   I3
  U5D1   CN20  UPI2_RX_DN<10>  SKX_EXT_B_BGA1   I3
  U5D1   CN26  VSS<406>  SKX_EXT_B_BGA1  I284
  U5D1   CN32  VSS<405>  SKX_EXT_B_BGA1  I284
  U5D1   CN60  VSS<404>  SKX_EXT_B_BGA1  I284
  U5D1   CN62  VSS<403>  SKX_EXT_B_BGA1  I284
  U5D1   CN68  VSS<402>  SKX_EXT_B_BGA1  I284
  U5D1   CN78  VSS<401>  SKX_EXT_B_BGA1  I284
  U5D1   CP1  VSS<400>  SKX_EXT_B_BGA1  I284
  U5D1   CP19  UPI2_RX_DP<10>  SKX_EXT_B_BGA1   I3
  U5D1   CP21  UPI2_RX_DN<11>  SKX_EXT_B_BGA1   I3
  U5D1   CP25  VSS<398>  SKX_EXT_B_BGA1  I284
  U5D1   CP59  VSS<397>  SKX_EXT_B_BGA1  I284
  U5D1   CP69  VSS<396>  SKX_EXT_B_BGA1  I284
  U5D1   CP73  VSS<395>  SKX_EXT_B_BGA1  I284
  U5D1   CP75  VSS<394>  SKX_EXT_B_BGA1  I284
  U5D1   CP81  VSS<393>  SKX_EXT_B_BGA1  I284
  U5D1   CP83  VSS<392>  SKX_EXT_B_BGA1  I284
  U5D1   CR6  VSS<391>  SKX_EXT_B_BGA1  I284
  U5D1   CR10  VSS<390>  SKX_EXT_B_BGA1  I284
  U5D1   CR18  UPI2_RX_DN<9>  SKX_EXT_B_BGA1   I3
  U5D1   CR20  UPI2_RX_DP<8>  SKX_EXT_B_BGA1   I3
  U5D1   CR22  VSS<389>  SKX_EXT_B_BGA1  I284
  U5D1   CR24  VSS<388>  SKX_EXT_B_BGA1  I284
  U5D1   CR32  VSS<387>  SKX_EXT_B_BGA1  I284
  U5D1   CR58  VSS<386>  SKX_EXT_B_BGA1  I284
  U5D1   CR62  VSS<385>  SKX_EXT_B_BGA1  I284
  U5D1   CR64  VSS<384>  SKX_EXT_B_BGA1  I284
  U5D1   CR66  VSS<383>  SKX_EXT_B_BGA1  I284
  U5D1   CR68  VSS<382>  SKX_EXT_B_BGA1  I284
  U5D1   CR78  VSS<381>  SKX_EXT_B_BGA1  I284
  U5D1   CR86  VSS<380>  SKX_EXT_B_BGA1  I284
  U5D1   CT7  VSS<1063>  SKX_EXT_B_BGA1  I21
  U5D1   CT13  VSS<378>  SKX_EXT_B_BGA1  I284
  U5D1   CT19  VSS<377>  SKX_EXT_B_BGA1  I284
  U5D1   CT21  UPI2_RX_DN<8>  SKX_EXT_B_BGA1   I3
  U5D1   CT27  VSS<376>  SKX_EXT_B_BGA1  I284
  U5D1   CT29  VSS<375>  SKX_EXT_B_BGA1  I284
  U5D1   CT33  VSS<374>  SKX_EXT_B_BGA1  I284
  U5D1   CT35  VSS<373>  SKX_EXT_B_BGA1  I284
  U5D1   CT57  VSS<372>  SKX_EXT_B_BGA1  I284
  U5D1   CT73  VSS<371>  SKX_EXT_B_BGA1  I284
  U5D1   CT79  VSS<370>  SKX_EXT_B_BGA1  I284
  U5D1   CT83  VSS<369>  SKX_EXT_B_BGA1  I284
  U5D1   CT85  VSS<368>  SKX_EXT_B_BGA1  I284
  U5D1   CU4  VSS<367>  SKX_EXT_B_BGA1  I284
  U5D1   CU20  UPI2_RX_DP<6>  SKX_EXT_B_BGA1   I3
  U5D1   CU22  VSS<366>  SKX_EXT_B_BGA1  I284
  U5D1   CU28  VSS<365>  SKX_EXT_B_BGA1  I284
  U5D1   CU30  VSS<364>  SKX_EXT_B_BGA1  I284
  U5D1   CU34  VSS<363>  SKX_EXT_B_BGA1  I284
  U5D1   CU36  VSS<362>  SKX_EXT_B_BGA1  I284
  U5D1   CU56  VSS<361>  SKX_EXT_B_BGA1  I284
  U5D1   CU62  VSS<360>  SKX_EXT_B_BGA1  I284
  U5D1   CU68  VSS<359>  SKX_EXT_B_BGA1  I284
  U5D1   CU76  VSS<358>  SKX_EXT_B_BGA1  I284
  U5D1   CU78  VSS<357>  SKX_EXT_B_BGA1  I284
  U5D1   CU80  VSS<356>  SKX_EXT_B_BGA1  I284
  U5D1   CU82  VSS<355>  SKX_EXT_B_BGA1  I284
  U5D1   CU86  VSS<354>  SKX_EXT_B_BGA1  I284
  U5D1   CV1  VSS<353>  SKX_EXT_B_BGA1  I284
  U5D1   CV17  VSS<351>  SKX_EXT_B_BGA1  I284
  U5D1   CV19  UPI2_RX_DN<7>  SKX_EXT_B_BGA1   I3
  U5D1   CV25  VSS<350>  SKX_EXT_B_BGA1  I284
  U5D1   CV27  VSS<349>  SKX_EXT_B_BGA1  I284
  U5D1   CV31  VSS<348>  SKX_EXT_B_BGA1  I284
  U5D1   CV33  VSS<347>  SKX_EXT_B_BGA1  I284
  U5D1   CV37  VSS<346>  SKX_EXT_B_BGA1  I284
  U5D1   CV39  VSS<345>  SKX_EXT_B_BGA1  I284
  U5D1   CV41  VSS<344>  SKX_EXT_B_BGA1  I284
  U5D1   CV53  VSS<343>  SKX_EXT_B_BGA1  I284
  U5D1   CV55  VSS<342>  SKX_EXT_B_BGA1  I284
  U5D1   CV63  VSS<341>  SKX_EXT_B_BGA1  I284
  U5D1   CV67  VSS<340>  SKX_EXT_B_BGA1  I284
  U5D1   CV73  VSS<339>  SKX_EXT_B_BGA1  I284
  U5D1   CV79  VSS<338>  SKX_EXT_B_BGA1  I284
  U5D1   CV81  VSS<337>  SKX_EXT_B_BGA1  I284
  U5D1   CV83  VSS<336>  SKX_EXT_B_BGA1  I284
  U5D1   CW6  VSS<1192>  SKX_EXT_B_BGA1  I20
  U5D1   CW12  VSS<335>  SKX_EXT_B_BGA1  I284
  U5D1   CW18  UPI2_RX_DP<7>  SKX_EXT_B_BGA1   I3
  U5D1   CW20  UPI2_RX_DN<6>  SKX_EXT_B_BGA1   I3
  U5D1   CW26  VSS<334>  SKX_EXT_B_BGA1  I284
  U5D1   CW32  VSS<333>  SKX_EXT_B_BGA1  I284
  U5D1   CW38  VSS<332>  SKX_EXT_B_BGA1  I284
  U5D1   CW40  VSS<331>  SKX_EXT_B_BGA1  I284
  U5D1   CW42  VSS<330>  SKX_EXT_B_BGA1  I284
  U5D1   CW52  VSS<329>  SKX_EXT_B_BGA1  I284
  U5D1   CW54  VSS<328>  SKX_EXT_B_BGA1  I284
  U5D1   CW64  VSS<327>  SKX_EXT_B_BGA1  I284
  U5D1   CW66  VSS<326>  SKX_EXT_B_BGA1  I284
  U5D1   CW68  VSS<325>  SKX_EXT_B_BGA1  I284
  U5D1   CW74  VSS<324>  SKX_EXT_B_BGA1  I284
  U5D1   CW78  VSS<323>  SKX_EXT_B_BGA1  I284
  U5D1   CW82  VSS<322>  SKX_EXT_B_BGA1  I284
  U5D1   CY1  VSS<321>  SKX_EXT_B_BGA1  I284
  U5D1   CY9  VSS<320>  SKX_EXT_B_BGA1  I284
  U5D1   CY13  VSS<319>  SKX_EXT_B_BGA1  I284
  U5D1   CY15  VSS<318>  SKX_EXT_B_BGA1  I284
  U5D1   CY19  UPI2_RX_DP<5>  SKX_EXT_B_BGA1   I3
  U5D1   CY21  VSS<317>  SKX_EXT_B_BGA1  I284
  U5D1   CY41  VSS<316>  SKX_EXT_B_BGA1  I284
  U5D1   CY45  VSS<315>  SKX_EXT_B_BGA1  I284
  U5D1   CY51  VSS<314>  SKX_EXT_B_BGA1  I284
  U5D1   CY59  VSS<313>  SKX_EXT_B_BGA1  I284
  U5D1   CY61  VSS<312>  SKX_EXT_B_BGA1  I284
  U5D1   CY65  VSS<311>  SKX_EXT_B_BGA1  I284
  U5D1   CY69  VSS<310>  SKX_EXT_B_BGA1  I284
  U5D1   CY75  VSS<309>  SKX_EXT_B_BGA1  I284
  U5D1   CY77  VSS<308>  SKX_EXT_B_BGA1  I284
  U5D1   CY83  VSS<307>  SKX_EXT_B_BGA1  I284
  U5D1   CY85  VSS<306>  SKX_EXT_B_BGA1  I284
  U5D1    D3  VSS<1246>  SKX_EXT_B_BGA1  I20
  U5D1   D11  VSS<1167>  SKX_EXT_B_BGA1  I20
  U5D1   D13  VSS<1166>  SKX_EXT_B_BGA1  I20
  U5D1   D25  VSS<1165>  SKX_EXT_B_BGA1  I20
  U5D1   D27  VSS<1164>  SKX_EXT_B_BGA1  I20
  U5D1   D29  VSS<1163>  SKX_EXT_B_BGA1  I20
  U5D1   D31  VSS<1162>  SKX_EXT_B_BGA1  I20
  U5D1   D33  VSS<1161>  SKX_EXT_B_BGA1  I20
  U5D1   D35  VSS<1160>  SKX_EXT_B_BGA1  I20
  U5D1   D37  VSS<1159>  SKX_EXT_B_BGA1  I20
  U5D1   D39  VSS<1158>  SKX_EXT_B_BGA1  I20
  U5D1   D41  VSS<1157>  SKX_EXT_B_BGA1  I20
  U5D1   D43  VSS<1156>  SKX_EXT_B_BGA1  I20
  U5D1   D77  VSS<1155>  SKX_EXT_B_BGA1  I20
  U5D1   D81  VSS<1245>  SKX_EXT_B_BGA1  I20
  U5D1   DA6  VSS<305>  SKX_EXT_B_BGA1  I284
  U5D1   DA18  VSS<303>  SKX_EXT_B_BGA1  I284
  U5D1   DA20  UPI2_RX_DN<5>  SKX_EXT_B_BGA1   I3
  U5D1   DA22  UPI2_RX_DP<2>  SKX_EXT_B_BGA1   I3
  U5D1   DA26  VSS<302>  SKX_EXT_B_BGA1  I284
  U5D1   DA28  VSS<301>  SKX_EXT_B_BGA1  I284
  U5D1   DA30  VSS<300>  SKX_EXT_B_BGA1  I284
  U5D1   DA32  VSS<299>  SKX_EXT_B_BGA1  I284
  U5D1   DA34  VSS<298>  SKX_EXT_B_BGA1  I284
  U5D1   DA36  VSS<297>  SKX_EXT_B_BGA1  I284
  U5D1   DA38  VSS<296>  SKX_EXT_B_BGA1  I284
  U5D1   DA44  VSS<295>  SKX_EXT_B_BGA1  I284
  U5D1   DA46  VSS<294>  SKX_EXT_B_BGA1  I284
  U5D1   DA48  VSS<293>  SKX_EXT_B_BGA1  I285
  U5D1   DA50  VSS<292>  SKX_EXT_B_BGA1  I285
  U5D1   DA64  VSS<291>  SKX_EXT_B_BGA1  I285
  U5D1   DA70  VSS<290>  SKX_EXT_B_BGA1  I285
  U5D1   DA74  VSS<289>  SKX_EXT_B_BGA1  I285
  U5D1   DA76  VSS<288>  SKX_EXT_B_BGA1  I285
  U5D1   DA78  VSS<287>  SKX_EXT_B_BGA1  I285
  U5D1   DA80  VSS<286>  SKX_EXT_B_BGA1  I285
  U5D1   DB3  VSS<285>  SKX_EXT_B_BGA1  I285
  U5D1   DB7  VSS<1086>  SKX_EXT_B_BGA1  I21
  U5D1   DB13  VSS<284>  SKX_EXT_B_BGA1  I285
  U5D1   DB17  VSS<283>  SKX_EXT_B_BGA1  I285
  U5D1   DB19  UPI2_RX_DP<4>  SKX_EXT_B_BGA1   I3
  U5D1   DB21  UPI2_RX_DN<3>  SKX_EXT_B_BGA1   I3
  U5D1   DB23  VSS<282>  SKX_EXT_B_BGA1  I285
  U5D1   DB25  VSS<281>  SKX_EXT_B_BGA1  I285
  U5D1   DB39  VSS<280>  SKX_EXT_B_BGA1  I285
  U5D1   DB41  VSS<279>  SKX_EXT_B_BGA1  I285
  U5D1   DB47  VSS<278>  SKX_EXT_B_BGA1  I285
  U5D1   DB49  VSS<277>  SKX_EXT_B_BGA1  I285
  U5D1   DB73  VSS<276>  SKX_EXT_B_BGA1  I285
  U5D1   DB77  VSS<275>  SKX_EXT_B_BGA1  I285
  U5D1   DB83  VSS<274>  SKX_EXT_B_BGA1  I285
  U5D1   DB85  VSS<273>  SKX_EXT_B_BGA1  I285
  U5D1   DC14  VSS<272>  SKX_EXT_B_BGA1  I285
  U5D1   DC20  UPI2_RX_DP<3>  SKX_EXT_B_BGA1   I3
  U5D1   DC22  UPI2_RX_DN<2>  SKX_EXT_B_BGA1   I3
  U5D1   DC24  VSS<271>  SKX_EXT_B_BGA1  I285
  U5D1   DC26  VSS<270>  SKX_EXT_B_BGA1  I285
  U5D1   DC32  VSS<269>  SKX_EXT_B_BGA1  I285
  U5D1   DC38  VSS<268>  SKX_EXT_B_BGA1  I285
  U5D1   DC42  VSS<267>  SKX_EXT_B_BGA1  I285
  U5D1   DC64  VSS<266>  SKX_EXT_B_BGA1  I285
  U5D1   DC66  VSS<265>  SKX_EXT_B_BGA1  I285
  U5D1   DC68  VSS<264>  SKX_EXT_B_BGA1  I285
  U5D1   DC70  VSS<263>  SKX_EXT_B_BGA1  I285
  U5D1   DC78  VSS<262>  SKX_EXT_B_BGA1  I285
  U5D1   DC84  VSS<261>  SKX_EXT_B_BGA1  I285
  U5D1   DC86  VSS<260>  SKX_EXT_B_BGA1  I285
  U5D1   DD11  VSS<259>  SKX_EXT_B_BGA1  I285
  U5D1   DD19  UPI2_RX_DN<4>  SKX_EXT_B_BGA1   I3
  U5D1   DD21  UPI2_RX_DP<1>  SKX_EXT_B_BGA1   I3
  U5D1   DD23  VSS<258>  SKX_EXT_B_BGA1  I285
  U5D1   DD27  VSS<257>  SKX_EXT_B_BGA1  I285
  U5D1   DD31  VSS<256>  SKX_EXT_B_BGA1  I285
  U5D1   DD33  VSS<255>  SKX_EXT_B_BGA1  I285
  U5D1   DD37  VSS<254>  SKX_EXT_B_BGA1  I285
  U5D1   DD71  VSS<253>  SKX_EXT_B_BGA1  I285
  U5D1   DD73  VSS<252>  SKX_EXT_B_BGA1  I285
  U5D1   DD75  VSS<251>  SKX_EXT_B_BGA1  I285
  U5D1   DD81  VSS<250>  SKX_EXT_B_BGA1  I285
  U5D1   DD83  VSS<249>  SKX_EXT_B_BGA1  I285
  U5D1   DE6  VSS<248>  SKX_EXT_B_BGA1  I285
  U5D1   DE8  VSS<247>  SKX_EXT_B_BGA1  I285
  U5D1   DE18  VSS<246>  SKX_EXT_B_BGA1  I285
  U5D1   DE20  VSS<245>  SKX_EXT_B_BGA1  I285
  U5D1   DE22  UPI2_RX_DN<1>  SKX_EXT_B_BGA1   I3
  U5D1   DE24  VSS<244>  SKX_EXT_B_BGA1  I285
  U5D1   DE28  VSS<243>  SKX_EXT_B_BGA1  I285
  U5D1   DE30  VSS<242>  SKX_EXT_B_BGA1  I285
  U5D1   DE34  VSS<241>  SKX_EXT_B_BGA1  I285
  U5D1   DE36  VSS<240>  SKX_EXT_B_BGA1  I285
  U5D1   DE48  VSS<1193>  SKX_EXT_B_BGA1  I20
  U5D1   DE50  VSS<1194>  SKX_EXT_B_BGA1  I20
  U5D1   DE52  VSS<1195>  SKX_EXT_B_BGA1  I20
  U5D1   DE54  VSS<1196>  SKX_EXT_B_BGA1  I20
  U5D1   DE56  VSS<1197>  SKX_EXT_B_BGA1  I20
  U5D1   DE58  VSS<1198>  SKX_EXT_B_BGA1  I20
  U5D1   DE60  VSS<1199>  SKX_EXT_B_BGA1  I20
  U5D1   DE62  VSS<1200>  SKX_EXT_B_BGA1  I20
  U5D1   DE64  VSS<239>  SKX_EXT_B_BGA1  I285
  U5D1   DE70  VSS<238>  SKX_EXT_B_BGA1  I285
  U5D1   DE72  VSS<237>  SKX_EXT_B_BGA1  I285
  U5D1   DE78  VSS<236>  SKX_EXT_B_BGA1  I285
  U5D1   DF5  VSS<235>  SKX_EXT_B_BGA1  I285
  U5D1   DF7  VSS<234>  SKX_EXT_B_BGA1  I285
  U5D1   DF19  VSS<232>  SKX_EXT_B_BGA1  I285
  U5D1   DF23  UPI2_RX_DN<0>  SKX_EXT_B_BGA1   I3
  U5D1   DF29  VSS<231>  SKX_EXT_B_BGA1  I285
  U5D1   DF35  VSS<230>  SKX_EXT_B_BGA1  I285
  U5D1   DF37  VSS<229>  SKX_EXT_B_BGA1  I285
  U5D1   DF39  VSS<228>  SKX_EXT_B_BGA1  I285
  U5D1   DF41  VSS<227>  SKX_EXT_B_BGA1  I285
  U5D1   DF65  VSS<226>  SKX_EXT_B_BGA1  I285
  U5D1   DF69  VSS<225>  SKX_EXT_B_BGA1  I285
  U5D1   DF73  VSS<224>  SKX_EXT_B_BGA1  I285
  U5D1   DF79  VSS<223>  SKX_EXT_B_BGA1  I285
  U5D1   DF83  VSS<222>  SKX_EXT_B_BGA1  I285
  U5D1   DF85  VSS<221>  SKX_EXT_B_BGA1  I285
  U5D1   DG2  VSS<220>  SKX_EXT_B_BGA1  I285
  U5D1   DG14  VSS<218>  SKX_EXT_B_BGA1  I285
  U5D1   DG16  VSS<217>  SKX_EXT_B_BGA1  I285
  U5D1   DG22  UPI2_RX_DP<0>  SKX_EXT_B_BGA1   I3
  U5D1   DG24  VSS<216>  SKX_EXT_B_BGA1  I285
  U5D1   DG66  VSS<215>  SKX_EXT_B_BGA1  I285
  U5D1   DG68  VSS<214>  SKX_EXT_B_BGA1  I285
  U5D1   DG76  VSS<213>  SKX_EXT_B_BGA1  I285
  U5D1   DG78  VSS<212>  SKX_EXT_B_BGA1  I285
  U5D1   DG80  VSS<211>  SKX_EXT_B_BGA1  I285
  U5D1   DG82  VSS<210>  SKX_EXT_B_BGA1  I285
  U5D1   DH13  VSS<209>  SKX_EXT_B_BGA1  I285
  U5D1   DH15  VSS<208>  SKX_EXT_B_BGA1  I285
  U5D1   DH21  VSS<102>  SKX_EXT_B_BGA1  I286
  U5D1   DH23  VSS<207>  SKX_EXT_B_BGA1  I285
  U5D1   DH25  VSS<206>  SKX_EXT_B_BGA1  I285
  U5D1   DH27  VSS<205>  SKX_EXT_B_BGA1  I285
  U5D1   DH29  VSS<204>  SKX_EXT_B_BGA1  I285
  U5D1   DH31  VSS<203>  SKX_EXT_B_BGA1  I285
  U5D1   DH33  VSS<202>  SKX_EXT_B_BGA1  I285
  U5D1   DH35  VSS<201>  SKX_EXT_B_BGA1  I285
  U5D1   DH37  VSS<200>  SKX_EXT_B_BGA1  I285
  U5D1   DH41  VSS<199>  SKX_EXT_B_BGA1  I285
  U5D1   DH67  VSS<198>  SKX_EXT_B_BGA1  I285
  U5D1   DH71  VSS<197>  SKX_EXT_B_BGA1  I285
  U5D1   DH73  VSS<196>  SKX_EXT_B_BGA1  I285
  U5D1   DH79  VSS<195>  SKX_EXT_B_BGA1  I285
  U5D1   DH81  VSS<194>  SKX_EXT_B_BGA1  I285
  U5D1   DH83  VSS<193>  SKX_EXT_B_BGA1  I285
  U5D1   DJ2  VSS<192>  SKX_EXT_B_BGA1  I285
  U5D1   DJ10  VSS<191>  SKX_EXT_B_BGA1  I285
  U5D1   DJ22  VSS<189>  SKX_EXT_B_BGA1  I285
  U5D1   DJ38  VSS<188>  SKX_EXT_B_BGA1  I285
  U5D1   DJ42  VSS<187>  SKX_EXT_B_BGA1  I285
  U5D1   DJ68  VSS<186>  SKX_EXT_B_BGA1  I285
  U5D1   DJ74  VSS<185>  SKX_EXT_B_BGA1  I285
  U5D1   DJ78  VSS<184>  SKX_EXT_B_BGA1  I285
  U5D1   DJ82  VSS<183>  SKX_EXT_B_BGA1  I285
  U5D1   DJ84  VSS<182>  SKX_EXT_B_BGA1  I285
  U5D1   DK7  VSS<181>  SKX_EXT_B_BGA1  I285
  U5D1   DK23  VSS<180>  SKX_EXT_B_BGA1  I285
  U5D1   DK29  VSS<179>  SKX_EXT_B_BGA1  I285
  U5D1   DK35  VSS<178>  SKX_EXT_B_BGA1  I285
  U5D1   DK39  VSS<177>  SKX_EXT_B_BGA1  I285
  U5D1   DK41  VSS<176>  SKX_EXT_B_BGA1  I285
  U5D1   DK73  VSS<175>  SKX_EXT_B_BGA1  I285
  U5D1   DK75  VSS<174>  SKX_EXT_B_BGA1  I285
  U5D1   DK77  VSS<173>  SKX_EXT_B_BGA1  I285
  U5D1   DK83  VSS<172>  SKX_EXT_B_BGA1  I285
  U5D1   DK85  VSS<171>  SKX_EXT_B_BGA1  I285
  U5D1   DL4  VSS<168>  SKX_EXT_B_BGA1  I285
  U5D1   DL8  VSS<1201>  SKX_EXT_B_BGA1  I20
  U5D1   DL16  VSS<170>  SKX_EXT_B_BGA1  I285
  U5D1   DL18  VSS<169>  SKX_EXT_B_BGA1  I285
  U5D1   DL22  VSS<167>  SKX_EXT_B_BGA1  I285
  U5D1   DL24  VSS<166>  SKX_EXT_B_BGA1  I285
  U5D1   DL28  VSS<165>  SKX_EXT_B_BGA1  I285
  U5D1   DL30  VSS<164>  SKX_EXT_B_BGA1  I285
  U5D1   DL34  VSS<163>  SKX_EXT_B_BGA1  I285
  U5D1   DL36  VSS<162>  SKX_EXT_B_BGA1  I285
  U5D1   DL40  VSS<161>  SKX_EXT_B_BGA1  I285
  U5D1   DL68  VSS<160>  SKX_EXT_B_BGA1  I285
  U5D1   DL70  VSS<159>  SKX_EXT_B_BGA1  I285
  U5D1   DL74  VSS<158>  SKX_EXT_B_BGA1  I285
  U5D1   DL76  VSS<157>  SKX_EXT_B_BGA1  I285
  U5D1   DL78  VSS<156>  SKX_EXT_B_BGA1  I285
  U5D1   DL80  VSS<155>  SKX_EXT_B_BGA1  I285
  U5D1   DM15  VSS<154>  SKX_EXT_B_BGA1  I285
  U5D1   DM19  VSS<1043>  SKX_EXT_B_BGA1  I21
  U5D1   DM25  VSS<152>  SKX_EXT_B_BGA1  I285
  U5D1   DM27  VSS<151>  SKX_EXT_B_BGA1  I285
  U5D1   DM31  VSS<150>  SKX_EXT_B_BGA1  I285
  U5D1   DM33  VSS<149>  SKX_EXT_B_BGA1  I285
  U5D1   DM37  VSS<148>  SKX_EXT_B_BGA1  I285
  U5D1   DM39  VSS<147>  SKX_EXT_B_BGA1  I285
  U5D1   DM65  VSS<146>  SKX_EXT_B_BGA1  I285
  U5D1   DM73  VSS<145>  SKX_EXT_B_BGA1  I285
  U5D1   DM77  VSS<144>  SKX_EXT_B_BGA1  I285
  U5D1   DM83  VSS<143>  SKX_EXT_B_BGA1  I285
  U5D1   DN2  VSS<142>  SKX_EXT_B_BGA1  I285
  U5D1   DN12  VSS<140>  SKX_EXT_B_BGA1  I285
  U5D1   DN18  VSS<1202>  SKX_EXT_B_BGA1  I20
  U5D1   DN22  VSS<139>  SKX_EXT_B_BGA1  I285
  U5D1   DN26  VSS<138>  SKX_EXT_B_BGA1  I285
  U5D1   DN32  VSS<137>  SKX_EXT_B_BGA1  I285
  U5D1   DN38  VSS<136>  SKX_EXT_B_BGA1  I285
  U5D1   DN44  VSS<1106>  SKX_EXT_B_BGA1  I20
  U5D1   DN68  VSS<135>  SKX_EXT_B_BGA1  I285
  U5D1   DN72  VSS<134>  SKX_EXT_B_BGA1  I285
  U5D1   DN78  VSS<133>  SKX_EXT_B_BGA1  I286
  U5D1   DP9  VSS<1213>  SKX_EXT_B_BGA1  I20
  U5D1   DP45  VSS<1203>  SKX_EXT_B_BGA1  I20
  U5D1   DP47  VSS<1204>  SKX_EXT_B_BGA1  I20
  U5D1   DP49  VSS<1205>  SKX_EXT_B_BGA1  I20
  U5D1   DP51  VSS<1206>  SKX_EXT_B_BGA1  I20
  U5D1   DP53  VSS<1207>  SKX_EXT_B_BGA1  I20
  U5D1   DP55  VSS<1208>  SKX_EXT_B_BGA1  I20
  U5D1   DP57  VSS<1209>  SKX_EXT_B_BGA1  I20
  U5D1   DP59  VSS<1210>  SKX_EXT_B_BGA1  I20
  U5D1   DP61  VSS<1211>  SKX_EXT_B_BGA1  I20
  U5D1   DP63  VSS<1212>  SKX_EXT_B_BGA1  I20
  U5D1   DP67  VSS<132>  SKX_EXT_B_BGA1  I286
  U5D1   DP69  VSS<131>  SKX_EXT_B_BGA1  I286
  U5D1   DP71  VSS<130>  SKX_EXT_B_BGA1  I286
  U5D1   DP81  VSS<129>  SKX_EXT_B_BGA1  I286
  U5D1   DP83  VSS<128>  SKX_EXT_B_BGA1  I286
  U5D1   DR6  VSS<126>  SKX_EXT_B_BGA1  I286
  U5D1   DR20  VSS<123>  SKX_EXT_B_BGA1  I286
  U5D1   DR22  VSS<122>  SKX_EXT_B_BGA1  I286
  U5D1   DR24  VSS<121>  SKX_EXT_B_BGA1  I286
  U5D1   DR26  VSS<120>  SKX_EXT_B_BGA1  I286
  U5D1   DR28  VSS<119>  SKX_EXT_B_BGA1  I286
  U5D1   DR30  VSS<118>  SKX_EXT_B_BGA1  I286
  U5D1   DR32  VSS<117>  SKX_EXT_B_BGA1  I286
  U5D1   DR34  VSS<116>  SKX_EXT_B_BGA1  I286
  U5D1   DR36  VSS<115>  SKX_EXT_B_BGA1  I286
  U5D1   DR38  VSS<114>  SKX_EXT_B_BGA1  I286
  U5D1   DR40  VSS<113>  SKX_EXT_B_BGA1  I286
  U5D1   DR42  VSS<112>  SKX_EXT_B_BGA1  I286
  U5D1   DR66  VSS<111>  SKX_EXT_B_BGA1  I286
  U5D1   DR68  VSS<110>  SKX_EXT_B_BGA1  I286
  U5D1   DR70  VSS<109>  SKX_EXT_B_BGA1  I286
  U5D1   DR72  VSS<108>  SKX_EXT_B_BGA1  I286
  U5D1   DR74  VSS<107>  SKX_EXT_B_BGA1  I286
  U5D1   DR76  VSS<106>  SKX_EXT_B_BGA1  I286
  U5D1   DR78  VSS<105>  SKX_EXT_B_BGA1  I286
  U5D1   DT3  VSS<104>  SKX_EXT_B_BGA1  I286
  U5D1   DT17  VSS<103>  SKX_EXT_B_BGA1  I286
  U5D1   DT65  VSS<101>  SKX_EXT_B_BGA1  I286
  U5D1   DT69  VSS<100>  SKX_EXT_B_BGA1  I286
  U5D1   DT79  VSS<99>  SKX_EXT_B_BGA1  I286
  U5D1   DT83  VSS<98>  SKX_EXT_B_BGA1  I286
  U5D1   DT85  VSS<97>  SKX_EXT_B_BGA1  I286
  U5D1   DU10  VSS<96>  SKX_EXT_B_BGA1  I286
  U5D1   DU14  VSS<95>  SKX_EXT_B_BGA1  I286
  U5D1   DU22  VSS<93>  SKX_EXT_B_BGA1  I286
  U5D1   DU26  VSS<92>  SKX_EXT_B_BGA1  I286
  U5D1   DU32  VSS<91>  SKX_EXT_B_BGA1  I286
  U5D1   DU38  VSS<90>  SKX_EXT_B_BGA1  I286
  U5D1   DU70  VSS<89>  SKX_EXT_B_BGA1  I286
  U5D1   DU72  VSS<88>  SKX_EXT_B_BGA1  I286
  U5D1   DU78  VSS<87>  SKX_EXT_B_BGA1  I286
  U5D1   DU80  VSS<86>  SKX_EXT_B_BGA1  I286
  U5D1   DU82  VSS<85>  SKX_EXT_B_BGA1  I286
  U5D1   DU84  VSS<84>  SKX_EXT_B_BGA1  I286
  U5D1   DV19  VSS<1214>  SKX_EXT_B_BGA1  I20
  U5D1   DV21  VSS<83>  SKX_EXT_B_BGA1  I286
  U5D1   DV25  VSS<82>  SKX_EXT_B_BGA1  I286
  U5D1   DV27  VSS<81>  SKX_EXT_B_BGA1  I286
  U5D1   DV31  VSS<80>  SKX_EXT_B_BGA1  I286
  U5D1   DV33  VSS<79>  SKX_EXT_B_BGA1  I286
  U5D1   DV37  VSS<78>  SKX_EXT_B_BGA1  I286
  U5D1   DV39  VSS<77>  SKX_EXT_B_BGA1  I286
  U5D1   DV73  VSS<76>  SKX_EXT_B_BGA1  I286
  U5D1   DV77  VSS<75>  SKX_EXT_B_BGA1  I286
  U5D1   DV81  VSS<74>  SKX_EXT_B_BGA1  I286
  U5D1   DW2  VSS<1239>  SKX_EXT_B_BGA1  I20
  U5D1   DW8  VSS<58>  SKX_EXT_B_BGA1  I286
  U5D1   DW12  VSS<73>  SKX_EXT_B_BGA1  I286
  U5D1   DW20  VSS<72>  SKX_EXT_B_BGA1  I286
  U5D1   DW24  VSS<71>  SKX_EXT_B_BGA1  I286
  U5D1   DW28  VSS<70>  SKX_EXT_B_BGA1  I286
  U5D1   DW30  VSS<69>  SKX_EXT_B_BGA1  I286
  U5D1   DW34  VSS<68>  SKX_EXT_B_BGA1  I286
  U5D1   DW36  VSS<67>  SKX_EXT_B_BGA1  I286
  U5D1   DW40  VSS<66>  SKX_EXT_B_BGA1  I286
  U5D1   DW64  VSS<65>  SKX_EXT_B_BGA1  I286
  U5D1   DW66  VSS<64>  SKX_EXT_B_BGA1  I286
  U5D1   DW68  VSS<63>  SKX_EXT_B_BGA1  I286
  U5D1   DW70  VSS<62>  SKX_EXT_B_BGA1  I286
  U5D1   DW72  VSS<61>  SKX_EXT_B_BGA1  I286
  U5D1   DW74  VSS<60>  SKX_EXT_B_BGA1  I286
  U5D1   DW76  VSS<59>  SKX_EXT_B_BGA1  I286
  U5D1   DW82  VSS<57>  SKX_EXT_B_BGA1  I286
  U5D1   DW84  VSS<56>  SKX_EXT_B_BGA1  I286
  U5D1   DY5  VSS<55>  SKX_EXT_B_BGA1  I286
  U5D1   DY19  VSS<54>  SKX_EXT_B_BGA1  I286
  U5D1   DY23  VSS<53>  SKX_EXT_B_BGA1  I286
  U5D1   DY29  VSS<52>  SKX_EXT_B_BGA1  I286
  U5D1   DY35  VSS<51>  SKX_EXT_B_BGA1  I286
  U5D1   DY41  VSS<50>  SKX_EXT_B_BGA1  I286
  U5D1   DY45  VSS<1215>  SKX_EXT_B_BGA1  I20
  U5D1   DY47  VSS<1216>  SKX_EXT_B_BGA1  I20
  U5D1   DY49  VSS<1217>  SKX_EXT_B_BGA1  I20
  U5D1   DY51  VSS<1218>  SKX_EXT_B_BGA1  I20
  U5D1   DY53  VSS<1219>  SKX_EXT_B_BGA1  I20
  U5D1   DY55  VSS<1220>  SKX_EXT_B_BGA1  I20
  U5D1   DY57  VSS<1221>  SKX_EXT_B_BGA1  I20
  U5D1   DY59  VSS<1222>  SKX_EXT_B_BGA1  I20
  U5D1   DY61  VSS<1223>  SKX_EXT_B_BGA1  I20
  U5D1   DY63  VSS<1224>  SKX_EXT_B_BGA1  I20
  U5D1   DY71  VSS<49>  SKX_EXT_B_BGA1  I286
  U5D1   DY75  VSS<48>  SKX_EXT_B_BGA1  I286
  U5D1   DY85  VSS<1242>  SKX_EXT_B_BGA1  I20
  U5D1    E6  VSS<1154>  SKX_EXT_B_BGA1  I20
  U5D1    E8  VSS<1153>  SKX_EXT_B_BGA1  I20
  U5D1   E16  VSS<1152>  SKX_EXT_B_BGA1  I20
  U5D1   E18  VSS<1151>  SKX_EXT_B_BGA1  I20
  U5D1   E20  VSS<1150>  SKX_EXT_B_BGA1  I20
  U5D1   E22  VSS<1149>  SKX_EXT_B_BGA1  I20
  U5D1   E66  VSS<1228>  SKX_EXT_B_BGA1  I20
  U5D1   E72  VSS<1148>  SKX_EXT_B_BGA1  I20
  U5D1   E74  VSS<1147>  SKX_EXT_B_BGA1  I20
  U5D1   E76  VSS<1146>  SKX_EXT_B_BGA1  I20
  U5D1   E82  VSS<1244>  SKX_EXT_B_BGA1  I20
  U5D1   EA6  VSS<47>  SKX_EXT_B_BGA1  I286
  U5D1   EA14  VSS<1225>  SKX_EXT_B_BGA1  I20
  U5D1   EA16  VSS<45>  SKX_EXT_B_BGA1  I286
  U5D1   EA20  VSS<44>  SKX_EXT_B_BGA1  I286
  U5D1   EA22  VSS<43>  SKX_EXT_B_BGA1  I286
  U5D1   EA42  VSS<42>  SKX_EXT_B_BGA1  I286
  U5D1   EA64  VSS<41>  SKX_EXT_B_BGA1  I286
  U5D1   EA70  VSS<40>  SKX_EXT_B_BGA1  I286
  U5D1   EA76  VSS<39>  SKX_EXT_B_BGA1  I286
  U5D1   EA78  VSS<38>  SKX_EXT_B_BGA1  I286
  U5D1   EA80  VSS<37>  SKX_EXT_B_BGA1  I286
  U5D1   EA82  VSS<36>  SKX_EXT_B_BGA1  I286
  U5D1   EA84  VSS<1241>  SKX_EXT_B_BGA1  I20
  U5D1   EB13  VSS<35>  SKX_EXT_B_BGA1  I286
  U5D1   EB23  VSS<33>  SKX_EXT_B_BGA1  I286
  U5D1   EB25  VSS<32>  SKX_EXT_B_BGA1  I286
  U5D1   EB27  VSS<31>  SKX_EXT_B_BGA1  I286
  U5D1   EB29  VSS<30>  SKX_EXT_B_BGA1  I286
  U5D1   EB31  VSS<29>  SKX_EXT_B_BGA1  I286
  U5D1   EB33  VSS<28>  SKX_EXT_B_BGA1  I286
  U5D1   EB35  VSS<27>  SKX_EXT_B_BGA1  I286
  U5D1   EB37  VSS<26>  SKX_EXT_B_BGA1  I286
  U5D1   EB39  VSS<25>  SKX_EXT_B_BGA1  I286
  U5D1   EB41  VSS<24>  SKX_EXT_B_BGA1  I286
  U5D1   EB65  VSS<23>  SKX_EXT_B_BGA1  I286
  U5D1   EB69  VSS<22>  SKX_EXT_B_BGA1  I286
  U5D1   EB83  VSS<1240>  SKX_EXT_B_BGA1  I20
  U5D1   EC6  VSS<1237>  SKX_EXT_B_BGA1  I20
  U5D1   EC10  VSS<21>  SKX_EXT_B_BGA1  I286
  U5D1   EC42  VSS<1238>  SKX_EXT_B_BGA1  I20
  U5D1   EC70  VSS<20>  SKX_EXT_B_BGA1  I286
  U5D1   EC72  VSS<19>  SKX_EXT_B_BGA1  I286
  U5D1   EC74  VSS<18>  SKX_EXT_B_BGA1  I286
  U5D1   EC76  VSS<17>  SKX_EXT_B_BGA1  I286
  U5D1   EC82  VSS<1236>  SKX_EXT_B_BGA1  I20
  U5D1   ED7  VSS<1234>  SKX_EXT_B_BGA1  I20
  U5D1   ED11  VSS<16>  SKX_EXT_B_BGA1  I286
  U5D1   ED15  VSS<15>  SKX_EXT_B_BGA1  I286
  U5D1   ED23  VSS<14>  SKX_EXT_B_BGA1  I286
  U5D1   ED29  VSS<13>  SKX_EXT_B_BGA1  I286
  U5D1   ED35  VSS<12>  SKX_EXT_B_BGA1  I286
  U5D1   ED41  VSS<1235>  SKX_EXT_B_BGA1  I20
  U5D1   ED69  VSS<1229>  SKX_EXT_B_BGA1  I20
  U5D1   ED77  VSS<11>  SKX_EXT_B_BGA1  I286
  U5D1   ED81  VSS<1233>  SKX_EXT_B_BGA1  I20
  U5D1   EE8  VSS<1231>  SKX_EXT_B_BGA1  I20
  U5D1   EE24  VSS<10>  SKX_EXT_B_BGA1  I286
  U5D1   EE28  VSS<9>  SKX_EXT_B_BGA1  I286
  U5D1   EE30  VSS<8>  SKX_EXT_B_BGA1  I286
  U5D1   EE34  VSS<7>  SKX_EXT_B_BGA1  I286
  U5D1   EE36  VSS<6>  SKX_EXT_B_BGA1  I286
  U5D1   EE40  VSS<1232>  SKX_EXT_B_BGA1  I20
  U5D1   EE70  VSS<5>  SKX_EXT_B_BGA1  I286
  U5D1   EE76  VSS<4>  SKX_EXT_B_BGA1  I286
  U5D1   EE78  VSS<3>  SKX_EXT_B_BGA1  I286
  U5D1   EE80  VSS<1230>  SKX_EXT_B_BGA1  I20
  U5D1   EF71  VSS<2>  SKX_EXT_B_BGA1  I286
  U5D1   EF75  VSS<1>  SKX_EXT_B_BGA1  I286
  U5D1   EF79  VSS<0>  SKX_EXT_B_BGA1  I286
  U5D1    F5  VSS<1145>  SKX_EXT_B_BGA1  I20
  U5D1   F17  VSS<1144>  SKX_EXT_B_BGA1  I20
  U5D1   F19  VSS<1143>  SKX_EXT_B_BGA1  I20
  U5D1   F25  VSS<1142>  SKX_EXT_B_BGA1  I20
  U5D1   F31  VSS<1141>  SKX_EXT_B_BGA1  I20
  U5D1   F37  VSS<1140>  SKX_EXT_B_BGA1  I20
  U5D1   F43  VSS<1139>  SKX_EXT_B_BGA1  I20
  U5D1   F67  VSS<1138>  SKX_EXT_B_BGA1  I20
  U5D1   F69  VSS<1137>  SKX_EXT_B_BGA1  I20
  U5D1    G4  VSS<1136>  SKX_EXT_B_BGA1  I20
  U5D1    G8  VSS<1135>  SKX_EXT_B_BGA1  I20
  U5D1   G22  VSS<1134>  SKX_EXT_B_BGA1  I20
  U5D1   G24  VSS<1133>  SKX_EXT_B_BGA1  I20
  U5D1   G26  VSS<1132>  SKX_EXT_B_BGA1  I20
  U5D1   G30  VSS<1131>  SKX_EXT_B_BGA1  I20
  U5D1   G32  VSS<1130>  SKX_EXT_B_BGA1  I20
  U5D1   G36  VSS<1129>  SKX_EXT_B_BGA1  I20
  U5D1   G38  VSS<1128>  SKX_EXT_B_BGA1  I20
  U5D1   G42  VSS<1127>  SKX_EXT_B_BGA1  I20
  U5D1   G66  VSS<1126>  SKX_EXT_B_BGA1  I20
  U5D1   G70  VSS<1125>  SKX_EXT_B_BGA1  I20
  U5D1   G76  VSS<1124>  SKX_EXT_B_BGA1  I20
  U5D1   G78  VSS<1123>  SKX_EXT_B_BGA1  I20
  U5D1   G80  VSS<1122>  SKX_EXT_B_BGA1  I20
  U5D1   G82  VSS<1121>  SKX_EXT_B_BGA1  I20
  U5D1    H3  VSS<1120>  SKX_EXT_B_BGA1  I20
  U5D1   H11  VSS<1119>  SKX_EXT_B_BGA1  I20
  U5D1   H25  VSS<1118>  SKX_EXT_B_BGA1  I20
  U5D1   H27  VSS<1117>  SKX_EXT_B_BGA1  I20
  U5D1   H29  VSS<1116>  SKX_EXT_B_BGA1  I20
  U5D1   H31  VSS<1115>  SKX_EXT_B_BGA1  I20
  U5D1   H33  VSS<1114>  SKX_EXT_B_BGA1  I20
  U5D1   H35  VSS<1113>  SKX_EXT_B_BGA1  I20
  U5D1   H37  VSS<1112>  SKX_EXT_B_BGA1  I20
  U5D1   H39  VSS<1111>  SKX_EXT_B_BGA1  I20
  U5D1   H41  VSS<1110>  SKX_EXT_B_BGA1  I20
  U5D1   H45  VSS<153>  SKX_EXT_B_BGA1  I285
  U5D1   H47  VSS<190>  SKX_EXT_B_BGA1  I285
  U5D1   H49  VSS<219>  SKX_EXT_B_BGA1  I285
  U5D1   H51  VSS<233>  SKX_EXT_B_BGA1  I285
  U5D1   H53  VSS<304>  SKX_EXT_B_BGA1  I284
  U5D1   H55  VSS<352>  SKX_EXT_B_BGA1  I284
  U5D1   H57  VSS<379>  SKX_EXT_B_BGA1  I284
  U5D1   H59  VSS<399>  SKX_EXT_B_BGA1  I284
  U5D1   H61  VSS<407>  SKX_EXT_B_BGA1  I284
  U5D1   H63  VSS<428>  SKX_EXT_B_BGA1  I284
  U5D1   H65  VSS<1109>  SKX_EXT_B_BGA1  I20
  U5D1   H71  VSS<1108>  SKX_EXT_B_BGA1  I20
  U5D1   H75  VSS<1107>  SKX_EXT_B_BGA1  I20
  U5D1    J4  VSS<1105>  SKX_EXT_B_BGA1  I20
  U5D1   J12  VSS<1104>  SKX_EXT_B_BGA1  I20
  U5D1   J14  VSS<1103>  SKX_EXT_B_BGA1  I20
  U5D1   J16  VSS<46>  SKX_EXT_B_BGA1  I286
  U5D1   J22  VSS<1102>  SKX_EXT_B_BGA1  I20
  U5D1   J26  VSS<1101>  SKX_EXT_B_BGA1  I20
  U5D1   J28  VSS<1100>  SKX_EXT_B_BGA1  I20
  U5D1   J32  VSS<1099>  SKX_EXT_B_BGA1  I20
  U5D1   J34  VSS<1098>  SKX_EXT_B_BGA1  I20
  U5D1   J38  VSS<1097>  SKX_EXT_B_BGA1  I20
  U5D1   J40  VSS<1096>  SKX_EXT_B_BGA1  I20
  U5D1   J72  VSS<1095>  SKX_EXT_B_BGA1  I20
  U5D1   J74  VSS<1094>  SKX_EXT_B_BGA1  I20
  U5D1   J76  VSS<1093>  SKX_EXT_B_BGA1  I21
  U5D1   J82  VSS<1092>  SKX_EXT_B_BGA1  I21
  U5D1   J84  VSS<1091>  SKX_EXT_B_BGA1  I21
  U5D1   J86  VSS<1243>  SKX_EXT_B_BGA1  I20
  U5D1    K1  VSS<1090>  SKX_EXT_B_BGA1  I21
  U5D1   K11  VSS<1089>  SKX_EXT_B_BGA1  I21
  U5D1   K13  VSS<1088>  SKX_EXT_B_BGA1  I21
  U5D1   K17  VSS<1087>  SKX_EXT_B_BGA1  I21
  U5D1   K27  VSS<1085>  SKX_EXT_B_BGA1  I21
  U5D1   K33  VSS<1084>  SKX_EXT_B_BGA1  I21
  U5D1   K39  VSS<1083>  SKX_EXT_B_BGA1  I21
  U5D1   K65  VSS<1082>  SKX_EXT_B_BGA1  I21
  U5D1   K67  VSS<1081>  SKX_EXT_B_BGA1  I21
  U5D1   K69  VSS<1080>  SKX_EXT_B_BGA1  I21
  U5D1   K71  VSS<1079>  SKX_EXT_B_BGA1  I21
  U5D1   K73  VSS<1078>  SKX_EXT_B_BGA1  I21
  U5D1   K77  VSS<1077>  SKX_EXT_B_BGA1  I21
  U5D1   K81  VSS<1076>  SKX_EXT_B_BGA1  I21
  U5D1   K83  VSS<1075>  SKX_EXT_B_BGA1  I21
  U5D1   K85  VSS<1074>  SKX_EXT_B_BGA1  I21
  U5D1    L2  VSS<1072>  SKX_EXT_B_BGA1  I21
  U5D1    L6  VSS<1071>  SKX_EXT_B_BGA1  I21
  U5D1    L8  VSS<1226>  SKX_EXT_B_BGA1  I20
  U5D1   L10  VSS<1073>  SKX_EXT_B_BGA1  I21
  U5D1   L20  VSS<1070>  SKX_EXT_B_BGA1  I21
  U5D1   L22  VSS<1069>  SKX_EXT_B_BGA1  I21
  U5D1   L72  VSS<1068>  SKX_EXT_B_BGA1  I21
  U5D1   L78  VSS<1067>  SKX_EXT_B_BGA1  I21
  U5D1   L80  VSS<1066>  SKX_EXT_B_BGA1  I21
  U5D1   L82  VSS<1065>  SKX_EXT_B_BGA1  I21
  U5D1   M15  VSS<1062>  SKX_EXT_B_BGA1  I21
  U5D1   M17  VSS<1061>  SKX_EXT_B_BGA1  I21
  U5D1   M19  VSS<1060>  SKX_EXT_B_BGA1  I21
  U5D1   M23  VSS<1059>  SKX_EXT_B_BGA1  I21
  U5D1   M25  VSS<1058>  SKX_EXT_B_BGA1  I21
  U5D1   M27  VSS<1057>  SKX_EXT_B_BGA1  I21
  U5D1   M29  VSS<1056>  SKX_EXT_B_BGA1  I21
  U5D1   M31  VSS<1055>  SKX_EXT_B_BGA1  I21
  U5D1   M33  VSS<1054>  SKX_EXT_B_BGA1  I21
  U5D1   M35  VSS<1053>  SKX_EXT_B_BGA1  I21
  U5D1   M37  VSS<1052>  SKX_EXT_B_BGA1  I21
  U5D1   M39  VSS<1051>  SKX_EXT_B_BGA1  I21
  U5D1   M41  VSS<1050>  SKX_EXT_B_BGA1  I21
  U5D1   M43  VSS<1049>  SKX_EXT_B_BGA1  I21
  U5D1   M65  VSS<1048>  SKX_EXT_B_BGA1  I21
  U5D1   M71  VSS<1047>  SKX_EXT_B_BGA1  I21
  U5D1   M79  VSS<1046>  SKX_EXT_B_BGA1  I21
  U5D1   M83  VSS<1045>  SKX_EXT_B_BGA1  I21
  U5D1   M85  VSS<1044>  SKX_EXT_B_BGA1  I21
  U5D1    N4  VSS<1033>  SKX_EXT_B_BGA1  I21
  U5D1    N6  VSS<1040>  SKX_EXT_B_BGA1  I21
  U5D1    N8  VSS<1032>  SKX_EXT_B_BGA1  I21
  U5D1   N20  VSS<1042>  SKX_EXT_B_BGA1  I21
  U5D1   N22  VSS<1041>  SKX_EXT_B_BGA1  I21
  U5D1   N66  VSS<1039>  SKX_EXT_B_BGA1  I21
  U5D1   N70  VSS<1038>  SKX_EXT_B_BGA1  I21
  U5D1   N72  VSS<1037>  SKX_EXT_B_BGA1  I21
  U5D1   N74  VSS<1036>  SKX_EXT_B_BGA1  I21
  U5D1   N76  VSS<1035>  SKX_EXT_B_BGA1  I21
  U5D1   N78  VSS<1034>  SKX_EXT_B_BGA1  I21
  U5D1   P11  VSS<1031>  SKX_EXT_B_BGA1  I21
  U5D1   P15  VSS<1030>  SKX_EXT_B_BGA1  I21
  U5D1   P27  VSS<1029>  SKX_EXT_B_BGA1  I21
  U5D1   P33  VSS<1028>  SKX_EXT_B_BGA1  I21
  U5D1   P39  VSS<1027>  SKX_EXT_B_BGA1  I21
  U5D1   P45  VSS<429>  SKX_EXT_B_BGA1  I284
  U5D1   P47  VSS<453>  SKX_EXT_B_BGA1  I284
  U5D1   P49  VSS<454>  SKX_EXT_B_BGA1  I283
  U5D1   P51  VSS<476>  SKX_EXT_B_BGA1  I283
  U5D1   P53  VSS<483>  SKX_EXT_B_BGA1  I283
  U5D1   P55  VSS<545>  SKX_EXT_B_BGA1  I283
  U5D1   P57  VSS<567>  SKX_EXT_B_BGA1  I283
  U5D1   P59  VSS<578>  SKX_EXT_B_BGA1  I283
  U5D1   P61  VSS<594>  SKX_EXT_B_BGA1  I283
  U5D1   P63  VSS<732>  SKX_EXT_B_BGA1  I23
  U5D1   P67  VSS<1026>  SKX_EXT_B_BGA1  I21
  U5D1   P69  VSS<1025>  SKX_EXT_B_BGA1  I21
  U5D1   P71  VSS<1024>  SKX_EXT_B_BGA1  I21
  U5D1   P81  VSS<1023>  SKX_EXT_B_BGA1  I21
  U5D1   P83  VSS<1022>  SKX_EXT_B_BGA1  I21
  U5D1    R2  VSS<1019>  SKX_EXT_B_BGA1  I21
  U5D1    R4  VSS<1018>  SKX_EXT_B_BGA1  I21
  U5D1   R14  VSS<1021>  SKX_EXT_B_BGA1  I21
  U5D1   R18  VSS<1020>  SKX_EXT_B_BGA1  I21
  U5D1   R22  VSS<1017>  SKX_EXT_B_BGA1  I21
  U5D1   R26  VSS<1016>  SKX_EXT_B_BGA1  I21
  U5D1   R28  VSS<1015>  SKX_EXT_B_BGA1  I21
  U5D1   R32  VSS<1014>  SKX_EXT_B_BGA1  I21
  U5D1   R34  VSS<1013>  SKX_EXT_B_BGA1  I21
  U5D1   R38  VSS<1012>  SKX_EXT_B_BGA1  I21
  U5D1   R40  VSS<1011>  SKX_EXT_B_BGA1  I21
  U5D1   R68  VSS<1010>  SKX_EXT_B_BGA1  I21
  U5D1   R72  VSS<1009>  SKX_EXT_B_BGA1  I21
  U5D1   R78  VSS<1008>  SKX_EXT_B_BGA1  I21
  U5D1   R86  VSS<1007>  SKX_EXT_B_BGA1  I21
  U5D1   T13  VSS<1006>  SKX_EXT_B_BGA1  I21
  U5D1   T17  VSS<1005>  SKX_EXT_B_BGA1  I21
  U5D1   T25  VSS<1004>  SKX_EXT_B_BGA1  I21
  U5D1   T29  VSS<1003>  SKX_EXT_B_BGA1  I21
  U5D1   T31  VSS<1002>  SKX_EXT_B_BGA1  I21
  U5D1   T35  VSS<1001>  SKX_EXT_B_BGA1  I21
  U5D1   T37  VSS<1000>  SKX_EXT_B_BGA1  I21
  U5D1   T41  VSS<999>  SKX_EXT_B_BGA1  I21
  U5D1   T65  VSS<998>  SKX_EXT_B_BGA1  I21
  U5D1   T73  VSS<997>  SKX_EXT_B_BGA1  I21
  U5D1   T77  VSS<996>  SKX_EXT_B_BGA1  I21
  U5D1   T83  VSS<995>  SKX_EXT_B_BGA1  I21
  U5D1   T85  VSS<994>  SKX_EXT_B_BGA1  I21
  U5D1    U2  VSS<993>  SKX_EXT_B_BGA1  I21
  U5D1    U4  VSS<992>  SKX_EXT_B_BGA1  I21
  U5D1    U6  VSS<991>  SKX_EXT_B_BGA1  I21
  U5D1   U20  VSS<990>  SKX_EXT_B_BGA1  I21
  U5D1   U22  VSS<989>  SKX_EXT_B_BGA1  I21
  U5D1   U24  VSS<988>  SKX_EXT_B_BGA1  I21
  U5D1   U30  VSS<987>  SKX_EXT_B_BGA1  I21
  U5D1   U36  VSS<986>  SKX_EXT_B_BGA1  I21
  U5D1   U42  VSS<985>  SKX_EXT_B_BGA1  I21
  U5D1   U68  VSS<984>  SKX_EXT_B_BGA1  I21
  U5D1   U70  VSS<983>  SKX_EXT_B_BGA1  I21
  U5D1   U74  VSS<982>  SKX_EXT_B_BGA1  I21
  U5D1   U76  VSS<981>  SKX_EXT_B_BGA1  I21
  U5D1   U78  VSS<980>  SKX_EXT_B_BGA1  I21
  U5D1   U80  VSS<979>  SKX_EXT_B_BGA1  I21
  U5D1   U86  VSS<978>  SKX_EXT_B_BGA1  I21
  U5D1    V1  VSS<977>  SKX_EXT_B_BGA1  I21
  U5D1    V5  VSS<976>  SKX_EXT_B_BGA1  I21
  U5D1    V9  VSS<975>  SKX_EXT_B_BGA1  I21
  U5D1   V11  VSS<1227>  SKX_EXT_B_BGA1  I20
  U5D1   V13  VSS<974>  SKX_EXT_B_BGA1  I21
  U5D1   V15  VSS<973>  SKX_EXT_B_BGA1  I21
  U5D1   V21  VSS<972>  SKX_EXT_B_BGA1  I21
  U5D1   V23  VSS<971>  SKX_EXT_B_BGA1  I21
  U5D1   V43  VSS<970>  SKX_EXT_B_BGA1  I21
  U5D1   V73  VSS<969>  SKX_EXT_B_BGA1  I21
  U5D1   V75  VSS<968>  SKX_EXT_B_BGA1  I21
  U5D1   V77  VSS<967>  SKX_EXT_B_BGA1  I21
  U5D1   V83  VSS<966>  SKX_EXT_B_BGA1  I21
  U5D1    W8  VSS<965>  SKX_EXT_B_BGA1  I21
  U5D1   W12  VSS<963>  SKX_EXT_B_BGA1  I21
  U5D1   W22  VSS<962>  SKX_EXT_B_BGA1  I21
  U5D1   W24  VSS<961>  SKX_EXT_B_BGA1  I21
  U5D1   W26  VSS<960>  SKX_EXT_B_BGA1  I21
  U5D1   W28  VSS<959>  SKX_EXT_B_BGA1  I21
  U5D1   W30  VSS<958>  SKX_EXT_B_BGA1  I21
  U5D1   W32  VSS<957>  SKX_EXT_B_BGA1  I21
  U5D1   W34  VSS<956>  SKX_EXT_B_BGA1  I21
  U5D1   W36  VSS<955>  SKX_EXT_B_BGA1  I21
  U5D1   W38  VSS<954>  SKX_EXT_B_BGA1  I21
  U5D1   W40  VSS<953>  SKX_EXT_B_BGA1  I21
  U5D1   W42  VSS<952>  SKX_EXT_B_BGA1  I21
  U5D1   W68  VSS<951>  SKX_EXT_B_BGA1  I21
  U5D1   W74  VSS<950>  SKX_EXT_B_BGA1  I21
  U5D1   W78  VSS<949>  SKX_EXT_B_BGA1  I21
  U5D1   W82  VSS<948>  SKX_EXT_B_BGA1  I21
  U5D1    Y5  VSS<945>  SKX_EXT_B_BGA1  I21
  U5D1    Y7  VSS<943>  SKX_EXT_B_BGA1  I21
  U5D1    Y9  VSS<942>  SKX_EXT_B_BGA1  I21
  U5D1   Y15  VSS<947>  SKX_EXT_B_BGA1  I21
  U5D1   Y17  VSS<946>  SKX_EXT_B_BGA1  I21
  U5D1   Y67  VSS<944>  SKX_EXT_B_BGA1  I21
  U5D1   Y71  VSS<941>  SKX_EXT_B_BGA1  I21
  U5D1   Y73  VSS<940>  SKX_EXT_B_BGA1  I21
  U5D1   Y79  VSS<939>  SKX_EXT_B_BGA1  I21
  U5D1   Y81  VSS<938>  SKX_EXT_B_BGA1  I21
  U5D1   Y83  VSS<937>  SKX_EXT_B_BGA1  I21
  U5D1   Y85  VSS<936>  SKX_EXT_B_BGA1  I21
  U7C1    A5  VSS<484>  LBG_CORE_QAT_EXT_D  I13
  U7C1    A7  VSS<483>  LBG_CORE_QAT_EXT_D  I13
  U7C1    A9  VSS<482>  LBG_CORE_QAT_EXT_D  I13
  U7C1   A18  VSS<448>  LBG_CORE_QAT_EXT_D  I13
  U7C1   A22  VSS<447>  LBG_CORE_QAT_EXT_D  I13
  U7C1   A30  VSS<446>  LBG_CORE_QAT_EXT_D  I13
  U7C1   A34  VSS<445>  LBG_CORE_QAT_EXT_D  I13
  U7C1   A37  VSS<444>  LBG_CORE_QAT_EXT_D  I13
  U7C1   A41  VSS<443>  LBG_CORE_QAT_EXT_D  I13
  U7C1   A65  VSS<481>  LBG_CORE_QAT_EXT_D  I13
  U7C1   A66  VSS<480>  LBG_CORE_QAT_EXT_D  I13
  U7C1   A68  VSS<479>  LBG_CORE_QAT_EXT_D  I13
  U7C1   A70  VSS<468>  LBG_CORE_QAT_EXT_D  I13
  U7C1   AA26  VSS<297>  LBG_CORE_QAT_EXT_D  I17
  U7C1   AA27  VSS<296>  LBG_CORE_QAT_EXT_D  I17
  U7C1   AA43  VSS<295>  LBG_CORE_QAT_EXT_D  I17
  U7C1   AA48  VSS<294>  LBG_CORE_QAT_EXT_D  I17
  U7C1   AA50  VSS<309>  LBG_CORE_QAT_EXT_D  I17
  U7C1   AB5  VSS<293>  LBG_CORE_QAT_EXT_D  I17
  U7C1   AB68  VSS<292>  LBG_CORE_QAT_EXT_D  I17
  U7C1   AB70  VSS<291>  LBG_CORE_QAT_EXT_D  I17
  U7C1   AB72  VSS<290>  LBG_CORE_QAT_EXT_D  I17
  U7C1   AC7  VSS<275>  LBG_CORE_QAT_EXT_D  I17
  U7C1   AC11  VSS<289>  LBG_CORE_QAT_EXT_D  I17
  U7C1   AC15  VSS<288>  LBG_CORE_QAT_EXT_D  I17
  U7C1   AC18  VSS<287>  LBG_CORE_QAT_EXT_D  I17
  U7C1   AC22  VSS<286>  LBG_CORE_QAT_EXT_D  I17
  U7C1   AC27  VSS<283>  LBG_CORE_QAT_EXT_D  I17
  U7C1   AC43  VSS<282>  LBG_CORE_QAT_EXT_D  I17
  U7C1   AC45  VSS<285>  LBG_CORE_QAT_EXT_D  I17
  U7C1   AC46  VSS<281>  LBG_CORE_QAT_EXT_D  I17
  U7C1   AC48  VSS<280>  LBG_CORE_QAT_EXT_D  I17
  U7C1   AC52  VSS<279>  LBG_CORE_QAT_EXT_D  I17
  U7C1   AC59  VSS<278>  LBG_CORE_QAT_EXT_D  I17
  U7C1   AC63  VSS<277>  LBG_CORE_QAT_EXT_D  I17
  U7C1   AC66  VSS<276>  LBG_CORE_QAT_EXT_D  I17
  U7C1   AD5  VSS<274>  LBG_CORE_QAT_EXT_D  I17
  U7C1   AD58  VSS<284>  LBG_CORE_QAT_EXT_D  I17
  U7C1   AD65  VSS<273>  LBG_CORE_QAT_EXT_D  I17
  U7C1   AD68  VSS<272>  LBG_CORE_QAT_EXT_D  I17
  U7C1   AE22  VSS<172>  LBG_CORE_QAT_EXT_D  I16
  U7C1   AE29  VSS<271>  LBG_CORE_QAT_EXT_D  I17
  U7C1   AE43  VSS<347>  LBG_CORE_QAT_EXT_D  I17
  U7C1   AE48  VSS<269>  LBG_CORE_QAT_EXT_D  I17
  U7C1   AE52  VSS<268>  LBG_CORE_QAT_EXT_D  I17
  U7C1   AE56  VSS<267>  LBG_CORE_QAT_EXT_D  I17
  U7C1   AE59  VSS<266>  LBG_CORE_QAT_EXT_D  I17
  U7C1   AE63  VSS<265>  LBG_CORE_QAT_EXT_D  I17
  U7C1   AE66  VSS<264>  LBG_CORE_QAT_EXT_D  I17
  U7C1   AF1  VSS<263>  LBG_CORE_QAT_EXT_D  I17
  U7C1   AF3  VSS<257>  LBG_CORE_QAT_EXT_D  I17
  U7C1   AF5  VSS<261>  LBG_CORE_QAT_EXT_D  I17
  U7C1   AF9  VSS<260>  LBG_CORE_QAT_EXT_D  I17
  U7C1   AF13  VSS<262>  LBG_CORE_QAT_EXT_D  I17
  U7C1   AF17  VSS<259>  LBG_CORE_QAT_EXT_D  I17
  U7C1   AF24  VSS<258>  LBG_CORE_QAT_EXT_D  I17
  U7C1   AF50  VSS<323>  LBG_CORE_QAT_EXT_D  I17
  U7C1   AF68  VSS<256>  LBG_CORE_QAT_EXT_D  I17
  U7C1   AG26  VSS<255>  LBG_CORE_QAT_EXT_D  I17
  U7C1   AG30  VSS<254>  LBG_CORE_QAT_EXT_D  I17
  U7C1   AG41  VSS<253>  LBG_CORE_QAT_EXT_D  I17
  U7C1   AG43  VSS<252>  LBG_CORE_QAT_EXT_D  I17
  U7C1   AG46  VSS<322>  LBG_CORE_QAT_EXT_D  I17
  U7C1   AG52  VSS<251>  LBG_CORE_QAT_EXT_D  I17
  U7C1   AG56  VSS<250>  LBG_CORE_QAT_EXT_D  I17
  U7C1   AG59  VSS<249>  LBG_CORE_QAT_EXT_D  I17
  U7C1   AG66  VSS<248>  LBG_CORE_QAT_EXT_D  I17
  U7C1   AH20  VSS<247>  LBG_CORE_QAT_EXT_D  I17
  U7C1   AJ5  VSS<232>  LBG_CORE_QAT_EXT_D  I17
  U7C1   AJ7  VSS<227>  LBG_CORE_QAT_EXT_D  I17
  U7C1   AJ11  VSS<246>  LBG_CORE_QAT_EXT_D  I17
  U7C1   AJ15  VSS<242>  LBG_CORE_QAT_EXT_D  I17
  U7C1   AJ18  VSS<241>  LBG_CORE_QAT_EXT_D  I17
  U7C1   AJ22  VSS<240>  LBG_CORE_QAT_EXT_D  I17
  U7C1   AJ26  VSS<239>  LBG_CORE_QAT_EXT_D  I17
  U7C1   AJ30  VSS<238>  LBG_CORE_QAT_EXT_D  I17
  U7C1   AJ32  VSS<245>  LBG_CORE_QAT_EXT_D  I17
  U7C1   AJ34  VSS<237>  LBG_CORE_QAT_EXT_D  I17
  U7C1   AJ36  VSS<236>  LBG_CORE_QAT_EXT_D  I17
  U7C1   AJ37  VSS<235>  LBG_CORE_QAT_EXT_D  I17
  U7C1   AJ39  VSS<234>  LBG_CORE_QAT_EXT_D  I17
  U7C1   AJ41  VSS<233>  LBG_CORE_QAT_EXT_D  I17
  U7C1   AJ45  VSS<328>  LBG_CORE_QAT_EXT_D  I17
  U7C1   AJ52  VSS<231>  LBG_CORE_QAT_EXT_D  I17
  U7C1   AJ56  VSS<244>  LBG_CORE_QAT_EXT_D  I17
  U7C1   AJ59  VSS<230>  LBG_CORE_QAT_EXT_D  I17
  U7C1   AJ66  VSS<229>  LBG_CORE_QAT_EXT_D  I17
  U7C1   AJ68  VSS<228>  LBG_CORE_QAT_EXT_D  I17
  U7C1   AK26  VSS<226>  LBG_CORE_QAT_EXT_D  I17
  U7C1   AK30  VSS<243>  LBG_CORE_QAT_EXT_D  I17
  U7C1   AK41  VSS<225>  LBG_CORE_QAT_EXT_D  I17
  U7C1   AK46  VSS<224>  LBG_CORE_QAT_EXT_D  I17
  U7C1   AK48  VSS<223>  LBG_CORE_QAT_EXT_D  I17
  U7C1   AK58  VSS<222>  LBG_CORE_QAT_EXT_D  I17
  U7C1   AK61  VSS<221>  LBG_CORE_QAT_EXT_D  I17
  U7C1   AK69  VSS<220>  LBG_CORE_QAT_EXT_D  I17
  U7C1   AK71  VSS<219>  LBG_CORE_QAT_EXT_D  I17
  U7C1   AL5  VSS<217>  LBG_CORE_QAT_EXT_D  I17
  U7C1   AL22  VSS<218>  LBG_CORE_QAT_EXT_D  I17
  U7C1   AL52  VSS<216>  LBG_CORE_QAT_EXT_D  I17
  U7C1   AL59  VSS<215>  LBG_CORE_QAT_EXT_D  I17
  U7C1   AL68  VSS<214>  LBG_CORE_QAT_EXT_D  I16
  U7C1   AL70  VSS<213>  LBG_CORE_QAT_EXT_D  I16
  U7C1   AL72  VSS<212>  LBG_CORE_QAT_EXT_D  I16
  U7C1   AM26  VSS<211>  LBG_CORE_QAT_EXT_D  I16
  U7C1   AM30  VSS<210>  LBG_CORE_QAT_EXT_D  I16
  U7C1   AM41  VSS<209>  LBG_CORE_QAT_EXT_D  I16
  U7C1   AM46  VSS<208>  LBG_CORE_QAT_EXT_D  I16
  U7C1   AN5  VSS<202>  LBG_CORE_QAT_EXT_D  I16
  U7C1   AN9  VSS<200>  LBG_CORE_QAT_EXT_D  I16
  U7C1   AN13  VSS<207>  LBG_CORE_QAT_EXT_D  I16
  U7C1   AN17  VSS<206>  LBG_CORE_QAT_EXT_D  I16
  U7C1   AN20  VSS<203>  LBG_CORE_QAT_EXT_D  I16
  U7C1   AN58  VSS<201>  LBG_CORE_QAT_EXT_D  I16
  U7C1   AN68  VSS<205>  LBG_CORE_QAT_EXT_D  I16
  U7C1   AP2  VSS<199>  LBG_CORE_QAT_EXT_D  I16
  U7C1   AP4  VSS<196>  LBG_CORE_QAT_EXT_D  I16
  U7C1   AP22  VSS<204>  LBG_CORE_QAT_EXT_D  I16
  U7C1   AP26  VSS<198>  LBG_CORE_QAT_EXT_D  I16
  U7C1   AP30  VSS<197>  LBG_CORE_QAT_EXT_D  I16
  U7C1   AP41  VSS<195>  LBG_CORE_QAT_EXT_D  I16
  U7C1   AP46  VSS<194>  LBG_CORE_QAT_EXT_D  I16
  U7C1   AP52  VSS<193>  LBG_CORE_QAT_EXT_D  I16
  U7C1   AP66  VSS<192>  LBG_CORE_QAT_EXT_D  I16
  U7C1   AR5  VSS<191>  LBG_CORE_QAT_EXT_D  I16
  U7C1   AR50  VSS<190>  LBG_CORE_QAT_EXT_D  I16
  U7C1   AR58  VSS<189>  LBG_CORE_QAT_EXT_D  I16
  U7C1   AR65  VSS<188>  LBG_CORE_QAT_EXT_D  I16
  U7C1   AR68  VSS<187>  LBG_CORE_QAT_EXT_D  I16
  U7C1   AR70  VSS<186>  LBG_CORE_QAT_EXT_D  I16
  U7C1   AR72  VSS<185>  LBG_CORE_QAT_EXT_D  I16
  U7C1   AT7  VSS<184>  LBG_CORE_QAT_EXT_D  I16
  U7C1   AT11  VSS<183>  LBG_CORE_QAT_EXT_D  I16
  U7C1   AT15  VSS<182>  LBG_CORE_QAT_EXT_D  I16
  U7C1   AT18  VSS<181>  LBG_CORE_QAT_EXT_D  I16
  U7C1   AT22  VSS<180>  LBG_CORE_QAT_EXT_D  I16
  U7C1   AT26  VSS<179>  LBG_CORE_QAT_EXT_D  I16
  U7C1   AT30  VSS<178>  LBG_CORE_QAT_EXT_D  I16
  U7C1   AT37  VSS<451>  LBG_CORE_QAT_EXT_D  I13
  U7C1   AT41  VSS<177>  LBG_CORE_QAT_EXT_D  I16
  U7C1   AT46  VSS<176>  LBG_CORE_QAT_EXT_D  I16
  U7C1   AT59  VSS<175>  LBG_CORE_QAT_EXT_D  I16
  U7C1   AU26  VSS<174>  LBG_CORE_QAT_EXT_D  I16
  U7C1   AU30  VSS<173>  LBG_CORE_QAT_EXT_D  I16
  U7C1   AU41  VSS<171>  LBG_CORE_QAT_EXT_D  I16
  U7C1   AU46  VSS<170>  LBG_CORE_QAT_EXT_D  I16
  U7C1   AU50  VSS<169>  LBG_CORE_QAT_EXT_D  I16
  U7C1   AU54  VSS<168>  LBG_CORE_QAT_EXT_D  I16
  U7C1   AU61  VSS<167>  LBG_CORE_QAT_EXT_D  I16
  U7C1   AV5  VSS<166>  LBG_CORE_QAT_EXT_D  I16
  U7C1   AV22  VSS<165>  LBG_CORE_QAT_EXT_D  I16
  U7C1   AV59  VSS<164>  LBG_CORE_QAT_EXT_D  I16
  U7C1   AV68  VSS<163>  LBG_CORE_QAT_EXT_D  I16
  U7C1   AW9  VSS<162>  LBG_CORE_QAT_EXT_D  I16
  U7C1   AW13  VSS<161>  LBG_CORE_QAT_EXT_D  I16
  U7C1   AW17  VSS<160>  LBG_CORE_QAT_EXT_D  I16
  U7C1   AW26  VSS<159>  LBG_CORE_QAT_EXT_D  I16
  U7C1   AW30  VSS<158>  LBG_CORE_QAT_EXT_D  I16
  U7C1   AW32  VSS<157>  LBG_CORE_QAT_EXT_D  I16
  U7C1   AW34  VSS<156>  LBG_CORE_QAT_EXT_D  I16
  U7C1   AW36  VSS<155>  LBG_CORE_QAT_EXT_D  I16
  U7C1   AW37  VSS<154>  LBG_CORE_QAT_EXT_D  I16
  U7C1   AW39  VSS<153>  LBG_CORE_QAT_EXT_D  I16
  U7C1   AW41  VSS<152>  LBG_CORE_QAT_EXT_D  I16
  U7C1   AW46  VSS<151>  LBG_CORE_QAT_EXT_D  I16
  U7C1   AW50  VSS<150>  LBG_CORE_QAT_EXT_D  I16
  U7C1   AW58  VSS<149>  LBG_CORE_QAT_EXT_D  I16
  U7C1   AW61  VSS<148>  LBG_CORE_QAT_EXT_D  I16
  U7C1   AY5  VSS<147>  LBG_CORE_QAT_EXT_D  I16
  U7C1   AY22  VSS<146>  LBG_CORE_QAT_EXT_D  I16
  U7C1   AY56  VSS<145>  LBG_CORE_QAT_EXT_D  I16
  U7C1   AY63  VSS<144>  LBG_CORE_QAT_EXT_D  I16
  U7C1   AY68  VSS<143>  LBG_CORE_QAT_EXT_D  I16
  U7C1   B12  VSS<442>  LBG_CORE_QAT_EXT_D  I13
  U7C1   B19  VSS<441>  LBG_CORE_QAT_EXT_D  I13
  U7C1   B25  VSS<440>  LBG_CORE_QAT_EXT_D  I13
  U7C1   B27  VSS<439>  LBG_CORE_QAT_EXT_D  I13
  U7C1   B47  VSS<438>  LBG_CORE_QAT_EXT_D  I13
  U7C1   BA50  VSS<142>  LBG_CORE_QAT_EXT_D  I16
  U7C1   BA54  VSS<141>  LBG_CORE_QAT_EXT_D  I16
  U7C1   BA58  VSS<140>  LBG_CORE_QAT_EXT_D  I16
  U7C1   BB5  VSS<139>  LBG_CORE_QAT_EXT_D  I16
  U7C1   BB7  VSS<138>  LBG_CORE_QAT_EXT_D  I16
  U7C1   BB11  VSS<137>  LBG_CORE_QAT_EXT_D  I16
  U7C1   BB15  VSS<136>  LBG_CORE_QAT_EXT_D  I16
  U7C1   BB18  VSS<135>  LBG_CORE_QAT_EXT_D  I16
  U7C1   BB22  VSS<134>  LBG_CORE_QAT_EXT_D  I16
  U7C1   BB44  VSS<133>  LBG_CORE_QAT_EXT_D  I16
  U7C1   BB48  VSS<452>  LBG_CORE_QAT_EXT_D  I13
  U7C1   BB59  VSS<132>  LBG_CORE_QAT_EXT_D  I16
  U7C1   BB66  VSS<131>  LBG_CORE_QAT_EXT_D  I16
  U7C1   BB68  VSS<130>  LBG_CORE_QAT_EXT_D  I16
  U7C1   BB70  VSS<129>  LBG_CORE_QAT_EXT_D  I16
  U7C1   BB72  VSS<128>  LBG_CORE_QAT_EXT_D  I16
  U7C1   BC69  VSS<127>  LBG_CORE_QAT_EXT_D  I16
  U7C1   BC71  VSS<126>  LBG_CORE_QAT_EXT_D  I16
  U7C1   BD5  VSS<121>  LBG_CORE_QAT_EXT_D  I16
  U7C1   BD24  VSS<125>  LBG_CORE_QAT_EXT_D  I16
  U7C1   BD27  VSS<124>  LBG_CORE_QAT_EXT_D  I16
  U7C1   BD31  VSS<123>  LBG_CORE_QAT_EXT_D  I16
  U7C1   BD35  VSS<122>  LBG_CORE_QAT_EXT_D  I16
  U7C1   BD50  VSS<120>  LBG_CORE_QAT_EXT_D  I16
  U7C1   BD54  VSS<119>  LBG_CORE_QAT_EXT_D  I16
  U7C1   BD68  VSS<118>  LBG_CORE_QAT_EXT_D  I16
  U7C1   BE29  VSS<117>  LBG_CORE_QAT_EXT_D  I16
  U7C1   BE33  VSS<116>  LBG_CORE_QAT_EXT_D  I16
  U7C1   BE37  VSS<115>  LBG_CORE_QAT_EXT_D  I16
  U7C1   BE56  VSS<114>  LBG_CORE_QAT_EXT_D  I16
  U7C1   BE59  VSS<113>  LBG_CORE_QAT_EXT_D  I16
  U7C1   BE63  VSS<112>  LBG_CORE_QAT_EXT_D  I16
  U7C1   BE66  VSS<111>  LBG_CORE_QAT_EXT_D  I16
  U7C1   BF5  VSS<101>  LBG_CORE_QAT_EXT_D  I16
  U7C1   BF9  VSS<95>  LBG_CORE_QAT_EXT_D  I16
  U7C1   BF13  VSS<110>  LBG_CORE_QAT_EXT_D  I16
  U7C1   BF17  VSS<109>  LBG_CORE_QAT_EXT_D  I16
  U7C1   BF20  VSS<106>  LBG_CORE_QAT_EXT_D  I16
  U7C1   BF24  VSS<105>  LBG_CORE_QAT_EXT_D  I16
  U7C1   BF27  VSS<104>  LBG_CORE_QAT_EXT_D  I16
  U7C1   BF38  VSS<103>  LBG_CORE_QAT_EXT_D  I16
  U7C1   BF42  VSS<102>  LBG_CORE_QAT_EXT_D  I16
  U7C1   BF50  VSS<100>  LBG_CORE_QAT_EXT_D  I16
  U7C1   BF54  VSS<108>  LBG_CORE_QAT_EXT_D  I16
  U7C1   BF58  VSS<99>  LBG_CORE_QAT_EXT_D  I16
  U7C1   BF61  VSS<98>  LBG_CORE_QAT_EXT_D  I16
  U7C1   BF65  VSS<97>  LBG_CORE_QAT_EXT_D  I16
  U7C1   BF68  VSS<96>  LBG_CORE_QAT_EXT_D  I16
  U7C1   BG33  VSS<94>  LBG_CORE_QAT_EXT_D  I16
  U7C1   BG44  VSS<107>  LBG_CORE_QAT_EXT_D  I16
  U7C1   BG48  VSS<93>  LBG_CORE_QAT_EXT_D  I16
  U7C1   BG59  VSS<92>  LBG_CORE_QAT_EXT_D  I16
  U7C1   BG63  VSS<91>  LBG_CORE_QAT_EXT_D  I16
  U7C1   BH27  VSS<90>  LBG_CORE_QAT_EXT_D  I16
  U7C1   BH38  VSS<89>  LBG_CORE_QAT_EXT_D  I16
  U7C1   BH42  VSS<88>  LBG_CORE_QAT_EXT_D  I16
  U7C1   BH46  VSS<87>  LBG_CORE_QAT_EXT_D  I16
  U7C1   BH54  VSS<86>  LBG_CORE_QAT_EXT_D  I16
  U7C1   BJ1  VSS<85>  LBG_CORE_QAT_EXT_D  I16
  U7C1   BJ3  VSS<78>  LBG_CORE_QAT_EXT_D  I16
  U7C1   BJ5  VSS<83>  LBG_CORE_QAT_EXT_D  I16
  U7C1   BJ7  VSS<82>  LBG_CORE_QAT_EXT_D  I16
  U7C1   BJ11  VSS<84>  LBG_CORE_QAT_EXT_D  I16
  U7C1   BJ15  VSS<81>  LBG_CORE_QAT_EXT_D  I16
  U7C1   BJ18  VSS<80>  LBG_CORE_QAT_EXT_D  I16
  U7C1   BJ26  VSS<79>  LBG_CORE_QAT_EXT_D  I16
  U7C1   BJ33  VSS<77>  LBG_CORE_QAT_EXT_D  I16
  U7C1   BJ52  VSS<76>  LBG_CORE_QAT_EXT_D  I16
  U7C1   BJ68  VSS<75>  LBG_CORE_QAT_EXT_D  I16
  U7C1   BK24  VSS<74>  LBG_CORE_QAT_EXT_D  I15
  U7C1   BK27  VSS<73>  LBG_CORE_QAT_EXT_D  I15
  U7C1   BK31  VSS<72>  LBG_CORE_QAT_EXT_D  I15
  U7C1   BK35  VSS<71>  LBG_CORE_QAT_EXT_D  I15
  U7C1   BK38  VSS<70>  LBG_CORE_QAT_EXT_D  I15
  U7C1   BK42  VSS<69>  LBG_CORE_QAT_EXT_D  I15
  U7C1   BK50  VSS<68>  LBG_CORE_QAT_EXT_D  I15
  U7C1   BL5  VSS<63>  LBG_CORE_QAT_EXT_D  I15
  U7C1   BL22  VSS<67>  LBG_CORE_QAT_EXT_D  I15
  U7C1   BL37  VSS<64>  LBG_CORE_QAT_EXT_D  I15
  U7C1   BL40  VSS<66>  LBG_CORE_QAT_EXT_D  I15
  U7C1   BL63  VSS<62>  LBG_CORE_QAT_EXT_D  I15
  U7C1   BL68  VSS<65>  LBG_CORE_QAT_EXT_D  I15
  U7C1   BL70  VSS<61>  LBG_CORE_QAT_EXT_D  I15
  U7C1   BL72  VSS<60>  LBG_CORE_QAT_EXT_D  I15
  U7C1   BM9  VSS<51>  LBG_CORE_QAT_EXT_D  I15
  U7C1   BM13  VSS<59>  LBG_CORE_QAT_EXT_D  I15
  U7C1   BM17  VSS<58>  LBG_CORE_QAT_EXT_D  I15
  U7C1   BM46  VSS<56>  LBG_CORE_QAT_EXT_D  I15
  U7C1   BM50  VSS<55>  LBG_CORE_QAT_EXT_D  I15
  U7C1   BM58  VSS<54>  LBG_CORE_QAT_EXT_D  I15
  U7C1   BM69  VSS<53>  LBG_CORE_QAT_EXT_D  I15
  U7C1   BM71  VSS<52>  LBG_CORE_QAT_EXT_D  I15
  U7C1   BN1  VSS<476>  LBG_CORE_QAT_EXT_D  I13
  U7C1   BN5  VSS<48>  LBG_CORE_QAT_EXT_D  I15
  U7C1   BN22  VSS<50>  LBG_CORE_QAT_EXT_D  I15
  U7C1   BN37  VSS<57>  LBG_CORE_QAT_EXT_D  I15
  U7C1   BN52  VSS<47>  LBG_CORE_QAT_EXT_D  I15
  U7C1   BN59  VSS<49>  LBG_CORE_QAT_EXT_D  I15
  U7C1   BN66  VSS<46>  LBG_CORE_QAT_EXT_D  I15
  U7C1   BN72  VSS<475>  LBG_CORE_QAT_EXT_D  I13
  U7C1   BP69  VSS<494>  LBG_CORE_QAT_EXT_D  I13
  U7C1   BR1  VSS<464>  LBG_CORE_QAT_EXT_D  I13
  U7C1   BR3  VSS<487>  LBG_CORE_QAT_EXT_D  I13
  U7C1   BR6  VSS<40>  LBG_CORE_QAT_EXT_D  I15
  U7C1   BR20  VSS<45>  LBG_CORE_QAT_EXT_D  I15
  U7C1   BR50  VSS<44>  LBG_CORE_QAT_EXT_D  I15
  U7C1   BR54  VSS<42>  LBG_CORE_QAT_EXT_D  I15
  U7C1   BR58  VSS<41>  LBG_CORE_QAT_EXT_D  I15
  U7C1   BR70  VSS<491>  LBG_CORE_QAT_EXT_D  I13
  U7C1   BR72  VSS<457>  LBG_CORE_QAT_EXT_D  I13
  U7C1   BT8  VSS<43>  LBG_CORE_QAT_EXT_D  I15
  U7C1   BT66  VSS<39>  LBG_CORE_QAT_EXT_D  I15
  U7C1   BT69  VSS<493>  LBG_CORE_QAT_EXT_D  I13
  U7C1   BU1  VSS<465>  LBG_CORE_QAT_EXT_D  I13
  U7C1   BU3  VSS<488>  LBG_CORE_QAT_EXT_D  I13
  U7C1   BU9  VSS<12>  LBG_CORE_QAT_EXT_D  I15
  U7C1   BU11  VSS<37>  LBG_CORE_QAT_EXT_D  I15
  U7C1   BU13  VSS<38>  LBG_CORE_QAT_EXT_D  I15
  U7C1   BU15  VSS<35>  LBG_CORE_QAT_EXT_D  I15
  U7C1   BU18  VSS<34>  LBG_CORE_QAT_EXT_D  I15
  U7C1   BU20  VSS<33>  LBG_CORE_QAT_EXT_D  I15
  U7C1   BU22  VSS<32>  LBG_CORE_QAT_EXT_D  I15
  U7C1   BU24  VSS<31>  LBG_CORE_QAT_EXT_D  I15
  U7C1   BU26  VSS<30>  LBG_CORE_QAT_EXT_D  I15
  U7C1   BU28  VSS<29>  LBG_CORE_QAT_EXT_D  I15
  U7C1   BU30  VSS<28>  LBG_CORE_QAT_EXT_D  I15
  U7C1   BU32  VSS<27>  LBG_CORE_QAT_EXT_D  I15
  U7C1   BU34  VSS<26>  LBG_CORE_QAT_EXT_D  I15
  U7C1   BU37  VSS<25>  LBG_CORE_QAT_EXT_D  I15
  U7C1   BU39  VSS<24>  LBG_CORE_QAT_EXT_D  I15
  U7C1   BU41  VSS<23>  LBG_CORE_QAT_EXT_D  I15
  U7C1   BU43  VSS<22>  LBG_CORE_QAT_EXT_D  I15
  U7C1   BU45  VSS<21>  LBG_CORE_QAT_EXT_D  I15
  U7C1   BU48  VSS<20>  LBG_CORE_QAT_EXT_D  I15
  U7C1   BU50  VSS<19>  LBG_CORE_QAT_EXT_D  I15
  U7C1   BU52  VSS<18>  LBG_CORE_QAT_EXT_D  I15
  U7C1   BU54  VSS<17>  LBG_CORE_QAT_EXT_D  I15
  U7C1   BU57  VSS<16>  LBG_CORE_QAT_EXT_D  I15
  U7C1   BU59  VSS<15>  LBG_CORE_QAT_EXT_D  I15
  U7C1   BU61  VSS<14>  LBG_CORE_QAT_EXT_D  I15
  U7C1   BU63  VSS<13>  LBG_CORE_QAT_EXT_D  I15
  U7C1   BU70  VSS<492>  LBG_CORE_QAT_EXT_D  I13
  U7C1   BU72  VSS<456>  LBG_CORE_QAT_EXT_D  I13
  U7C1   BV40  VSS<11>  LBG_CORE_QAT_EXT_D  I15
  U7C1   BV49  VSS<36>  LBG_CORE_QAT_EXT_D  I15
  U7C1   BW1  VSS<466>  LBG_CORE_QAT_EXT_D  I13
  U7C1   BW15  VSS<10>  LBG_CORE_QAT_EXT_D  I15
  U7C1   BW18  VSS<9>  LBG_CORE_QAT_EXT_D  I15
  U7C1   BW26  VSS<8>  LBG_CORE_QAT_EXT_D  I15
  U7C1   BW52  VSS<7>  LBG_CORE_QAT_EXT_D  I15
  U7C1   BW70  VSS<455>  LBG_CORE_QAT_EXT_D  I13
  U7C1   BW72  VSS<454>  LBG_CORE_QAT_EXT_D  I13
  U7C1   BY40  VSS<6>  LBG_CORE_QAT_EXT_D  I15
  U7C1   BY49  VSS<5>  LBG_CORE_QAT_EXT_D  I15
  U7C1    C3  VSS<463>  LBG_CORE_QAT_EXT_D  I13
  U7C1   C22  VSS<437>  LBG_CORE_QAT_EXT_D  I13
  U7C1   C30  VSS<436>  LBG_CORE_QAT_EXT_D  I13
  U7C1   C34  VSS<435>  LBG_CORE_QAT_EXT_D  I13
  U7C1   C37  VSS<434>  LBG_CORE_QAT_EXT_D  I13
  U7C1   C41  VSS<433>  LBG_CORE_QAT_EXT_D  I13
  U7C1   C65  VSS<432>  LBG_CORE_QAT_EXT_D  I13
  U7C1   C72  VSS<462>  LBG_CORE_QAT_EXT_D  I13
  U7C1   CA3  VSS<467>  LBG_CORE_QAT_EXT_D  I13
  U7C1   CA5  VSS<469>  LBG_CORE_QAT_EXT_D  I13
  U7C1   CA7  VSS<470>  LBG_CORE_QAT_EXT_D  I13
  U7C1   CA9  VSS<471>  LBG_CORE_QAT_EXT_D  I13
  U7C1   CA15  VSS<4>  LBG_CORE_QAT_EXT_D  I15
  U7C1   CA18  VSS<3>  LBG_CORE_QAT_EXT_D  I15
  U7C1   CA26  VSS<2>  LBG_CORE_QAT_EXT_D  I15
  U7C1   CA50  VSS<1>  LBG_CORE_QAT_EXT_D  I15
  U7C1   CA52  VSS<0>  LBG_CORE_QAT_EXT_D  I15
  U7C1   CA65  VSS<472>  LBG_CORE_QAT_EXT_D  I13
  U7C1   CA66  VSS<473>  LBG_CORE_QAT_EXT_D  I13
  U7C1   CA68  VSS<474>  LBG_CORE_QAT_EXT_D  I13
  U7C1   CA70  VSS<453>  LBG_CORE_QAT_EXT_D  I13
  U7C1   D12  VSS<431>  LBG_CORE_QAT_EXT_D  I13
  U7C1   D16  VSS<430>  LBG_CORE_QAT_EXT_D  I13
  U7C1   D19  VSS<429>  LBG_CORE_QAT_EXT_D  I13
  U7C1   D25  VSS<428>  LBG_CORE_QAT_EXT_D  I13
  U7C1   D27  VSS<427>  LBG_CORE_QAT_EXT_D  I13
  U7C1   D47  VSS<424>  LBG_CORE_QAT_EXT_D  I13
  U7C1    E1  VSS<461>  LBG_CORE_QAT_EXT_D  I13
  U7C1    E3  VSS<485>  LBG_CORE_QAT_EXT_D  I13
  U7C1    E6  VSS<402>  LBG_CORE_QAT_EXT_D  I13
  U7C1    E9  VSS<398>  LBG_CORE_QAT_EXT_D  I13
  U7C1   E11  VSS<423>  LBG_CORE_QAT_EXT_D  I13
  U7C1   E13  VSS<422>  LBG_CORE_QAT_EXT_D  I13
  U7C1   E15  VSS<421>  LBG_CORE_QAT_EXT_D  I13
  U7C1   E20  VSS<420>  LBG_CORE_QAT_EXT_D  I13
  U7C1   E22  VSS<419>  LBG_CORE_QAT_EXT_D  I13
  U7C1   E24  VSS<418>  LBG_CORE_QAT_EXT_D  I13
  U7C1   E26  VSS<417>  LBG_CORE_QAT_EXT_D  I13
  U7C1   E28  VSS<416>  LBG_CORE_QAT_EXT_D  I13
  U7C1   E30  VSS<415>  LBG_CORE_QAT_EXT_D  I13
  U7C1   E32  VSS<414>  LBG_CORE_QAT_EXT_D  I13
  U7C1   E34  VSS<413>  LBG_CORE_QAT_EXT_D  I13
  U7C1   E37  VSS<412>  LBG_CORE_QAT_EXT_D  I13
  U7C1   E39  VSS<411>  LBG_CORE_QAT_EXT_D  I13
  U7C1   E41  VSS<410>  LBG_CORE_QAT_EXT_D  I13
  U7C1   E43  VSS<409>  LBG_CORE_QAT_EXT_D  I13
  U7C1   E45  VSS<408>  LBG_CORE_QAT_EXT_D  I13
  U7C1   E48  VSS<407>  LBG_CORE_QAT_EXT_D  I13
  U7C1   E50  VSS<406>  LBG_CORE_QAT_EXT_D  I13
  U7C1   E52  VSS<405>  LBG_CORE_QAT_EXT_D  I13
  U7C1   E54  VSS<404>  LBG_CORE_QAT_EXT_D  I13
  U7C1   E57  VSS<403>  LBG_CORE_QAT_EXT_D  I13
  U7C1   E59  VSS<426>  LBG_CORE_QAT_EXT_D  I13
  U7C1   E61  VSS<401>  LBG_CORE_QAT_EXT_D  I13
  U7C1   E63  VSS<400>  LBG_CORE_QAT_EXT_D  I13
  U7C1   E65  VSS<425>  LBG_CORE_QAT_EXT_D  I13
  U7C1   E70  VSS<489>  LBG_CORE_QAT_EXT_D  I13
  U7C1   E72  VSS<460>  LBG_CORE_QAT_EXT_D  I13
  U7C1    F3  VSS<486>  LBG_CORE_QAT_EXT_D  I13
  U7C1   F70  VSS<490>  LBG_CORE_QAT_EXT_D  I13
  U7C1    G1  VSS<459>  LBG_CORE_QAT_EXT_D  I13
  U7C1    G6  VSS<393>  LBG_CORE_QAT_EXT_D  I13
  U7C1   G22  VSS<397>  LBG_CORE_QAT_EXT_D  I13
  U7C1   G29  VSS<396>  LBG_CORE_QAT_EXT_D  I13
  U7C1   G37  VSS<395>  LBG_CORE_QAT_EXT_D  I13
  U7C1   G48  VSS<394>  LBG_CORE_QAT_EXT_D  I13
  U7C1   G59  VSS<399>  LBG_CORE_QAT_EXT_D  I13
  U7C1   G63  VSS<392>  LBG_CORE_QAT_EXT_D  I13
  U7C1   G66  VSS<391>  LBG_CORE_QAT_EXT_D  I13
  U7C1   G72  VSS<458>  LBG_CORE_QAT_EXT_D  I13
  U7C1   H58  VSS<390>  LBG_CORE_QAT_EXT_D  I13
  U7C1   H65  VSS<386>  LBG_CORE_QAT_EXT_D  I13
  U7C1    J1  VSS<478>  LBG_CORE_QAT_EXT_D  I13
  U7C1    J5  VSS<388>  LBG_CORE_QAT_EXT_D  I13
  U7C1    J7  VSS<387>  LBG_CORE_QAT_EXT_D  I13
  U7C1   J11  VSS<385>  LBG_CORE_QAT_EXT_D  I13
  U7C1   J15  VSS<384>  LBG_CORE_QAT_EXT_D  I13
  U7C1   J18  VSS<270>  LBG_CORE_QAT_EXT_D  I17
  U7C1   J22  VSS<383>  LBG_CORE_QAT_EXT_D  I13
  U7C1   J29  VSS<389>  LBG_CORE_QAT_EXT_D  I13
  U7C1   J37  VSS<382>  LBG_CORE_QAT_EXT_D  I13
  U7C1   J44  VSS<381>  LBG_CORE_QAT_EXT_D  I13
  U7C1   J59  VSS<380>  LBG_CORE_QAT_EXT_D  I13
  U7C1   J68  VSS<379>  LBG_CORE_QAT_EXT_D  I13
  U7C1   J70  VSS<378>  LBG_CORE_QAT_EXT_D  I13
  U7C1   J72  VSS<477>  LBG_CORE_QAT_EXT_D  I13
  U7C1   K54  VSS<377>  LBG_CORE_QAT_EXT_D  I13
  U7C1   K69  VSS<376>  LBG_CORE_QAT_EXT_D  I13
  U7C1   K71  VSS<375>  LBG_CORE_QAT_EXT_D  I13
  U7C1    L5  VSS<374>  LBG_CORE_QAT_EXT_D  I13
  U7C1   L68  VSS<373>  LBG_CORE_QAT_EXT_D  I13
  U7C1    M2  VSS<372>  LBG_CORE_QAT_EXT_D  I13
  U7C1    M4  VSS<366>  LBG_CORE_QAT_EXT_D  I13
  U7C1   M22  VSS<371>  LBG_CORE_QAT_EXT_D  I13
  U7C1   M26  VSS<370>  LBG_CORE_QAT_EXT_D  I13
  U7C1   M29  VSS<369>  LBG_CORE_QAT_EXT_D  I13
  U7C1   M33  VSS<368>  LBG_CORE_QAT_EXT_D  I13
  U7C1   M37  VSS<367>  LBG_CORE_QAT_EXT_D  I13
  U7C1   M40  VSS<365>  LBG_CORE_QAT_EXT_D  I13
  U7C1   M44  VSS<362>  LBG_CORE_QAT_EXT_D  I13
  U7C1   M48  VSS<361>  LBG_CORE_QAT_EXT_D  I13
  U7C1    N5  VSS<351>  LBG_CORE_QAT_EXT_D  I17
  U7C1    N9  VSS<348>  LBG_CORE_QAT_EXT_D  I17
  U7C1   N13  VSS<360>  LBG_CORE_QAT_EXT_D  I13
  U7C1   N17  VSS<359>  LBG_CORE_QAT_EXT_D  I13
  U7C1   N20  VSS<358>  LBG_CORE_QAT_EXT_D  I13
  U7C1   N24  VSS<357>  LBG_CORE_QAT_EXT_D  I13
  U7C1   N27  VSS<356>  LBG_CORE_QAT_EXT_D  I13
  U7C1   N31  VSS<355>  LBG_CORE_QAT_EXT_D  I13
  U7C1   N35  VSS<354>  LBG_CORE_QAT_EXT_D  I17
  U7C1   N38  VSS<353>  LBG_CORE_QAT_EXT_D  I17
  U7C1   N42  VSS<364>  LBG_CORE_QAT_EXT_D  I13
  U7C1   N46  VSS<352>  LBG_CORE_QAT_EXT_D  I17
  U7C1   N50  VSS<363>  LBG_CORE_QAT_EXT_D  I13
  U7C1   N68  VSS<349>  LBG_CORE_QAT_EXT_D  I17
  U7C1   P63  VSS<346>  LBG_CORE_QAT_EXT_D  I17
  U7C1    R5  VSS<343>  LBG_CORE_QAT_EXT_D  I17
  U7C1   R27  VSS<345>  LBG_CORE_QAT_EXT_D  I17
  U7C1   R38  VSS<350>  LBG_CORE_QAT_EXT_D  I17
  U7C1   R50  VSS<342>  LBG_CORE_QAT_EXT_D  I17
  U7C1   R54  VSS<341>  LBG_CORE_QAT_EXT_D  I17
  U7C1   R58  VSS<339>  LBG_CORE_QAT_EXT_D  I17
  U7C1   R68  VSS<338>  LBG_CORE_QAT_EXT_D  I17
  U7C1    T7  VSS<324>  LBG_CORE_QAT_EXT_D  I17
  U7C1   T11  VSS<337>  LBG_CORE_QAT_EXT_D  I17
  U7C1   T15  VSS<336>  LBG_CORE_QAT_EXT_D  I17
  U7C1   T18  VSS<335>  LBG_CORE_QAT_EXT_D  I17
  U7C1   T22  VSS<334>  LBG_CORE_QAT_EXT_D  I17
  U7C1   T26  VSS<333>  LBG_CORE_QAT_EXT_D  I17
  U7C1   T29  VSS<332>  LBG_CORE_QAT_EXT_D  I17
  U7C1   T33  VSS<331>  LBG_CORE_QAT_EXT_D  I17
  U7C1   T37  VSS<330>  LBG_CORE_QAT_EXT_D  I17
  U7C1   T40  VSS<329>  LBG_CORE_QAT_EXT_D  I17
  U7C1   T48  VSS<327>  LBG_CORE_QAT_EXT_D  I17
  U7C1   T52  VSS<326>  LBG_CORE_QAT_EXT_D  I17
  U7C1   T56  VSS<340>  LBG_CORE_QAT_EXT_D  I17
  U7C1   T66  VSS<325>  LBG_CORE_QAT_EXT_D  I17
  U7C1   U42  VSS<344>  LBG_CORE_QAT_EXT_D  I17
  U7C1   U58  VSS<321>  LBG_CORE_QAT_EXT_D  I17
  U7C1    V5  VSS<318>  LBG_CORE_QAT_EXT_D  I17
  U7C1   V26  VSS<320>  LBG_CORE_QAT_EXT_D  I17
  U7C1   V48  VSS<319>  LBG_CORE_QAT_EXT_D  I17
  U7C1   V52  VSS<317>  LBG_CORE_QAT_EXT_D  I17
  U7C1   V66  VSS<315>  LBG_CORE_QAT_EXT_D  I17
  U7C1   V68  VSS<314>  LBG_CORE_QAT_EXT_D  I17
  U7C1    W9  VSS<306>  LBG_CORE_QAT_EXT_D  I17
  U7C1   W13  VSS<313>  LBG_CORE_QAT_EXT_D  I17
  U7C1   W17  VSS<312>  LBG_CORE_QAT_EXT_D  I17
  U7C1   W20  VSS<311>  LBG_CORE_QAT_EXT_D  I17
  U7C1   W24  VSS<310>  LBG_CORE_QAT_EXT_D  I17
  U7C1   W58  VSS<316>  LBG_CORE_QAT_EXT_D  I17
  U7C1   W61  VSS<307>  LBG_CORE_QAT_EXT_D  I17
  U7C1    Y5  VSS<302>  LBG_CORE_QAT_EXT_D  I17
  U7C1   Y22  VSS<305>  LBG_CORE_QAT_EXT_D  I17
  U7C1   Y27  VSS<304>  LBG_CORE_QAT_EXT_D  I17
  U7C1   Y43  VSS<308>  LBG_CORE_QAT_EXT_D  I17
  U7C1   Y48  VSS<303>  LBG_CORE_QAT_EXT_D  I17
  U7C1   Y52  VSS<301>  LBG_CORE_QAT_EXT_D  I17
  U7C1   Y59  VSS<300>  LBG_CORE_QAT_EXT_D  I17
  U7C1   Y63  VSS<299>  LBG_CORE_QAT_EXT_D  I17
  U7C1   Y68  VSS<298>  LBG_CORE_QAT_EXT_D  I17
  U7C1   Y70  VSS<449>  LBG_CORE_QAT_EXT_D  I13
  U7C1   Y72  VSS<450>  LBG_CORE_QAT_EXT_D  I13
  U7D2     7  GND<0>  GTL2014_SM  I32
  U7D2     8  GND<1>  GTL2014_SM  I32
  U7D2    11  GND<2>  GTL2014_SM  I32
  U7D3     2    GND  ADM1085_SMT  I70
  U7F1    10    GND  W25Q256_XSOI  I146
  U8D4     1     A0  AT24C64     I49
  U8D4     2     A1  AT24C64     I49
  U8D7    B2  GND<0>  LCMXO2_A_256BGA  I14
  U8D7   B15  GND<1>  LCMXO2_A_256BGA  I14
  U8D7    C3  GND<2>  LCMXO2_A_256BGA  I14
  U8D7   C14  GND<3>  LCMXO2_A_256BGA  I14
  U8D7    D4  GND<4>  LCMXO2_A_256BGA  I14
  U8D7   D13  GND<5>  LCMXO2_A_256BGA  I14
  U8D7    E5  GND<6>  LCMXO2_A_256BGA  I14
  U8D7   E12  GND<7>  LCMXO2_A_256BGA  I14
  U8D7    F6  GND<8>  LCMXO2_A_256BGA  I14
  U8D7   F11  GND<9>  LCMXO2_A_256BGA  I14
  U8D7    H8  GND<10>  LCMXO2_A_256BGA  I14
  U8D7    H9  GND<11>  LCMXO2_A_256BGA  I14
  U8D7    J8  GND<12>  LCMXO2_A_256BGA  I14
  U8D7    J9  GND<13>  LCMXO2_A_256BGA  I14
  U8D7    L6  GND<14>  LCMXO2_A_256BGA  I14
  U8D7   L11  GND<15>  LCMXO2_A_256BGA  I14
  U8D7    M5  GND<16>  LCMXO2_A_256BGA  I14
  U8D7   M12  GND<17>  LCMXO2_A_256BGA  I14
  U8D7    N4  GND<18>  LCMXO2_A_256BGA  I14
  U8D7   N13  GND<19>  LCMXO2_A_256BGA  I14
  U8D7    P3  GND<20>  LCMXO2_A_256BGA  I14
  U8D7   P14  GND<21>  LCMXO2_A_256BGA  I14
  U8D7    R2  GND<22>  LCMXO2_A_256BGA  I14
  U8D7   R15  GND<23>  LCMXO2_A_256BGA  I14
  U8D8     5    GND  TPS3700_SM  I104
  U8F1     8    GND  PI3B3257A_TSSOPLF  I74
  U8F1    15     EN  PI3B3257A_TSSOPLF  I74
  U8F2    10    GND  W25Q128_SKT16  I32
  U9A5     4      B  74CBTLV1G125  I185
  U9B4     5    GND  TMP421_TSSOP   I1
  U9E1     4    VSS  M25PE16_SM   I1
  U9F1     4    GND  FSA3357_SM  I75
  U9F2     4    GND  FSA3357_SM  I74
  U9F4   AA18  PLLVSS<0>  AST1250_BGA  I11
  U9F4   AA19  PLLVSS<1>  AST1250_BGA  I11
  U9F4    B8  RGMIICK  AST1250_BGA   I1
  U9F4    B9  RGMII2RXCTL_GPIOV3  AST1250_BGA   I1
  U9F4   D11  RGMII1RXCTL_GPIOU5  AST1250_BGA   I1
  U9F4   D21  PEAGND<0>  AST1250_BGA  I11
  U9F4   D22  PEAGND<1>  AST1250_BGA  I11
  U9F4   H21  NC<0>  AST1250_BGA  I11
  U9F4   H22  NC<1>  AST1250_BGA  I11
  U9F4    J9  GND<5>  AST1250_BGA  I11
  U9F4   J10  GND<0>  AST1250_BGA  I11
  U9F4   J11  GND<1>  AST1250_BGA  I11
  U9F4   J12  GND<2>  AST1250_BGA  I11
  U9F4   J13  GND<3>  AST1250_BGA  I11
  U9F4   J14  GND<4>  AST1250_BGA  I11
  U9F4    K9  GND<11>  AST1250_BGA  I11
  U9F4   K10  GND<6>  AST1250_BGA  I11
  U9F4   K11  GND<7>  AST1250_BGA  I11
  U9F4   K12  GND<8>  AST1250_BGA  I11
  U9F4   K13  GND<9>  AST1250_BGA  I11
  U9F4   K14  GND<10>  AST1250_BGA  I11
  U9F4    L9  GND<17>  AST1250_BGA  I11
  U9F4   L10  GND<12>  AST1250_BGA  I11
  U9F4   L11  GND<13>  AST1250_BGA  I11
  U9F4   L12  GND<14>  AST1250_BGA  I11
  U9F4   L13  GND<15>  AST1250_BGA  I11
  U9F4   L14  GND<16>  AST1250_BGA  I11
  U9F4    M1  ADC9_GPIX1  AST1250_BGA   I1
  U9F4    M2  ADC8_GPIX0  AST1250_BGA   I1
  U9F4    M9  GND<23>  AST1250_BGA  I11
  U9F4   M10  GND<18>  AST1250_BGA  I11
  U9F4   M11  GND<19>  AST1250_BGA  I11
  U9F4   M12  GND<20>  AST1250_BGA  I11
  U9F4   M13  GND<21>  AST1250_BGA  I11
  U9F4   M14  GND<22>  AST1250_BGA  I11
  U9F4    N1  ADC14_GPIX6  AST1250_BGA   I1
  U9F4    N2  ADC13_GPIX5  AST1250_BGA   I1
  U9F4    N3  ADC12_GPIX4  AST1250_BGA   I1
  U9F4    N4  ADC11_GPIX3  AST1250_BGA   I1
  U9F4    N5  ADC10_GPIX2  AST1250_BGA   I1
  U9F4    N9  GND<29>  AST1250_BGA  I11
  U9F4   N10  GND<24>  AST1250_BGA  I11
  U9F4   N11  GND<25>  AST1250_BGA  I11
  U9F4   N12  GND<26>  AST1250_BGA  I11
  U9F4   N13  GND<27>  AST1250_BGA  I11
  U9F4   N14  GND<28>  AST1250_BGA  I11
  U9F4    P4  ADCAVSS  AST1250_BGA  I11
  U9F4    P5  ADC15_GPIX7  AST1250_BGA   I1
  U9F4    P9  GND<35>  AST1250_BGA  I11
  U9F4   P10  GND<30>  AST1250_BGA  I11
  U9F4   P11  GND<31>  AST1250_BGA  I11
  U9F4   P12  GND<32>  AST1250_BGA  I11
  U9F4   P13  GND<33>  AST1250_BGA  I11
  U9F4   P14  GND<34>  AST1250_BGA  I11
  U9F4    R5  DACAVSS  AST1250_BGA  I11
  U9F4   V18  PLLVSS<2>  AST1250_BGA  I11
  U9F4   Y19  USB2AVSS  AST1250_BGA  I11
  U9F5    A9  VSS<0>  K4B1G16_BGA1   I1
  U9F5    B1  VSSQ<0>  K4B1G16_BGA1   I1
  U9F5    B3  VSS<1>  K4B1G16_BGA1   I1
  U9F5    B9  VSSQ<1>  K4B1G16_BGA1   I1
  U9F5    D1  VSSQ<2>  K4B1G16_BGA1   I1
  U9F5    D8  VSSQ<3>  K4B1G16_BGA1   I1
  U9F5    E1  VSS<2>  K4B1G16_BGA1   I1
  U9F5    E2  VSSQ<4>  K4B1G16_BGA1   I1
  U9F5    E8  VSSQ<5>  K4B1G16_BGA1   I1
  U9F5    F9  VSSQ<6>  K4B1G16_BGA1   I1
  U9F5    G1  VSSQ<7>  K4B1G16_BGA1   I1
  U9F5    G8  VSS<3>  K4B1G16_BGA1   I1
  U9F5    G9  VSSQ<8>  K4B1G16_BGA1   I1
  U9F5    J2  VSS<4>  K4B1G16_BGA1   I1
  U9F5    J8  VSS<5>  K4B1G16_BGA1   I1
  U9F5    M1  VSS<6>  K4B1G16_BGA1   I1
  U9F5    M9  VSS<7>  K4B1G16_BGA1   I1
  U9F5    P1  VSS<8>  K4B1G16_BGA1   I1
  U9F5    P9  VSS<9>  K4B1G16_BGA1   I1
  U9F5    T1  VSS<10>  K4B1G16_BGA1   I1
  U9F5    T9  VSS<11>  K4B1G16_BGA1   I1
  U9G1     7  GND<0>  GTL2014_SM   I1
  U9G1     8  GND<1>  GTL2014_SM   I1
  U9G1    11  GND<2>  GTL2014_SM   I1
  U9P1     5    GND  TPS3700_SM  I163
  U9P2     5    GND  TPS3700_SM  I200
  VR1D1    2      A  ZENER_SM    I99
  XBT8G1    3      N  VERT_BATT_3PIN_PIP  I51
  Y3F1     3    GND  OSC_C_6P10  I72
  Y6F1     3    GND  OSC_C_6P10  I71
  Y9F2     2    GND  OSC_C_SM4   I250

GND_LAN_TRCT1234_C   @BASEBOARD_FAB2_LIB.BASEBOARD_FAB2(SCH_1):GND_LAN_TRCT1234_C
  C9G4     1      A  CAP_A       I46
  C9G5     1      A  CAP_0402    I48
  C9G6     1      A  CAP_A       I47
  JA9G1   R1  TRCT3  CONN17_H71061002_PIP1  I109
  JA9G1   R6  TRCT2  CONN17_H71061002_PIP1  I109
  JA9G1   R7  TRCT4  CONN17_H71061002_PIP1  I109
  JA9G1  R12  TRCT1  CONN17_H71061002_PIP1  I109

GND_NIC         @BASEBOARD_FAB2_LIB.BASEBOARD_FAB2(SCH_1):GND_NIC
  JA9G1  MH1    MH1  CONN17_H71061002_PIP1  I109
  JA9G1  MH2    MH2  CONN17_H71061002_PIP1  I109
  R1U3     2      B  RES         I114
  R1U51    2      B  RES         I112

H_CPU0_ABC_MEMHOT_LVT3_R_N   @BASEBOARD_FAB2_LIB.BASEBOARD_FAB2(SCH_1):H_CPU0_ABC_MEMHOT_LVT3_R_N
  R1U59    1      A  RES         I74
  U9G1     9     A3  GTL2014_SM   I1

H_CPU0_BMCINIT   @BASEBOARD_FAB2_LIB.BASEBOARD_FAB2(SCH_1):H_CPU0_BMCINIT
  R6D7     2      B  RES         I31
  R6D16    2      B  RES         I299
  U5D1   BD23  BMCINIT  SKX_EXT_B_BGA1  I259

H_CPU0_CATERR_G_N   @BASEBOARD_FAB2_LIB.BASEBOARD_FAB2(SCH_1):H_CPU0_CATERR_G_N
  R3P59    1      A  RES         I97
  R4R2     2      B  RES         I101
  U5D1   AL14  CATERR_N  SKX_EXT_B_BGA1  I259

H_CPU0_DEF_MEMHOT_LVT3_R_N   @BASEBOARD_FAB2_LIB.BASEBOARD_FAB2(SCH_1):H_CPU0_DEF_MEMHOT_LVT3_R_N
  R9G33    1      A  RES         I73
  U9G1    10     A2  GTL2014_SM   I1

H_CPU0_ERR0_G_N   @BASEBOARD_FAB2_LIB.BASEBOARD_FAB2(SCH_1):H_CPU0_ERR0_G_N
  R2T17    1      A  RES         I23
  U5D1   AJ12  ERROR_N<0>  SKX_EXT_B_BGA1  I259

H_CPU0_ERR1_G_N   @BASEBOARD_FAB2_LIB.BASEBOARD_FAB2(SCH_1):H_CPU0_ERR1_G_N
  R2T32    1      A  RES         I15
  U5D1   AK11  ERROR_N<1>  SKX_EXT_B_BGA1  I259

H_CPU0_ERR2_G_N   @BASEBOARD_FAB2_LIB.BASEBOARD_FAB2(SCH_1):H_CPU0_ERR2_G_N
  R2T40    1      A  RES         I93
  U5D1   AL12  ERROR_N<2>  SKX_EXT_B_BGA1  I259

H_CPU0_FAST_WAKE   @BASEBOARD_FAB2_LIB.BASEBOARD_FAB2(SCH_1):H_CPU0_FAST_WAKE
  Q2T1     3      C  NPN_SM      I330
  Q2T2     1   GATE  FET_N       I340
  R2T5     2      B  RES         I326

H_CPU0_FAST_WAKE_B_N   @BASEBOARD_FAB2_LIB.BASEBOARD_FAB2(SCH_1):H_CPU0_FAST_WAKE_B_N
  Q2T1     1      B  NPN_SM      I330
  R4R1     2      B  RES         I368

H_CPU0_FAST_WAKE_LVT3_N   @BASEBOARD_FAB2_LIB.BASEBOARD_FAB2(SCH_1):H_CPU0_FAST_WAKE_LVT3_N
  Q2T2     3    DRN  FET_N       I340
  R2T7     2      B  RES         I327
  U7C1   BV47  GPP_D10_SSATA_DEVSLP4  LBG_CORE_QAT_EXT_D  I115
  U9F4   C17  GPIOF7_RXD4  AST1250_BGA  I100

H_CPU0_FAST_WAKE_N   @BASEBOARD_FAB2_LIB.BASEBOARD_FAB2(SCH_1):H_CPU0_FAST_WAKE_N
  R3D18    1      A  RES         I33
  R4R1     1      A  RES         I368
  R4R4     2      B  RES         I42
  U5D1   AF15  PM_FAST_WAKE_N  SKX_EXT_B_BGA1  I259

H_CPU0_FIVR_FAULT_G   @BASEBOARD_FAB2_LIB.BASEBOARD_FAB2(SCH_1):H_CPU0_FIVR_FAULT_G
  U5D1   AU14  FIVR_FAULT  SKX_EXT_B_BGA1  I204
  U7D2     3     B1  GTL2014_SM  I32

H_CPU0_MEMABC_MEMHOT   @BASEBOARD_FAB2_LIB.BASEBOARD_FAB2(SCH_1):H_CPU0_MEMABC_MEMHOT
  Q3U1     5  GATE<0>  FET_N_DUAL_SMLF  I89
  Q3U1     6  DRAIN<0>  FET_N_DUAL_SMLF  I49
  R7G7     2      B  RES         I51

H_CPU0_MEMABC_MEMHOT_G_N   @BASEBOARD_FAB2_LIB.BASEBOARD_FAB2(SCH_1):H_CPU0_MEMABC_MEMHOT_G_N
  Q2U1     6  DRAIN<0>  FET_N_DUAL_SMLF  I28
  Q3U1     3  DRAIN<0>  FET_N_DUAL_SMLF  I89
  R2U40    2      B  RES         I53
  R2U51    2      B  RES         I51
  R4P17    1      A  RES         I58
  R9G34    1      A  RES         I45
  U5D1   AH13  MEM_HOT_C012_N  SKX_EXT_B_BGA1  I259

H_CPU0_MEMABC_MEMHOT_G_PCH_N   @BASEBOARD_FAB2_LIB.BASEBOARD_FAB2(SCH_1):H_CPU0_MEMABC_MEMHOT_G_PCH_N
  R2U49    1      A  RES         I66
  R2U51    1      A  RES         I51

H_CPU0_MEMABC_MEMHOT_G_R_N   @BASEBOARD_FAB2_LIB.BASEBOARD_FAB2(SCH_1):H_CPU0_MEMABC_MEMHOT_G_R_N
  R9G34    2      B  RES         I45
  U9G1     6     B3  GTL2014_SM   I1

H_CPU0_MEMABC_MEMHOT_LVT3_BMC_N   @BASEBOARD_FAB2_LIB.BASEBOARD_FAB2(SCH_1):H_CPU0_MEMABC_MEMHOT_LVT3_BMC_N
  R2U47    2      B  RES         I79
  U9F4    A2  GPIOC2_SD1DAT0_SCL11  AST1250_BGA  I100

H_CPU0_MEMABC_MEMHOT_LVT3_K_N   @BASEBOARD_FAB2_LIB.BASEBOARD_FAB2(SCH_1):H_CPU0_MEMABC_MEMHOT_LVT3_K_N
  R1U46    1      A  RES          I6
  R1U59    2      B  RES         I74
  R2U49    2      B  RES         I66

H_CPU0_MEMABC_MEMHOT_LVT3_N   @BASEBOARD_FAB2_LIB.BASEBOARD_FAB2(SCH_1):H_CPU0_MEMABC_MEMHOT_LVT3_N
  R1U46    2      B  RES          I6
  R2U47    1      A  RES         I79
  R3N30    1      A  RES         I95

H_CPU0_MEMABC_MEMHOT_PCH_N   @BASEBOARD_FAB2_LIB.BASEBOARD_FAB2(SCH_1):H_CPU0_MEMABC_MEMHOT_PCH_N
  R3N30    2      B  RES         I95
  U7C1   Y15  GPP_L12_TESTCH1_D1  LBG_CORE_QAT_EXT_D  I34

H_CPU0_MEMDEF_MEMHOT   @BASEBOARD_FAB2_LIB.BASEBOARD_FAB2(SCH_1):H_CPU0_MEMDEF_MEMHOT
  Q7E1     5  GATE<0>  FET_N_DUAL_SMLF  I64
  Q7E1     6  DRAIN<0>  FET_N_DUAL_SMLF  I60
  R3R4     2      B  RES         I66

H_CPU0_MEMDEF_MEMHOT_G_N   @BASEBOARD_FAB2_LIB.BASEBOARD_FAB2(SCH_1):H_CPU0_MEMDEF_MEMHOT_G_N
  Q2U1     3  DRAIN<0>  FET_N_DUAL_SMLF  I113
  Q7E1     3  DRAIN<0>  FET_N_DUAL_SMLF  I64
  R1U56    2      B  RES         I50
  R1U58    1      A  RES         I49
  R2U41    2      B  RES         I54
  R4P20    1      A  RES         I59
  U5D1   AF13  MEM_HOT_C345_N  SKX_EXT_B_BGA1  I259

H_CPU0_MEMDEF_MEMHOT_G_PCH_N   @BASEBOARD_FAB2_LIB.BASEBOARD_FAB2(SCH_1):H_CPU0_MEMDEF_MEMHOT_G_PCH_N
  R1U56    1      A  RES         I50
  R9G27    1      A  RES         I47

H_CPU0_MEMDEF_MEMHOT_G_R_N   @BASEBOARD_FAB2_LIB.BASEBOARD_FAB2(SCH_1):H_CPU0_MEMDEF_MEMHOT_G_R_N
  R1U58    2      B  RES         I49
  U9G1     5     B2  GTL2014_SM   I1

H_CPU0_MEMDEF_MEMHOT_LVT3_BMC_N   @BASEBOARD_FAB2_LIB.BASEBOARD_FAB2(SCH_1):H_CPU0_MEMDEF_MEMHOT_LVT3_BMC_N
  R9G29    2      B  RES         I92
  U9F4    E5  GPIOC3_SD1DAT1_SDA11  AST1250_BGA  I100

H_CPU0_MEMDEF_MEMHOT_LVT3_K_N   @BASEBOARD_FAB2_LIB.BASEBOARD_FAB2(SCH_1):H_CPU0_MEMDEF_MEMHOT_LVT3_K_N
  R9G27    2      B  RES         I47
  R9G31    1      A  RES         I14
  R9G33    2      B  RES         I73

H_CPU0_MEMDEF_MEMHOT_LVT3_N   @BASEBOARD_FAB2_LIB.BASEBOARD_FAB2(SCH_1):H_CPU0_MEMDEF_MEMHOT_LVT3_N
  R9G29    1      A  RES         I92
  R9G30    1      A  RES         I98
  R9G31    2      B  RES         I14

H_CPU0_MEMDEF_MEMHOT_PCH_N   @BASEBOARD_FAB2_LIB.BASEBOARD_FAB2(SCH_1):H_CPU0_MEMDEF_MEMHOT_PCH_N
  R9G30    2      B  RES         I98
  U7C1   AD13  GPP_L13_TESTCH1_D2  LBG_CORE_QAT_EXT_D  I34

H_CPU0_MSMI_G_N   @BASEBOARD_FAB2_LIB.BASEBOARD_FAB2(SCH_1):H_CPU0_MSMI_G_N
  R6D9     2      B  RES         I64
  R7D27    1      A  RES         I68
  U5D1   AN20  MSMI_N  SKX_EXT_B_BGA1  I259

H_CPU0_PROCHOT_G_N   @BASEBOARD_FAB2_LIB.BASEBOARD_FAB2(SCH_1):H_CPU0_PROCHOT_G_N
  Q7E3     6  DRAIN<0>  FET_N_DUAL_SMLF  I52
  Q7E5     3  DRAIN<0>  FET_N_DUAL_SMLF  I59
  R2T59    1      A  RES         I107
  R2T60    1      A  RES         I103
  R2T72    2      B  RES         I143
  R4R3     2      B  RES         I79
  U5D1   AC16  PROCHOT_N  SKX_EXT_B_BGA1  I259

H_CPU0_PROCHOT_G_PCH_N   @BASEBOARD_FAB2_LIB.BASEBOARD_FAB2(SCH_1):H_CPU0_PROCHOT_G_PCH_N
  R2T59    2      B  RES         I107
  R2T71    2      B  RES         I109

H_CPU0_PROCHOT_G_R_N   @BASEBOARD_FAB2_LIB.BASEBOARD_FAB2(SCH_1):H_CPU0_PROCHOT_G_R_N
  R2T60    2      B  RES         I103
  U2T4     3     B1  GTL2014_SM  I30

H_CPU0_THERMTRIP_G_N   @BASEBOARD_FAB2_LIB.BASEBOARD_FAB2(SCH_1):H_CPU0_THERMTRIP_G_N
  R7E2     2      B  RES         I19
  U5D1   AB15  THERMTRIP_N  SKX_EXT_B_BGA1  I259
  U7D2     6     B3  GTL2014_SM  I32

H_CPU1_BMCINIT   @BASEBOARD_FAB2_LIB.BASEBOARD_FAB2(SCH_1):H_CPU1_BMCINIT
  R3D16    2      B  RES         I24
  R3D31    2      B  RES         I300
  U2D1   BD23  BMCINIT  SKX_EXT_B_BGA1  I172

H_CPU1_CATERR_G_N   @BASEBOARD_FAB2_LIB.BASEBOARD_FAB2(SCH_1):H_CPU1_CATERR_G_N
  R3P58    1      A  RES         I98
  R7P18    2      B  RES         I100
  U2D1   AL14  CATERR_N  SKX_EXT_B_BGA1  I172

H_CPU1_ERR0_G_N   @BASEBOARD_FAB2_LIB.BASEBOARD_FAB2(SCH_1):H_CPU1_ERR0_G_N
  R2T20    1      A  RES         I16
  U2D1   AJ12  ERROR_N<0>  SKX_EXT_B_BGA1  I172

H_CPU1_ERR1_G_N   @BASEBOARD_FAB2_LIB.BASEBOARD_FAB2(SCH_1):H_CPU1_ERR1_G_N
  R2T27    1      A  RES         I13
  U2D1   AK11  ERROR_N<1>  SKX_EXT_B_BGA1  I172

H_CPU1_ERR2_G_N   @BASEBOARD_FAB2_LIB.BASEBOARD_FAB2(SCH_1):H_CPU1_ERR2_G_N
  R2T44    1      A  RES         I92
  U2D1   AL12  ERROR_N<2>  SKX_EXT_B_BGA1  I172

H_CPU1_FAST_WAKE_N   @BASEBOARD_FAB2_LIB.BASEBOARD_FAB2(SCH_1):H_CPU1_FAST_WAKE_N
  R3D18    2      B  RES         I33
  R7P20    2      B  RES         I44
  U2D1   AF15  PM_FAST_WAKE_N  SKX_EXT_B_BGA1  I172

H_CPU1_FIVR_FAULT_G   @BASEBOARD_FAB2_LIB.BASEBOARD_FAB2(SCH_1):H_CPU1_FIVR_FAULT_G
  R3R2     1      A  RES         I75
  U2D1   AU14  FIVR_FAULT  SKX_EXT_B_BGA1  I169
  U3P2     3     B1  GTL2014_SM   I1

H_CPU1_GHJ_MEMHOT_LVT3_R_N   @BASEBOARD_FAB2_LIB.BASEBOARD_FAB2(SCH_1):H_CPU1_GHJ_MEMHOT_LVT3_R_N
  R9G32    1      A  RES         I72
  U9G1    12     A1  GTL2014_SM   I1

H_CPU1_KLM_MEMHOT_LVT3_R_N   @BASEBOARD_FAB2_LIB.BASEBOARD_FAB2(SCH_1):H_CPU1_KLM_MEMHOT_LVT3_R_N
  R9G28    1      A  RES         I71
  U9G1    13     A0  GTL2014_SM   I1

H_CPU1_MEMGHJ_MEMHOT   @BASEBOARD_FAB2_LIB.BASEBOARD_FAB2(SCH_1):H_CPU1_MEMGHJ_MEMHOT
  Q7E2     5  GATE<0>  FET_N_DUAL_SMLF  I75
  Q7E2     6  DRAIN<0>  FET_N_DUAL_SMLF  I69
  R3R10    2      B  RES         I79

H_CPU1_MEMGHJ_MEMHOT_G_N   @BASEBOARD_FAB2_LIB.BASEBOARD_FAB2(SCH_1):H_CPU1_MEMGHJ_MEMHOT_G_N
  Q4B2     6  DRAIN<0>  FET_N_DUAL_SMLF  I32
  Q7E2     3  DRAIN<0>  FET_N_DUAL_SMLF  I75
  R1U41    2      B  RES         I56
  R1U53    1      A  RES         I64
  R1U55    1      A  RES         I67
  R7P5     1      A  RES         I61
  U2D1   AH13  MEM_HOT_C012_N  SKX_EXT_B_BGA1  I172

H_CPU1_MEMGHJ_MEMHOT_G_PCH_N   @BASEBOARD_FAB2_LIB.BASEBOARD_FAB2(SCH_1):H_CPU1_MEMGHJ_MEMHOT_G_PCH_N
  R1U55    2      B  RES         I67
  R1U57    2      B  RES         I69

H_CPU1_MEMGHJ_MEMHOT_G_R_N   @BASEBOARD_FAB2_LIB.BASEBOARD_FAB2(SCH_1):H_CPU1_MEMGHJ_MEMHOT_G_R_N
  R1U53    2      B  RES         I64
  U9G1     3     B1  GTL2014_SM   I1

H_CPU1_MEMGHJ_MEMHOT_LVT3_BMC_N   @BASEBOARD_FAB2_LIB.BASEBOARD_FAB2(SCH_1):H_CPU1_MEMGHJ_MEMHOT_LVT3_BMC_N
  R1U54    2      B  RES         I93
  U9F4    B2  GPIOC6_SD1CD_N_SCL13  AST1250_BGA  I100

H_CPU1_MEMGHJ_MEMHOT_LVT3_K_N   @BASEBOARD_FAB2_LIB.BASEBOARD_FAB2(SCH_1):H_CPU1_MEMGHJ_MEMHOT_LVT3_K_N
  R1U36    1      A  RES         I15
  R1U57    1      A  RES         I69
  R9G32    2      B  RES         I72

H_CPU1_MEMGHJ_MEMHOT_LVT3_N   @BASEBOARD_FAB2_LIB.BASEBOARD_FAB2(SCH_1):H_CPU1_MEMGHJ_MEMHOT_LVT3_N
  R1U36    2      B  RES         I15
  R1U54    1      A  RES         I93
  R3P63    1      A  RES         I100

H_CPU1_MEMGHJ_MEMHOT_PCH_N   @BASEBOARD_FAB2_LIB.BASEBOARD_FAB2(SCH_1):H_CPU1_MEMGHJ_MEMHOT_PCH_N
  R3P63    2      B  RES         I100
  U7C1   AA13  GPP_L14_TESTCH1_D3  LBG_CORE_QAT_EXT_D  I34

H_CPU1_MEMKLM_MEMHOT   @BASEBOARD_FAB2_LIB.BASEBOARD_FAB2(SCH_1):H_CPU1_MEMKLM_MEMHOT
  Q4B1     5  GATE<0>  FET_N_DUAL_SMLF  I77
  Q4B1     6  DRAIN<0>  FET_N_DUAL_SMLF  I84
  R6M4     2      B  RES         I82

H_CPU1_MEMKLM_MEMHOT_G_N   @BASEBOARD_FAB2_LIB.BASEBOARD_FAB2(SCH_1):H_CPU1_MEMKLM_MEMHOT_G_N
  Q4B1     3  DRAIN<0>  FET_N_DUAL_SMLF  I77
  Q4B2     3  DRAIN<0>  FET_N_DUAL_SMLF  I33
  R1U35    2      B  RES         I57
  R1U60    1      A  RES         I65
  R1U62    1      A  RES         I68
  R7P21    1      A  RES         I62
  U2D1   AF13  MEM_HOT_C345_N  SKX_EXT_B_BGA1  I172

H_CPU1_MEMKLM_MEMHOT_G_PCH_N   @BASEBOARD_FAB2_LIB.BASEBOARD_FAB2(SCH_1):H_CPU1_MEMKLM_MEMHOT_G_PCH_N
  R1U61    2      B  RES         I70
  R1U62    2      B  RES         I68

H_CPU1_MEMKLM_MEMHOT_G_R_N   @BASEBOARD_FAB2_LIB.BASEBOARD_FAB2(SCH_1):H_CPU1_MEMKLM_MEMHOT_G_R_N
  R1U60    2      B  RES         I65
  U9G1     2     B0  GTL2014_SM   I1

H_CPU1_MEMKLM_MEMHOT_LVT3_BMC_N   @BASEBOARD_FAB2_LIB.BASEBOARD_FAB2(SCH_1):H_CPU1_MEMKLM_MEMHOT_LVT3_BMC_N
  R2U46    2      B  RES         I94
  U9F4    A1  GPIOC7_SD1WP_N_SDA13  AST1250_BGA  I100

H_CPU1_MEMKLM_MEMHOT_LVT3_K_N   @BASEBOARD_FAB2_LIB.BASEBOARD_FAB2(SCH_1):H_CPU1_MEMKLM_MEMHOT_LVT3_K_N
  R1U34    1      A  RES         I16
  R1U61    1      A  RES         I70
  R9G28    2      B  RES         I71

H_CPU1_MEMKLM_MEMHOT_LVT3_N   @BASEBOARD_FAB2_LIB.BASEBOARD_FAB2(SCH_1):H_CPU1_MEMKLM_MEMHOT_LVT3_N
  R1U34    2      B  RES         I16
  R2U45    1      A  RES         I102
  R2U46    1      A  RES         I94

H_CPU1_MEMKLM_MEMHOT_PCH_N   @BASEBOARD_FAB2_LIB.BASEBOARD_FAB2(SCH_1):H_CPU1_MEMKLM_MEMHOT_PCH_N
  R2U45    2      B  RES         I102
  U7C1   Y11  GPP_L15_TESTCH1_D4  LBG_CORE_QAT_EXT_D  I34

H_CPU1_MSMI_G_N   @BASEBOARD_FAB2_LIB.BASEBOARD_FAB2(SCH_1):H_CPU1_MSMI_G_N
  R7D28    1      A  RES         I67
  R7P27    2      B  RES         I65
  U2D1   AN20  MSMI_N  SKX_EXT_B_BGA1  I172

H_CPU1_PROCHOT_G_N   @BASEBOARD_FAB2_LIB.BASEBOARD_FAB2(SCH_1):H_CPU1_PROCHOT_G_N
  Q7E3     3  DRAIN<0>  FET_N_DUAL_SMLF  I51
  Q7E6     3  DRAIN<0>  FET_N_DUAL_SMLF  I69
  R2T68    1      A  RES         I102
  R2T69    1      A  RES         I108
  R2T73    2      B  RES         I144
  R7P28    2      B  RES         I106
  U2D1   AC16  PROCHOT_N  SKX_EXT_B_BGA1  I172

H_CPU1_PROCHOT_G_PCH_N   @BASEBOARD_FAB2_LIB.BASEBOARD_FAB2(SCH_1):H_CPU1_PROCHOT_G_PCH_N
  R2T69    2      B  RES         I108
  R7D43    2      B  RES         I110

H_CPU1_PROCHOT_G_R_N   @BASEBOARD_FAB2_LIB.BASEBOARD_FAB2(SCH_1):H_CPU1_PROCHOT_G_R_N
  R2T68    2      B  RES         I102
  U2T4     2     B0  GTL2014_SM  I30

H_CPU1_THERMTRIP_G_N   @BASEBOARD_FAB2_LIB.BASEBOARD_FAB2(SCH_1):H_CPU1_THERMTRIP_G_N
  R3P41    2      B  RES          I9
  U2D1   AB15  THERMTRIP_N  SKX_EXT_B_BGA1  I172
  U3P2     6     B3  GTL2014_SM   I1

H_CPU_CATERR_G_N   @BASEBOARD_FAB2_LIB.BASEBOARD_FAB2(SCH_1):H_CPU_CATERR_G_N
  R3P58    2      B  RES         I98
  R3P59    2      B  RES         I97
  U3P2     5     B2  GTL2014_SM   I1

H_CPU_ERR0_GTL_N   @BASEBOARD_FAB2_LIB.BASEBOARD_FAB2(SCH_1):H_CPU_ERR0_GTL_N
  R2T16    2      B  RES         I67
  U2T4     6     B3  GTL2014_SM  I30

H_CPU_ERR0_GTL_R_N   @BASEBOARD_FAB2_LIB.BASEBOARD_FAB2(SCH_1):H_CPU_ERR0_GTL_R_N
  R2T16    1      A  RES         I67
  R2T17    2      B  RES         I23
  R2T19    2      B  RES         I63
  R2T20    2      B  RES         I16
  R2T57    2      B  RES         I88

H_CPU_ERR0_PCH_N   @BASEBOARD_FAB2_LIB.BASEBOARD_FAB2(SCH_1):H_CPU_ERR0_PCH_N
  R2T57    1      A  RES         I88
  R2T58    1      A  RES         I94

H_CPU_ERR1_GTL_N   @BASEBOARD_FAB2_LIB.BASEBOARD_FAB2(SCH_1):H_CPU_ERR1_GTL_N
  R2T31    2      B  RES         I68
  U2T4     5     B2  GTL2014_SM  I30

H_CPU_ERR1_GTL_R_N   @BASEBOARD_FAB2_LIB.BASEBOARD_FAB2(SCH_1):H_CPU_ERR1_GTL_R_N
  R2T26    2      B  RES         I87
  R2T27    2      B  RES         I13
  R2T31    1      A  RES         I68
  R2T32    2      B  RES         I15
  R2T61    2      B  RES         I89

H_CPU_ERR1_PCH_N   @BASEBOARD_FAB2_LIB.BASEBOARD_FAB2(SCH_1):H_CPU_ERR1_PCH_N
  R2T61    1      A  RES         I89
  R2T62    1      A  RES         I93

H_CPU_ERR2_GTL_N   @BASEBOARD_FAB2_LIB.BASEBOARD_FAB2(SCH_1):H_CPU_ERR2_GTL_N
  R2T43    2      B  RES         I96
  U7D2     5     B2  GTL2014_SM  I32

H_CPU_ERR2_G_R_N   @BASEBOARD_FAB2_LIB.BASEBOARD_FAB2(SCH_1):H_CPU_ERR2_G_R_N
  R2T37    2      B  RES         I94
  R2T40    2      B  RES         I93
  R2T43    1      A  RES         I96
  R2T44    2      B  RES         I92

H_CPU_MSMI_G_N   @BASEBOARD_FAB2_LIB.BASEBOARD_FAB2(SCH_1):H_CPU_MSMI_G_N
  R7D27    2      B  RES         I68
  R7D28    2      B  RES         I67
  U7D2     2     B0  GTL2014_SM  I32

H_PMSYNC_CLK_24M   @BASEBOARD_FAB2_LIB.BASEBOARD_FAB2(SCH_1):H_PMSYNC_CLK_24M
  R4P19    2      B  RES         I219
  R7P26    2      B  RES         I156
  R8B20    2      B  RES         I110
  R8B21    1      A  RES         I124

H_PMSYNC_CLK_24M_CPU0   @BASEBOARD_FAB2_LIB.BASEBOARD_FAB2(SCH_1):H_PMSYNC_CLK_24M_CPU0
  R4P19    1      A  RES         I219
  U5D1   AT19  PMSYNC_CLK  SKX_EXT_B_BGA1  I259

H_PMSYNC_CLK_24M_CPU1   @BASEBOARD_FAB2_LIB.BASEBOARD_FAB2(SCH_1):H_PMSYNC_CLK_24M_CPU1
  R7P26    1      A  RES         I156
  U2D1   AT19  PMSYNC_CLK  SKX_EXT_B_BGA1  I172

H_PMSYNC_CLK_24M_R   @BASEBOARD_FAB2_LIB.BASEBOARD_FAB2(SCH_1):H_PMSYNC_CLK_24M_R
  R8B20    1      A  RES         I110
  U7C1   BY51  CLOCKSE_PMSYNCCLK1  LBG_CORE_QAT_EXT_D  I40

H_PM_SYNC1_GTL_R   @BASEBOARD_FAB2_LIB.BASEBOARD_FAB2(SCH_1):H_PM_SYNC1_GTL_R
  R3N9     1      A  RES         I66
  U7C1   U13  PM_SYNC  LBG_CORE_QAT_EXT_D  I73

H_PM_SYNC_GTL   @BASEBOARD_FAB2_LIB.BASEBOARD_FAB2(SCH_1):H_PM_SYNC_GTL
  R3N9     2      B  RES         I66
  R3N14    1      A  RES         I67
  R4P18    2      B  RES         I244
  R7P25    2      B  RES         I170

H_PM_SYNC_GTL_R1   @BASEBOARD_FAB2_LIB.BASEBOARD_FAB2(SCH_1):H_PM_SYNC_GTL_R1
  R4P18    1      A  RES         I244
  U5D1   AR14  PMSYNC  SKX_EXT_B_BGA1  I259

H_PM_SYNC_GTL_R2   @BASEBOARD_FAB2_LIB.BASEBOARD_FAB2(SCH_1):H_PM_SYNC_GTL_R2
  R7P25    1      A  RES         I170
  U2D1   AR14  PMSYNC  SKX_EXT_B_BGA1  I172

IRQ_BMC_PCH_NMI_STBY_N   @BASEBOARD_FAB2_LIB.BASEBOARD_FAB2(SCH_1):IRQ_BMC_PCH_NMI_STBY_N
  R8E22    2      B  RES         I215
  R8E24    1      A  RES         I214
  U7C1   BB52  GPP_E6_SATA_DEVSLP2  LBG_CORE_QAT_EXT_D  I147
  U9F4   D16  GPIOD1_SD2CMD  AST1250_BGA  I100

IRQ_BMC_PCH_NMI_STBY_R_N   @BASEBOARD_FAB2_LIB.BASEBOARD_FAB2(SCH_1):IRQ_BMC_PCH_NMI_STBY_R_N
  R8E24    2      B  RES         I214
  U7C1   BR42  GPP_D0  LBG_CORE_QAT_EXT_D  I115

IRQ_BMC_PCH_SCI_LPC_N   @BASEBOARD_FAB2_LIB.BASEBOARD_FAB2(SCH_1):IRQ_BMC_PCH_SCI_LPC_N
  R8C2     2      B  RES         I304
  U7C1   BN48  GPP_E10_USB2_OC1_N  LBG_CORE_QAT_EXT_D  I147
  U7C1   BY38  GPP_C14  LBG_CORE_QAT_EXT_D  I115
  U9F4   E14  GPIOE4_NDTR3  AST1250_BGA  I100

IRQ_BMC_PCH_SMI_LPC_N   @BASEBOARD_FAB2_LIB.BASEBOARD_FAB2(SCH_1):IRQ_BMC_PCH_SMI_LPC_N
  R8C4     2      B  RES         I286
  U7C1   AW54  GPP_E11_USB2_OC2_N  LBG_CORE_QAT_EXT_D  I147
  U7C1   CA34  GPP_C22  LBG_CORE_QAT_EXT_D  I115
  U9F4   D14  GPIOE5_NRTS3  AST1250_BGA  I100

IRQ_BOARD_BMC_ALERT_N   @BASEBOARD_FAB2_LIB.BASEBOARD_FAB2(SCH_1):IRQ_BOARD_BMC_ALERT_N
  J1C1    B5   IOB5  CONN76_H22707001_THMT1  I18
  R1C9     1      A  RES         I104
  R2N7     2      B  RES         I309
  U7C1   BW24  GPP_I5_DO_RESET_OUT_N  LBG_CORE_QAT_EXT_D  I147
  U9F4    Y1  GPIOM2_NDSR2_VPIB4  AST1250_BGA  I100

IRQ_CPU0_PROCHOT_G_N   @BASEBOARD_FAB2_LIB.BASEBOARD_FAB2(SCH_1):IRQ_CPU0_PROCHOT_G_N
  Q7E5     2  GATE<0>  FET_N_DUAL_SMLF  I111
  U7E2     4   Y<0>  TTL1G08     I117

IRQ_CPU0_VRHOT   @BASEBOARD_FAB2_LIB.BASEBOARD_FAB2(SCH_1):IRQ_CPU0_VRHOT
  Q7E5     5  GATE<0>  FET_N_DUAL_SMLF  I59
  Q7E5     6  DRAIN<0>  FET_N_DUAL_SMLF  I111
  R7E10    2      B  RES         I62

IRQ_CPU1_PROCHOT_G_N   @BASEBOARD_FAB2_LIB.BASEBOARD_FAB2(SCH_1):IRQ_CPU1_PROCHOT_G_N
  Q7E6     2  GATE<0>  FET_N_DUAL_SMLF  I112
  U7E3     4   Y<0>  TTL1G08     I118

IRQ_CPU1_VRHOT   @BASEBOARD_FAB2_LIB.BASEBOARD_FAB2(SCH_1):IRQ_CPU1_VRHOT
  Q7E6     5  GATE<0>  FET_N_DUAL_SMLF  I69
  Q7E6     6  DRAIN<0>  FET_N_DUAL_SMLF  I112
  R7E11    2      B  RES         I72

IRQ_DIMM_SAVE_LVT3   @BASEBOARD_FAB2_LIB.BASEBOARD_FAB2(SCH_1):IRQ_DIMM_SAVE_LVT3
  Q8D1     2   B<0>  NPN_DUAL    I36
  Q8D1     3   C<0>  NPN_DUAL    I35
  R8D29    2      B  RES         I26

IRQ_DIMM_SAVE_LVT3_N   @BASEBOARD_FAB2_LIB.BASEBOARD_FAB2(SCH_1):IRQ_DIMM_SAVE_LVT3_N
  Q8D1     6   C<0>  NPN_DUAL    I36
  R2P12    1      A  RES         I23
  R8D31    2      B  RES         I27
  U7C1   BW20  GPP_I4_DO_RESET_IN_N  LBG_CORE_QAT_EXT_D  I147
  U9F4   U18  GPIOG7_FLWP_N  AST1250_BGA   I1

IRQ_DIMM_SAVE_N   @BASEBOARD_FAB2_LIB.BASEBOARD_FAB2(SCH_1):IRQ_DIMM_SAVE_N
  Q6F1     3    DRN  FET_N       I18
  R6F1     1      A  RES          I4
  R6F2     1      A  RES          I6
  R6F3     2      B  RES          I7
  R6F4     1      A  RES          I3
  R6F5     1      A  RES          I5
  R8D30    1      A  RES         I34

IRQ_DIMM_SAVE_R_N   @BASEBOARD_FAB2_LIB.BASEBOARD_FAB2(SCH_1):IRQ_DIMM_SAVE_R_N
  Q8D1     5   B<0>  NPN_DUAL    I35
  R8D30    2      B  RES         I34

IRQ_FORCE_NM_THROTTLE_N   @BASEBOARD_FAB2_LIB.BASEBOARD_FAB2(SCH_1):IRQ_FORCE_NM_THROTTLE_N
  R2P4     2      B  RES         I74
  R2T41    1      A  RES         I203
  U7C1   BA17  GPP_G20_SSATA_DEVSLP0  LBG_CORE_QAT_EXT_D  I147
  U7C1   BY42  GPP_D9_SSATA_DEVSLP3  LBG_CORE_QAT_EXT_D  I115
  U8E1     1   A<0>  TTL08_QFN15  I10

IRQ_FORCE_NM_THROTTLE_R_N   @BASEBOARD_FAB2_LIB.BASEBOARD_FAB2(SCH_1):IRQ_FORCE_NM_THROTTLE_R_N
  R2P3     2      B  RES          I2
  R2P4     1      A  RES         I74
  U8D3     4      Y  TTL1G07_A_SOP   I4

IRQ_HFI0_CPU0_LVT2_N   @BASEBOARD_FAB2_LIB.BASEBOARD_FAB2(SCH_1):IRQ_HFI0_CPU0_LVT2_N
  J8B1     8    IO8  SCONN24_H46321001_SM   I1
  R8B10    2      B  RES         I16
  U5D1   BP19  CD_HFI0_INT_N  SKX_EXT_B_BGA1  I61

IRQ_HFI1_CPU0_LVT2_N   @BASEBOARD_FAB2_LIB.BASEBOARD_FAB2(SCH_1):IRQ_HFI1_CPU0_LVT2_N
  J8B1    16   IO16  SCONN24_H46321001_SM   I1
  R8B17    2      B  RES         I18
  U5D1   BM21  CD_HFI1_INT_N  SKX_EXT_B_BGA1  I61

IRQ_HSC_FAULT_N   @BASEBOARD_FAB2_LIB.BASEBOARD_FAB2(SCH_1):IRQ_HSC_FAULT_N
  R1D30    2      B  RES         I110
  R2M4     2      B  RES         I284
  U7C1   BJ44  GPP_D2  LBG_CORE_QAT_EXT_D  I115
  U9F4   A20  GPIOF2_NDSR4_SIOPWRGD  AST1250_BGA  I100

IRQ_HSC_FAULT_R_N   @BASEBOARD_FAB2_LIB.BASEBOARD_FAB2(SCH_1):IRQ_HSC_FAULT_R_N
  EU1D2    6  FAULT_N  ADM1278_SM  I10
  R1D30    1      A  RES         I110

IRQ_LOM_ALERT_N   @BASEBOARD_FAB2_LIB.BASEBOARD_FAB2(SCH_1):IRQ_LOM_ALERT_N
  EU9E1   35  SMB_ALRT_N  SPRINGVILLE_SM1  I72
  R9E7     2      B  RES         I193
  U7C1   BY47  GPP_D11_SSATA_DEVSLP5  LBG_CORE_QAT_EXT_D  I115
  U9F4   E16  GPIOF6_TXD4  AST1250_BGA  I100

IRQ_LPC_SERIRQ_N   @BASEBOARD_FAB2_LIB.BASEBOARD_FAB2(SCH_1):IRQ_LPC_SERIRQ_N
  R2T24    1      A  RES         I520
  R7D3     2      B  RES         I243
  U7C1    P2  GPP_A6_SERIRQ_ESPI_CS1_N  LBG_CORE_QAT_EXT_D  I115

IRQ_LPC_SERIRQ_R   @BASEBOARD_FAB2_LIB.BASEBOARD_FAB2(SCH_1):IRQ_LPC_SERIRQ_R
  R2T24    2      B  RES         I520
  U9F4   E17  LSIRQ_N  AST1250_BGA  I347

IRQ_LVC3_WAKE_N   @BASEBOARD_FAB2_LIB.BASEBOARD_FAB2(SCH_1):IRQ_LVC3_WAKE_N
  R3N13    2      B  RES         I71
  R8E17    2      B  RES          I2
  U7C1    K9  WAKE_N  LBG_CORE_QAT_EXT_D  I73

IRQ_LVC3_WAKE_R_N   @BASEBOARD_FAB2_LIB.BASEBOARD_FAB2(SCH_1):IRQ_LVC3_WAKE_R_N
  R8E17    1      A  RES          I2
  U8E4     4      Y  TTL1G126_A_SOT   I1

IRQ_MEZZ_LAN_ALERT_N   @BASEBOARD_FAB2_LIB.BASEBOARD_FAB2(SCH_1):IRQ_MEZZ_LAN_ALERT_N
  J9B3    28   IO28  SCONN120_A28699018_SM  I336
  R8F23    2      B  RES         I296
  U7C1   BW45  GPP_D3  LBG_CORE_QAT_EXT_D  I115
  U9F4   A19  GPIOF5_NRTS4_SIOSCI_N  AST1250_BGA  I100

IRQ_OC_DETECT_N   @BASEBOARD_FAB2_LIB.BASEBOARD_FAB2(SCH_1):IRQ_OC_DETECT_N
  R1D23    2      B  RES         I191
  R9P15    2      B  RES         I198
  U1D1     2      A  TTL1G126_A_SOT  I103
  U1D2     1   OUTB  TPS3700_SM  I170
  U7C1   AG7  GPP_F0_SATAXPCIE3_SATAGP3  LBG_CORE_QAT_EXT_D  I147
  U9F4    T5  GPIOL1_NDCD1_VPIDE  AST1250_BGA  I100

IRQ_OOB_MGMT_RISER_ALERT_N   @BASEBOARD_FAB2_LIB.BASEBOARD_FAB2(SCH_1):IRQ_OOB_MGMT_RISER_ALERT_N
  J8G1    16   IO16  SCONN200_H68296001_SM  I258
  R2T29    2      B  RES         I298
  U7C1   BV42  GPP_D16_SML0BALERT_IE_N  LBG_CORE_QAT_EXT_D  I115
  U9F4   D17  GPIOF3_NRI4_SIOPBO_N  AST1250_BGA  I100

IRQ_PCH_NIC_ALERT_N   @BASEBOARD_FAB2_LIB.BASEBOARD_FAB2(SCH_1):IRQ_PCH_NIC_ALERT_N
  R8C25    2      B  RES         I333
  U7C1   AR17  GPP_F21_LAN_SMBALRT_N  LBG_CORE_QAT_EXT_D  I147
  U7C1   BG22  GPP_B16  LBG_CORE_QAT_EXT_D  I115
  U9F4   E13  GPIOG1_SGPSLD  AST1250_BGA  I347

IRQ_PIRQA_SPI_TPM_N   @BASEBOARD_FAB2_LIB.BASEBOARD_FAB2(SCH_1):IRQ_PIRQA_SPI_TPM_N
  R7D7     2      B  RES         I331
  R8E1     2      B  RES         I99
  U7C1   AA2  GPP_A7_PIRQA_N_ESPI_ALERT0_N  LBG_CORE_QAT_EXT_D  I115

IRQ_PVCCIN_CPU0_VRHOT_LVC3_N   @BASEBOARD_FAB2_LIB.BASEBOARD_FAB2(SCH_1):IRQ_PVCCIN_CPU0_VRHOT_LVC3_N
  R6P45    2      B  RES         I128
  U7C1   BA9  GPP_G4_FANTACH4_FANTACH4IE  LBG_CORE_QAT_EXT_D  I147
  U7E2     2   B<0>  TTL1G08     I117
  U9F4   AB6  GPIOP4_TACH12  AST1250_BGA   I1

IRQ_PVCCIN_CPU0_VRHOT_LVC3_R_N   @BASEBOARD_FAB2_LIB.BASEBOARD_FAB2(SCH_1):IRQ_PVCCIN_CPU0_VRHOT_LVC3_R_N
  EU4D4   13  VRHOT_N  PXE1610B_QFN  I155
  R4E3     2      B  RES         I111
  R6P45    1      A  RES         I128

IRQ_PVCCIN_CPU1_VRHOT_LVC3_N   @BASEBOARD_FAB2_LIB.BASEBOARD_FAB2(SCH_1):IRQ_PVCCIN_CPU1_VRHOT_LVC3_N
  R9P3     2      B  RES         I117
  U7C1   AW20  GPP_G5_FANTACH5_FANTACH5IE  LBG_CORE_QAT_EXT_D  I147
  U7E3     2   B<0>  TTL1G08     I118
  U9F4    Y7  GPIOP5_TACH13  AST1250_BGA   I1

IRQ_PVCCIN_CPU1_VRHOT_LVC3_R_N   @BASEBOARD_FAB2_LIB.BASEBOARD_FAB2(SCH_1):IRQ_PVCCIN_CPU1_VRHOT_LVC3_R_N
  EU1C2   13  VRHOT_N  PXE1610B_QFN  I130
  R1D6     2      B  RES          I6
  R9P3     1      A  RES         I117

IRQ_PVCCIO_CPU0_VRHOT_N   @BASEBOARD_FAB2_LIB.BASEBOARD_FAB2(SCH_1):IRQ_PVCCIO_CPU0_VRHOT_N
  EU3P1   11  VRHOT_N  PXE1110B_QFN  I93
  R3P18    2      B  RES         I64

IRQ_PVCCIO_CPU1_VRHOT_N   @BASEBOARD_FAB2_LIB.BASEBOARD_FAB2(SCH_1):IRQ_PVCCIO_CPU1_VRHOT_N
  EU4D5   11  VRHOT_N  PXE1110B_QFN  I96
  R4D49    2      B  RES         I63

IRQ_PVDDQ_ABC_VRHOT_LVT3_N   @BASEBOARD_FAB2_LIB.BASEBOARD_FAB2(SCH_1):IRQ_PVDDQ_ABC_VRHOT_LVT3_N
  Q3U1     2  GATE<0>  FET_N_DUAL_SMLF  I49
  R7F23    2      B  RES         I297
  U7C1   BN7  GPP_B4_CPU_GP3  LBG_CORE_QAT_EXT_D  I115
  U9F4    C4  GPIOC0_SD1CLK_SCL10  AST1250_BGA  I100

IRQ_PVDDQ_ABC_VRHOT_LVT3_R_N   @BASEBOARD_FAB2_LIB.BASEBOARD_FAB2(SCH_1):IRQ_PVDDQ_ABC_VRHOT_LVT3_R_N
  EU7G1   11  VRHOT_N  PXM1310B_QFN  I358
  R7F23    1      A  RES         I297
  R7F27    2      B  RES         I303

IRQ_PVDDQ_DEF_VRHOT_LVT3_N   @BASEBOARD_FAB2_LIB.BASEBOARD_FAB2(SCH_1):IRQ_PVDDQ_DEF_VRHOT_LVT3_N
  Q7E1     2  GATE<0>  FET_N_DUAL_SMLF  I60
  R7B1     2      B  RES         I12
  U7C1   BK17  GPP_B5_SRCCLKREQ0_N  LBG_CORE_QAT_EXT_D  I115
  U9F4    B3  GPIOC1_SD1CMD_SDA10  AST1250_BGA  I100

IRQ_PVDDQ_DEF_VRHOT_LVT3_R_N   @BASEBOARD_FAB2_LIB.BASEBOARD_FAB2(SCH_1):IRQ_PVDDQ_DEF_VRHOT_LVT3_R_N
  EU7A5   11  VRHOT_N  PXM1310B_QFN  I75
  R7B1     1      A  RES         I12
  R7B4     2      B  RES         I17

IRQ_PVDDQ_GHJ_VRHOT_LVT3_N   @BASEBOARD_FAB2_LIB.BASEBOARD_FAB2(SCH_1):IRQ_PVDDQ_GHJ_VRHOT_LVT3_N
  Q7E2     2  GATE<0>  FET_N_DUAL_SMLF  I69
  R1G8     2      B  RES         I82
  U7C1   BG18  GPP_B6_SRCCLKREQ1_N  LBG_CORE_QAT_EXT_D  I115
  U9F4    D4  GPIOC4_SD1DAT2_SCL12  AST1250_BGA  I100

IRQ_PVDDQ_GHJ_VRHOT_LVT3_R_N   @BASEBOARD_FAB2_LIB.BASEBOARD_FAB2(SCH_1):IRQ_PVDDQ_GHJ_VRHOT_LVT3_R_N
  EU1G2   11  VRHOT_N  PXM1310B_QFN  I90
  R1G8     1      A  RES         I82
  R1G11    2      B  RES         I79

IRQ_PVDDQ_KLM_VRHOT_LVT3_N   @BASEBOARD_FAB2_LIB.BASEBOARD_FAB2(SCH_1):IRQ_PVDDQ_KLM_VRHOT_LVT3_N
  Q4B1     2  GATE<0>  FET_N_DUAL_SMLF  I84
  R1B4     2      B  RES         I82
  U7C1   BR13  GPP_B7_SRCCLKREQ2_N  LBG_CORE_QAT_EXT_D  I115
  U9F4    C3  GPIOC5_SD1DAT3_SDA12  AST1250_BGA  I100

IRQ_PVDDQ_KLM_VRHOT_LVT3_R_N   @BASEBOARD_FAB2_LIB.BASEBOARD_FAB2(SCH_1):IRQ_PVDDQ_KLM_VRHOT_LVT3_R_N
  EU1B1   11  VRHOT_N  PXM1310B_QFN  I90
  R1B1     2      B  RES         I79
  R1B4     1      A  RES         I82

IRQ_PVNN_PCH_VRHOT_N   @BASEBOARD_FAB2_LIB.BASEBOARD_FAB2(SCH_1):IRQ_PVNN_PCH_VRHOT_N
  EU8A1   11  VRHOT_N  PXE1110B_QFN  I229
  R8A5     2      B  RES         I216

IRQ_SML0_ALERT_N   @BASEBOARD_FAB2_LIB.BASEBOARD_FAB2(SCH_1):IRQ_SML0_ALERT_N
  Q8E2     3    DRN  FET_N       I13
  R8C9     2      B  RES         I20
  U7C1   BW34  GPP_C5_SML0ALERT_IE_N  LBG_CORE_QAT_EXT_D  I115
  U9F4   D15  GPIOE0_NCTS3  AST1250_BGA  I100

IRQ_SML1_PMBUS_ALERT_BUF_N   @BASEBOARD_FAB2_LIB.BASEBOARD_FAB2(SCH_1):IRQ_SML1_PMBUS_ALERT_BUF_N
  R8D26    2      B  RES         I71
  U8D3     2      A  TTL1G07_A_SOP   I4
  U8D5     4      Y  TTL1G126_A_SOT  I38

IRQ_SML1_PMBUS_ALERT_N   @BASEBOARD_FAB2_LIB.BASEBOARD_FAB2(SCH_1):IRQ_SML1_PMBUS_ALERT_N
  C8D3     1      A  CAP         I42
  R1D26    2      B  RES         I109
  R2P8     2      B  RES         I52
  U7C1   C13  GPD8_SUSCLK  LBG_CORE_QAT_EXT_D  I73
  U8D5     2      A  TTL1G126_A_SOT  I38
  U9F4   B18  GPIOF4_NDTR4  AST1250_BGA  I100

IRQ_SML1_PMBUS_ALERT_R_N   @BASEBOARD_FAB2_LIB.BASEBOARD_FAB2(SCH_1):IRQ_SML1_PMBUS_ALERT_R_N
  EU1D2   13  GPO1_ALERT1_N_CONV  ADM1278_SM  I10
  J1F1    A6  GNDA6  CONN76_H22707001_THMT1  I111
  J1F3     5    IO5  CONN8_H62179001_PIP  I189
  R1D26    1      A  RES         I109

IRQ_SPI_TPM_N_R   @BASEBOARD_FAB2_LIB.BASEBOARD_FAB2(SCH_1):IRQ_SPI_TPM_N_R
  J8E1     9    IO9  SCONN11_H67026001_SM  I87
  R8E1     1      A  RES         I99

IRQ_UV_DETECT_N   @BASEBOARD_FAB2_LIB.BASEBOARD_FAB2(SCH_1):IRQ_UV_DETECT_N
  CR9P1    1      C  DIODE_SMLF  I214
  Q9P1     3  DRAIN<0>  FET_N_DUAL_SMLF  I199
  R9P4     2      B  RES         I210
  U7C1   AU58  GPP_E12_USB2_OC3_N  LBG_CORE_QAT_EXT_D  I147
  U8E1     4   A<0>  TTL08_QFN15  I11
  U9F4    U1  GPIOL0_NCTS1  AST1250_BGA  I100

IRQ_VM_INT_N    @BASEBOARD_FAB2_LIB.BASEBOARD_FAB2(SCH_1):IRQ_VM_INT_N
  R1U40    2      B  RES         I81
  U7C1   AA4  GPP_A10_CLKOUT_LPC1  LBG_CORE_QAT_EXT_D  I115

IRQ_VM_INT_R_N   @BASEBOARD_FAB2_LIB.BASEBOARD_FAB2(SCH_1):IRQ_VM_INT_R_N
  EU9G1    6  INT_N  ADC128D818_SM  I52
  R1U40    1      A  RES         I81
  R9G21    2      B  RES         I69

ISENSE_P1V05_PCH_STBY_PH1_IMON   @BASEBOARD_FAB2_LIB.BASEBOARD_FAB2(SCH_1):ISENSE_P1V05_PCH_STBY_PH1_IMON
  EU7A2   38   IOUT  IR354XX_SM  I117
  EU8A1   26  BISEN1  PXE1110B_QFN  I229

ISENSE_PVCCIN_CPU0_PH1_IMON   @BASEBOARD_FAB2_LIB.BASEBOARD_FAB2(SCH_1):ISENSE_PVCCIN_CPU0_PH1_IMON
  EU4D4   24  AISEN1  PXE1610B_QFN  I155
  EU4E1   38   IOUT  IR354XX_SM  I63

ISENSE_PVCCIN_CPU0_PH2_IMON   @BASEBOARD_FAB2_LIB.BASEBOARD_FAB2(SCH_1):ISENSE_PVCCIN_CPU0_PH2_IMON
  EU4D4   26  AISEN2  PXE1610B_QFN  I155
  EU4D6   38   IOUT  IR354XX_SM  I64

ISENSE_PVCCIN_CPU0_PH3_IMON   @BASEBOARD_FAB2_LIB.BASEBOARD_FAB2(SCH_1):ISENSE_PVCCIN_CPU0_PH3_IMON
  EU4D3   38   IOUT  IR354XX_SM  I70
  EU4D4   28  AISEN3  PXE1610B_QFN  I155

ISENSE_PVCCIN_CPU0_PH4_IMON   @BASEBOARD_FAB2_LIB.BASEBOARD_FAB2(SCH_1):ISENSE_PVCCIN_CPU0_PH4_IMON
  EU4D1   38   IOUT  IR354XX_SM  I71
  EU4D4   30  AISEN4  PXE1610B_QFN  I155

ISENSE_PVCCIN_CPU0_PH5_IMON   @BASEBOARD_FAB2_LIB.BASEBOARD_FAB2(SCH_1):ISENSE_PVCCIN_CPU0_PH5_IMON
  EU4C2   38   IOUT  IR354XX_SM  I71
  EU4D4   32  AISEN5  PXE1610B_QFN  I155

ISENSE_PVCCIN_CPU1_PH1_IMON   @BASEBOARD_FAB2_LIB.BASEBOARD_FAB2(SCH_1):ISENSE_PVCCIN_CPU1_PH1_IMON
  EU1C2   24  AISEN1  PXE1610B_QFN  I130
  EU1E2   38   IOUT  IR354XX_SM  I20

ISENSE_PVCCIN_CPU1_PH2_IMON   @BASEBOARD_FAB2_LIB.BASEBOARD_FAB2(SCH_1):ISENSE_PVCCIN_CPU1_PH2_IMON
  EU1C2   26  AISEN2  PXE1610B_QFN  I130
  EU1D4   38   IOUT  IR354XX_SM  I24

ISENSE_PVCCIN_CPU1_PH3_IMON   @BASEBOARD_FAB2_LIB.BASEBOARD_FAB2(SCH_1):ISENSE_PVCCIN_CPU1_PH3_IMON
  EU1C2   28  AISEN3  PXE1610B_QFN  I130
  EU1D3   38   IOUT  IR354XX_SM  I27

ISENSE_PVCCIN_CPU1_PH4_IMON   @BASEBOARD_FAB2_LIB.BASEBOARD_FAB2(SCH_1):ISENSE_PVCCIN_CPU1_PH4_IMON
  EU1C2   30  AISEN4  PXE1610B_QFN  I130
  EU1D1   38   IOUT  IR354XX_SM  I71

ISENSE_PVCCIN_CPU1_PH5_IMON   @BASEBOARD_FAB2_LIB.BASEBOARD_FAB2(SCH_1):ISENSE_PVCCIN_CPU1_PH5_IMON
  EU1C2   32  AISEN5  PXE1610B_QFN  I130
  EU1C3   38   IOUT  IR354XX_SM  I56

ISENSE_PVCCIO_CPU0_PH1_IMON   @BASEBOARD_FAB2_LIB.BASEBOARD_FAB2(SCH_1):ISENSE_PVCCIO_CPU0_PH1_IMON
  EU3P1   22  AISEN1  PXE1110B_QFN  I93
  EU7C1   38   IOUT  IR354XX_SM  I101

ISENSE_PVCCIO_CPU1_PH1_IMON   @BASEBOARD_FAB2_LIB.BASEBOARD_FAB2(SCH_1):ISENSE_PVCCIO_CPU1_PH1_IMON
  EU4D5   22  AISEN1  PXE1110B_QFN  I96
  EU4E2   38   IOUT  IR354XX_SM  I126

ISENSE_PVDDQ_ABC_PH1_IMON   @BASEBOARD_FAB2_LIB.BASEBOARD_FAB2(SCH_1):ISENSE_PVDDQ_ABC_PH1_IMON
  EU7G1   22  AISEN1  PXM1310B_QFN  I358
  EU7G2   38   IOUT  IR354XX_SM  I102

ISENSE_PVDDQ_ABC_PH2_IMON   @BASEBOARD_FAB2_LIB.BASEBOARD_FAB2(SCH_1):ISENSE_PVDDQ_ABC_PH2_IMON
  EU7G1   24  AISEN2  PXM1310B_QFN  I358
  EU7G3   38   IOUT  IR354XX_SM  I103

ISENSE_PVDDQ_DEF_PH1_IMON   @BASEBOARD_FAB2_LIB.BASEBOARD_FAB2(SCH_1):ISENSE_PVDDQ_DEF_PH1_IMON
  EU7A1   38   IOUT  IR354XX_SM  I106
  EU7A5   22  AISEN1  PXM1310B_QFN  I75

ISENSE_PVDDQ_DEF_PH2_IMON   @BASEBOARD_FAB2_LIB.BASEBOARD_FAB2(SCH_1):ISENSE_PVDDQ_DEF_PH2_IMON
  EU7A4   38   IOUT  IR354XX_SM  I107
  EU7A5   24  AISEN2  PXM1310B_QFN  I75

ISENSE_PVDDQ_GHJ_PH1_IMON   @BASEBOARD_FAB2_LIB.BASEBOARD_FAB2(SCH_1):ISENSE_PVDDQ_GHJ_PH1_IMON
  EU1G1   38   IOUT  IR354XX_SM  I110
  EU1G2   22  AISEN1  PXM1310B_QFN  I90

ISENSE_PVDDQ_GHJ_PH2_IMON   @BASEBOARD_FAB2_LIB.BASEBOARD_FAB2(SCH_1):ISENSE_PVDDQ_GHJ_PH2_IMON
  EU1F1   38   IOUT  IR354XX_SM  I111
  EU1G2   24  AISEN2  PXM1310B_QFN  I90

ISENSE_PVDDQ_KLM_PH1_IMON   @BASEBOARD_FAB2_LIB.BASEBOARD_FAB2(SCH_1):ISENSE_PVDDQ_KLM_PH1_IMON
  EU1A2   38   IOUT  IR354XX_SM  I101
  EU1B1   22  AISEN1  PXM1310B_QFN  I90

ISENSE_PVDDQ_KLM_PH2_IMON   @BASEBOARD_FAB2_LIB.BASEBOARD_FAB2(SCH_1):ISENSE_PVDDQ_KLM_PH2_IMON
  EU1A1   38   IOUT  IR354XX_SM  I102
  EU1B1   24  AISEN2  PXM1310B_QFN  I90

ISENSE_PVNN_PCH_PH1_IMON   @BASEBOARD_FAB2_LIB.BASEBOARD_FAB2(SCH_1):ISENSE_PVNN_PCH_PH1_IMON
  EU7A3   38   IOUT  IR354XX_SM  I116
  EU8A1   22  AISEN1  PXE1110B_QFN  I229

ISENSE_PVSA_CPU0_IMON   @BASEBOARD_FAB2_LIB.BASEBOARD_FAB2(SCH_1):ISENSE_PVSA_CPU0_IMON
  EU4C1   38   IOUT  IR354XX_SM  I46
  EU4D4   38  BISEN1  PXE1610B_QFN  I155

ISENSE_PVSA_CPU1_IMON   @BASEBOARD_FAB2_LIB.BASEBOARD_FAB2(SCH_1):ISENSE_PVSA_CPU1_IMON
  EU1C1   38   IOUT  IR354XX_SM  I51
  EU1C2   38  BISEN1  PXE1610B_QFN  I130

ISENSE_TMP421_1_BC   @BASEBOARD_FAB2_LIB.BASEBOARD_FAB2(SCH_1):ISENSE_TMP421_1_BC
  Q9B1     1      B  PNP          I3
  Q9B1     3      C  PNP          I3
  R9B5     1      A  RES          I5

ISENSE_TMP421_1_DXN   @BASEBOARD_FAB2_LIB.BASEBOARD_FAB2(SCH_1):ISENSE_TMP421_1_DXN
  C1M4     2      B  CAP          I7
  R9B5     2      B  RES          I5
  U9B4     2    DXN  TMP421_TSSOP   I1

ISENSE_TMP421_1_DXP   @BASEBOARD_FAB2_LIB.BASEBOARD_FAB2(SCH_1):ISENSE_TMP421_1_DXP
  C1M4     1      A  CAP          I7
  R9B4     2      B  RES          I6
  U9B4     1    DXP  TMP421_TSSOP   I1

ISENSE_TMP421_1_E   @BASEBOARD_FAB2_LIB.BASEBOARD_FAB2(SCH_1):ISENSE_TMP421_1_E
  Q9B1     2      E  PNP          I3
  R9B4     1      A  RES          I6

ISENSE_TMP421_2_BC   @BASEBOARD_FAB2_LIB.BASEBOARD_FAB2(SCH_1):ISENSE_TMP421_2_BC
  Q1E1     1      B  PNP         I27
  Q1E1     3      C  PNP         I27
  R9R6     1      A  RES         I26

ISENSE_TMP421_2_DXN   @BASEBOARD_FAB2_LIB.BASEBOARD_FAB2(SCH_1):ISENSE_TMP421_2_DXN
  C1E19    2      B  CAP         I24
  R9R6     2      B  RES         I26
  U1E1     2    DXN  TMP421_TSSOP  I30

ISENSE_TMP421_2_DXP   @BASEBOARD_FAB2_LIB.BASEBOARD_FAB2(SCH_1):ISENSE_TMP421_2_DXP
  C1E19    1      A  CAP         I24
  R9R5     2      B  RES         I25
  U1E1     1    DXP  TMP421_TSSOP  I30

ISENSE_TMP421_2_E   @BASEBOARD_FAB2_LIB.BASEBOARD_FAB2(SCH_1):ISENSE_TMP421_2_E
  Q1E1     2      E  PNP         I27
  R9R5     1      A  RES         I25

JTAG_BMC_TCK    @BASEBOARD_FAB2_LIB.BASEBOARD_FAB2(SCH_1):JTAG_BMC_TCK
  R8G17    1      A  RES         I25
  U9F4    F2    TCK  AST1250_BGA  I347

JTAG_BMC_TDI    @BASEBOARD_FAB2_LIB.BASEBOARD_FAB2(SCH_1):JTAG_BMC_TDI
  R8G8     1      A  RES         I17
  U9F4    F1    TDI  AST1250_BGA  I347

JTAG_BMC_TDO    @BASEBOARD_FAB2_LIB.BASEBOARD_FAB2(SCH_1):JTAG_BMC_TDO
  R7G17    1      A  RES         I37
  U9F4    G3    TDO  AST1250_BGA  I347

JTAG_BMC_TMS    @BASEBOARD_FAB2_LIB.BASEBOARD_FAB2(SCH_1):JTAG_BMC_TMS
  R8G14    1      A  RES         I20
  U9F4    G2    TMS  AST1250_BGA  I347

JTAG_BMC_TRST_N   @BASEBOARD_FAB2_LIB.BASEBOARD_FAB2(SCH_1):JTAG_BMC_TRST_N
  R8G10    1      A  RES          I7
  U9F4    E1  NTRST  AST1250_BGA  I347

JTAG_MCP_CPU0_TDI   @BASEBOARD_FAB2_LIB.BASEBOARD_FAB2(SCH_1):JTAG_MCP_CPU0_TDI
  R4R6     2      B  RES         I134
  U2M1     1     B1  NC7SB3157   I255
  U5D1   BY21  CD_TDI  SKX_EXT_B_BGA1  I61

JTAG_MCP_CPU0_TDI_R   @BASEBOARD_FAB2_LIB.BASEBOARD_FAB2(SCH_1):JTAG_MCP_CPU0_TDI_R
  C4R2     1      A  CAP_A       I246
  R4R6     1      A  RES         I134
  U4R1     4      B  74CBTLV1G125  I206

JTAG_MCP_CPU0_TDO   @BASEBOARD_FAB2_LIB.BASEBOARD_FAB2(SCH_1):JTAG_MCP_CPU0_TDO
  U1M2     1     B1  NC7SB3157   I107
  U1M6     2      A  74CBTLV1G125  I127
  U5D1   CC22  CD_TDO  SKX_EXT_B_BGA1  I61

JTAG_MCP_CPU1_TDI   @BASEBOARD_FAB2_LIB.BASEBOARD_FAB2(SCH_1):JTAG_MCP_CPU1_TDI
  R6M8     2      B  RES         I188
  U1M6     4      B  74CBTLV1G125  I127
  U2D1   BY21  CD_TDI  SKX_EXT_B_BGA1  I23
  U2M1     3     B0  NC7SB3157   I255

JTAG_MCP_CPU1_TDI_R   @BASEBOARD_FAB2_LIB.BASEBOARD_FAB2(SCH_1):JTAG_MCP_CPU1_TDI_R
  C6M6     1      A  CAP_A       I250
  R6M8     1      A  RES         I188
  U6M1     4      B  74CBTLV1G125  I190

JTAG_MCP_CPU1_TDO   @BASEBOARD_FAB2_LIB.BASEBOARD_FAB2(SCH_1):JTAG_MCP_CPU1_TDO
  U1M2     3     B0  NC7SB3157   I107
  U2D1   CC22  CD_TDO  SKX_EXT_B_BGA1  I23

JTAG_MCP_MUX_TDI   @BASEBOARD_FAB2_LIB.BASEBOARD_FAB2(SCH_1):JTAG_MCP_MUX_TDI
  J9B4     9    IO9  SCONN10_C12536004  I175
  R1M20    2      B  RES         I204
  U2M1     4      A  NC7SB3157   I255

JTAG_MCP_MUX_TDO   @BASEBOARD_FAB2_LIB.BASEBOARD_FAB2(SCH_1):JTAG_MCP_MUX_TDO
  J9B4     3    IO3  SCONN10_C12536004  I175
  R9B12    2      B  RES         I203
  U1M2     4      A  NC7SB3157   I107

JTAG_MCP_TCK    @BASEBOARD_FAB2_LIB.BASEBOARD_FAB2(SCH_1):JTAG_MCP_TCK
  R9B9     1      A  RES         I179
  R9B10    1      A  RES         I180
  R9B11    1      A  RES         I239
  U2D1   CB23  CD_TCLK  SKX_EXT_B_BGA1  I23
  U5D1   CB23  CD_TCLK  SKX_EXT_B_BGA1  I61

JTAG_MCP_TCK_R   @BASEBOARD_FAB2_LIB.BASEBOARD_FAB2(SCH_1):JTAG_MCP_TCK_R
  J9B4     1    IO1  SCONN10_C12536004  I175
  R9B10    2      B  RES         I180
  R9B11    2      B  RES         I239
  U9A5     2      A  74CBTLV1G125  I185

JTAG_MCP_TMS    @BASEBOARD_FAB2_LIB.BASEBOARD_FAB2(SCH_1):JTAG_MCP_TMS
  R1M19    2      B  RES         I202
  R1M22    2      B  RES         I195
  R9B13    1      A  RES         I240
  U2D1   CE24  CD_TMS  SKX_EXT_B_BGA1  I23
  U5D1   CE24  CD_TMS  SKX_EXT_B_BGA1  I61

JTAG_MCP_TMS_R   @BASEBOARD_FAB2_LIB.BASEBOARD_FAB2(SCH_1):JTAG_MCP_TMS_R
  J9B4     5    IO5  SCONN10_C12536004  I175
  R9B13    2      B  RES         I240

JTAG_MCP_TMS_R1   @BASEBOARD_FAB2_LIB.BASEBOARD_FAB2(SCH_1):JTAG_MCP_TMS_R1
  C1M33    1      A  CAP_A       I248
  R1M22    1      A  RES         I195
  U1M5     4      B  74CBTLV1G125  I196

JTAG_MCP_TRST_N   @BASEBOARD_FAB2_LIB.BASEBOARD_FAB2(SCH_1):JTAG_MCP_TRST_N
  J9B4     6    IO6  SCONN10_C12536004  I175
  R1M21    2      B  RES         I205
  R1M23    1      A  RES         I199
  U2D1   CD23  CD_TRST_N  SKX_EXT_B_BGA1  I23
  U5D1   CD23  CD_TRST_N  SKX_EXT_B_BGA1  I61

JTAG_PCH_GBE_CLK   @BASEBOARD_FAB2_LIB.BASEBOARD_FAB2(SCH_1):JTAG_PCH_GBE_CLK
  R8G15    1      A  RES         I24
  U7C1   BV21  GPP_I1_LAN_TCK  LBG_CORE_QAT_EXT_D  I147

JTAG_PCH_GBE_TDI   @BASEBOARD_FAB2_LIB.BASEBOARD_FAB2(SCH_1):JTAG_PCH_GBE_TDI
  R7G19    1      A  RES          I8
  U7C1   BY23  GPP_I3_LAN_TDI  LBG_CORE_QAT_EXT_D  I147

JTAG_PCH_GBE_TDO   @BASEBOARD_FAB2_LIB.BASEBOARD_FAB2(SCH_1):JTAG_PCH_GBE_TDO
  R7G16    1      A  RES         I27
  U7C1   CA20  GPP_I0_LAN_TDO  LBG_CORE_QAT_EXT_D  I147

JTAG_PCH_GBE_TMS   @BASEBOARD_FAB2_LIB.BASEBOARD_FAB2(SCH_1):JTAG_PCH_GBE_TMS
  R8G12    1      A  RES         I21
  U7C1   CA22  GPP_I2_LAN_TMS  LBG_CORE_QAT_EXT_D  I147

JTAG_PCH_GBE_TRST_N   @BASEBOARD_FAB2_LIB.BASEBOARD_FAB2(SCH_1):JTAG_PCH_GBE_TRST_N
  R8G9     1      A  RES          I9
  U7C1   CA24  GPP_I7_LAN_TRST_N  LBG_CORE_QAT_EXT_D  I147

JTAG_PCH_PLD_TCK   @BASEBOARD_FAB2_LIB.BASEBOARD_FAB2(SCH_1):JTAG_PCH_PLD_TCK
  R8G16    1      A  RES         I22
  U7C1   AL18  GPP_F6_SATA_DEVSLP4  LBG_CORE_QAT_EXT_D  I147

JTAG_PCH_PLD_TDI   @BASEBOARD_FAB2_LIB.BASEBOARD_FAB2(SCH_1):JTAG_PCH_PLD_TDI
  R7G18    1      A  RES         I13
  U7C1   AK17  GPP_F7_SATA_DEVSLP5  LBG_CORE_QAT_EXT_D  I147

JTAG_PCH_PLD_TDO   @BASEBOARD_FAB2_LIB.BASEBOARD_FAB2(SCH_1):JTAG_PCH_PLD_TDO
  R7G15    1      A  RES         I36
  U7C1   AR20  GPP_F9_SATA_DEVSLP7  LBG_CORE_QAT_EXT_D  I147

JTAG_PCH_PLD_TMS   @BASEBOARD_FAB2_LIB.BASEBOARD_FAB2(SCH_1):JTAG_PCH_PLD_TMS
  R8G11    1      A  RES         I19
  U7C1   AH9  GPP_F8_SATA_DEVSLP6  LBG_CORE_QAT_EXT_D  I147

JTAG_PLD_TCK    @BASEBOARD_FAB2_LIB.BASEBOARD_FAB2(SCH_1):JTAG_PLD_TCK
  R8G18    1      A  RES         I26
  U8D7    A7  PT16C_TCK  LCMXO2_A_256BGA  I59

JTAG_PLD_TDI    @BASEBOARD_FAB2_LIB.BASEBOARD_FAB2(SCH_1):JTAG_PLD_TDI
  R8G7     1      A  RES         I18
  U8D7    A6  PT12D_TDI  LCMXO2_A_256BGA  I59

JTAG_PLD_TDO    @BASEBOARD_FAB2_LIB.BASEBOARD_FAB2(SCH_1):JTAG_PLD_TDO
  R7G14    1      A  RES         I38
  U8D7    C6  PT12C_TDO  LCMXO2_A_256BGA  I59

JTAG_PLD_TMS    @BASEBOARD_FAB2_LIB.BASEBOARD_FAB2(SCH_1):JTAG_PLD_TMS
  R8G13    1      A  RES         I23
  U8D7    B8  PT16D_TMS  LCMXO2_A_256BGA  I59

JTAG_TCK        @BASEBOARD_FAB2_LIB.BASEBOARD_FAB2(SCH_1):JTAG_TCK
  R8G15    2      B  RES         I24
  R8G16    2      B  RES         I22
  R8G17    2      B  RES         I25
  R8G18    2      B  RES         I26
  R8G22    1      A  RES         I66

JTAG_TCK_R      @BASEBOARD_FAB2_LIB.BASEBOARD_FAB2(SCH_1):JTAG_TCK_R
  J7G2     8    IO8  CONN8_C77962004  I47
  R8G22    2      B  RES         I66
  R8G23    1      A  RES         I56

JTAG_TDI        @BASEBOARD_FAB2_LIB.BASEBOARD_FAB2(SCH_1):JTAG_TDI
  R7G18    2      B  RES         I13
  R7G19    2      B  RES          I8
  R8G7     2      B  RES         I18
  R8G8     2      B  RES         I17
  R8G19    1      A  RES         I64

JTAG_TDI_R      @BASEBOARD_FAB2_LIB.BASEBOARD_FAB2(SCH_1):JTAG_TDI_R
  J7G2     3    IO3  CONN8_C77962004  I47
  R7G23    2      B  RES         I51
  R8G19    2      B  RES         I64

JTAG_TDO        @BASEBOARD_FAB2_LIB.BASEBOARD_FAB2(SCH_1):JTAG_TDO
  R7G14    2      B  RES         I38
  R7G15    2      B  RES         I36
  R7G16    2      B  RES         I27
  R7G17    2      B  RES         I37
  R7G21    1      A  RES         I63

JTAG_TDO_R      @BASEBOARD_FAB2_LIB.BASEBOARD_FAB2(SCH_1):JTAG_TDO_R
  J7G2     2    IO2  CONN8_C77962004  I47
  R7G21    2      B  RES         I63
  R7G22    2      B  RES         I53

JTAG_TMS        @BASEBOARD_FAB2_LIB.BASEBOARD_FAB2(SCH_1):JTAG_TMS
  R8G11    2      B  RES         I19
  R8G12    2      B  RES         I21
  R8G13    2      B  RES         I23
  R8G14    2      B  RES         I20
  R8G21    1      A  RES         I65

JTAG_TMS_R      @BASEBOARD_FAB2_LIB.BASEBOARD_FAB2(SCH_1):JTAG_TMS_R
  J7G2     6    IO6  CONN8_C77962004  I47
  R8G20    2      B  RES         I50
  R8G21    2      B  RES         I65

JTAG_TRST_N     @BASEBOARD_FAB2_LIB.BASEBOARD_FAB2(SCH_1):JTAG_TRST_N
  J7G2     4    IO4  CONN8_C77962004  I47
  R8G9     2      B  RES          I9
  R8G10    2      B  RES          I7

KR_P0_OCP_RX_C_DN   @BASEBOARD_FAB2_LIB.BASEBOARD_FAB2(SCH_1):KR_P0_OCP_RX_C_DN
  C8C14    2      B  CAP_A       I86
  U7C1   BH31  LAN_RX_P0N  LBG_CORE_QAT_EXT_D  I73

KR_P0_OCP_RX_C_DP   @BASEBOARD_FAB2_LIB.BASEBOARD_FAB2(SCH_1):KR_P0_OCP_RX_C_DP
  C8C15    2      B  CAP_A       I82
  U7C1   BF31  LAN_RX_P0P  LBG_CORE_QAT_EXT_D  I73

KR_P0_OCP_RX_DN   @BASEBOARD_FAB2_LIB.BASEBOARD_FAB2(SCH_1):KR_P0_OCP_RX_DN
  C8C14    1      A  CAP_A       I86
  J8E4    53   IO53  SCONN64_H87568002_A_SMT  I27

KR_P0_OCP_RX_DP   @BASEBOARD_FAB2_LIB.BASEBOARD_FAB2(SCH_1):KR_P0_OCP_RX_DP
  C8C15    1      A  CAP_A       I82
  J8E4    52   IO52  SCONN64_H87568002_A_SMT  I27

KR_P0_OCP_TX_DN   @BASEBOARD_FAB2_LIB.BASEBOARD_FAB2(SCH_1):KR_P0_OCP_TX_DN
  J8E4    41   IO41  SCONN64_H87568002_A_SMT  I27
  U7C1   BM27  LAN_TX_P0N  LBG_CORE_QAT_EXT_D  I73

KR_P0_OCP_TX_DP   @BASEBOARD_FAB2_LIB.BASEBOARD_FAB2(SCH_1):KR_P0_OCP_TX_DP
  J8E4    40   IO40  SCONN64_H87568002_A_SMT  I27
  U7C1   BR27  LAN_TX_P0P  LBG_CORE_QAT_EXT_D  I73

KR_P1_OCP_RX_C_DN   @BASEBOARD_FAB2_LIB.BASEBOARD_FAB2(SCH_1):KR_P1_OCP_RX_C_DN
  C8C13    2      B  CAP_A       I81
  U7C1   BG29  LAN_RX_P1N  LBG_CORE_QAT_EXT_D  I73

KR_P1_OCP_RX_C_DP   @BASEBOARD_FAB2_LIB.BASEBOARD_FAB2(SCH_1):KR_P1_OCP_RX_C_DP
  C8C12    2      B  CAP_A       I80
  U7C1   BJ29  LAN_RX_P1P  LBG_CORE_QAT_EXT_D  I73

KR_P1_OCP_RX_DN   @BASEBOARD_FAB2_LIB.BASEBOARD_FAB2(SCH_1):KR_P1_OCP_RX_DN
  C8C13    1      A  CAP_A       I81
  J8E4    59   IO59  SCONN64_H87568002_A_SMT  I27

KR_P1_OCP_RX_DP   @BASEBOARD_FAB2_LIB.BASEBOARD_FAB2(SCH_1):KR_P1_OCP_RX_DP
  C8C12    1      A  CAP_A       I80
  J8E4    58   IO58  SCONN64_H87568002_A_SMT  I27

KR_P1_OCP_TX_DN   @BASEBOARD_FAB2_LIB.BASEBOARD_FAB2(SCH_1):KR_P1_OCP_TX_DN
  J8E4    47   IO47  SCONN64_H87568002_A_SMT  I27
  U7C1   BM24  LAN_TX_P1N  LBG_CORE_QAT_EXT_D  I73

KR_P1_OCP_TX_DP   @BASEBOARD_FAB2_LIB.BASEBOARD_FAB2(SCH_1):KR_P1_OCP_TX_DP
  J8E4    46   IO46  SCONN64_H87568002_A_SMT  I27
  U7C1   BR24  LAN_TX_P1P  LBG_CORE_QAT_EXT_D  I73

KR_P2_OCP_RX_C_DN   @BASEBOARD_FAB2_LIB.BASEBOARD_FAB2(SCH_1):KR_P2_OCP_RX_C_DN
  C8C10    2      B  CAP_A       I73
  U7C1   BJ37  LAN_RX_P2N  LBG_CORE_QAT_EXT_D  I73

KR_P2_OCP_RX_C_DP   @BASEBOARD_FAB2_LIB.BASEBOARD_FAB2(SCH_1):KR_P2_OCP_RX_C_DP
  C8C11    2      B  CAP_A       I72
  U7C1   BG37  LAN_RX_P2P  LBG_CORE_QAT_EXT_D  I73

KR_P2_OCP_RX_DN   @BASEBOARD_FAB2_LIB.BASEBOARD_FAB2(SCH_1):KR_P2_OCP_RX_DN
  C8C10    1      A  CAP_A       I73
  J8E4    18   IO18  SCONN64_H87568002_A_SMT  I27

KR_P2_OCP_RX_DP   @BASEBOARD_FAB2_LIB.BASEBOARD_FAB2(SCH_1):KR_P2_OCP_RX_DP
  C8C11    1      A  CAP_A       I72
  J8E4    17   IO17  SCONN64_H87568002_A_SMT  I27

KR_P2_OCP_TX_DN   @BASEBOARD_FAB2_LIB.BASEBOARD_FAB2(SCH_1):KR_P2_OCP_TX_DN
  J8E4     6    IO6  SCONN64_H87568002_A_SMT  I27
  U7C1   BM35  LAN_TX_P2N  LBG_CORE_QAT_EXT_D  I73

KR_P2_OCP_TX_DP   @BASEBOARD_FAB2_LIB.BASEBOARD_FAB2(SCH_1):KR_P2_OCP_TX_DP
  J8E4     5    IO5  SCONN64_H87568002_A_SMT  I27
  U7C1   BR35  LAN_TX_P2P  LBG_CORE_QAT_EXT_D  I73

KR_P3_OCP_RX_C_DN   @BASEBOARD_FAB2_LIB.BASEBOARD_FAB2(SCH_1):KR_P3_OCP_RX_C_DN
  C8C9     2      B  CAP_A       I68
  U7C1   BF35  LAN_RX_P3N  LBG_CORE_QAT_EXT_D  I73

KR_P3_OCP_RX_C_DP   @BASEBOARD_FAB2_LIB.BASEBOARD_FAB2(SCH_1):KR_P3_OCP_RX_C_DP
  C8C8     2      B  CAP_A       I64
  U7C1   BH35  LAN_RX_P3P  LBG_CORE_QAT_EXT_D  I73

KR_P3_OCP_RX_DN   @BASEBOARD_FAB2_LIB.BASEBOARD_FAB2(SCH_1):KR_P3_OCP_RX_DN
  C8C9     1      A  CAP_A       I68
  J8E4    24   IO24  SCONN64_H87568002_A_SMT  I27

KR_P3_OCP_RX_DP   @BASEBOARD_FAB2_LIB.BASEBOARD_FAB2(SCH_1):KR_P3_OCP_RX_DP
  C8C8     1      A  CAP_A       I64
  J8E4    23   IO23  SCONN64_H87568002_A_SMT  I27

KR_P3_OCP_TX_DN   @BASEBOARD_FAB2_LIB.BASEBOARD_FAB2(SCH_1):KR_P3_OCP_TX_DN
  J8E4    12   IO12  SCONN64_H87568002_A_SMT  I27
  U7C1   BR31  LAN_TX_P3N  LBG_CORE_QAT_EXT_D  I73

KR_P3_OCP_TX_DP   @BASEBOARD_FAB2_LIB.BASEBOARD_FAB2(SCH_1):KR_P3_OCP_TX_DP
  J8E4    11   IO11  SCONN64_H87568002_A_SMT  I27
  U7C1   BM31  LAN_TX_P3P  LBG_CORE_QAT_EXT_D  I73

LED_GBE_P0_0    @BASEBOARD_FAB2_LIB.BASEBOARD_FAB2(SCH_1):LED_GBE_P0_0
  J8E4    43   IO43  SCONN64_H87568002_A_SMT  I27
  U7C1   BL1  GPP_J0_LAN_LED_P0_0  LBG_CORE_QAT_EXT_D  I147

LED_GBE_P0_1    @BASEBOARD_FAB2_LIB.BASEBOARD_FAB2(SCH_1):LED_GBE_P0_1
  J8E4    44   IO44  SCONN64_H87568002_A_SMT  I27
  U7C1   BK4  GPP_J1_LAN_LED_P0_1  LBG_CORE_QAT_EXT_D  I147

LED_GBE_P1_0    @BASEBOARD_FAB2_LIB.BASEBOARD_FAB2(SCH_1):LED_GBE_P1_0
  J8E4     8    IO8  SCONN64_H87568002_A_SMT  I27
  U7C1   BP4  GPP_J2_LAN_LED_P1_0  LBG_CORE_QAT_EXT_D  I147

LED_GBE_P1_1    @BASEBOARD_FAB2_LIB.BASEBOARD_FAB2(SCH_1):LED_GBE_P1_1
  J8E4     9    IO9  SCONN64_H87568002_A_SMT  I27
  U7C1   BK2  GPP_J3_LAN_LED_P1_1  LBG_CORE_QAT_EXT_D  I147

LED_GBE_P2_0    @BASEBOARD_FAB2_LIB.BASEBOARD_FAB2(SCH_1):LED_GBE_P2_0
  J8E4    14   IO14  SCONN64_H87568002_A_SMT  I27
  U7C1   BL3  GPP_J4_LAN_LED_P2_0  LBG_CORE_QAT_EXT_D  I147

LED_GBE_P2_1    @BASEBOARD_FAB2_LIB.BASEBOARD_FAB2(SCH_1):LED_GBE_P2_1
  J8E4    15   IO15  SCONN64_H87568002_A_SMT  I27
  U7C1   BU6  GPP_J5_LAN_LED_P2_1  LBG_CORE_QAT_EXT_D  I147

LED_GBE_P3_0    @BASEBOARD_FAB2_LIB.BASEBOARD_FAB2(SCH_1):LED_GBE_P3_0
  J8E4    55   IO55  SCONN64_H87568002_A_SMT  I27
  U7C1   CA13  GPP_J6_LAN_LED_P3_0  LBG_CORE_QAT_EXT_D  I147

LED_GBE_P3_1    @BASEBOARD_FAB2_LIB.BASEBOARD_FAB2(SCH_1):LED_GBE_P3_1
  J8E4    56   IO56  SCONN64_H87568002_A_SMT  I27
  U7C1   BM2  GPP_J7_LAN_LED_P3_1  LBG_CORE_QAT_EXT_D  I147

LED_HFI0_CPU0_N   @BASEBOARD_FAB2_LIB.BASEBOARD_FAB2(SCH_1):LED_HFI0_CPU0_N
  J8B1     5    IO5  SCONN24_H46321001_SM   I1
  R8B5     2      B  RES         I22
  U5D1   BK21  CD_HFI0_LED_N  SKX_EXT_B_BGA1  I61

LED_HFI1_CPU0_N   @BASEBOARD_FAB2_LIB.BASEBOARD_FAB2(SCH_1):LED_HFI1_CPU0_N
  J8B1    13   IO13  SCONN24_H46321001_SM   I1
  R8B18    2      B  RES         I20
  U5D1   BM23  CD_HFI1_LED_N  SKX_EXT_B_BGA1  I61

LED_LAN_0_N     @BASEBOARD_FAB2_LIB.BASEBOARD_FAB2(SCH_1):LED_LAN_0_N
  C9G3     1      A  CAP         I59
  EU9E1   31   LED0  SPRINGVILLE_SM1  I72
  R9G3     2      B  RES         I28

LED_LAN_0_R_N   @BASEBOARD_FAB2_LIB.BASEBOARD_FAB2(SCH_1):LED_LAN_0_R_N
  JA9G1   L1     L1  CONN17_H71061002_PIP1  I109
  R9G3     1      A  RES         I28

LED_LAN_1_N     @BASEBOARD_FAB2_LIB.BASEBOARD_FAB2(SCH_1):LED_LAN_1_N
  C9F22    1      A  CAP         I60
  EU9E1   30   LED1  SPRINGVILLE_SM1  I72
  R9G1     1      A  RES         I54

LED_LAN_1_R_N   @BASEBOARD_FAB2_LIB.BASEBOARD_FAB2(SCH_1):LED_LAN_1_R_N
  JA9G1   L5     L5  CONN17_H71061002_PIP1  I109
  R9G1     2      B  RES         I54

LED_LAN_2_N     @BASEBOARD_FAB2_LIB.BASEBOARD_FAB2(SCH_1):LED_LAN_2_N
  C9G1     1      A  CAP         I58
  EU9E1   33   LED2  SPRINGVILLE_SM1  I72
  R9G2     2      B  RES         I30

LED_LAN_2_R_N   @BASEBOARD_FAB2_LIB.BASEBOARD_FAB2(SCH_1):LED_LAN_2_R_N
  JA9G1   L3     L3  CONN17_H71061002_PIP1  I109
  R9G2     1      A  RES         I30

LED_P5V_STBY    @BASEBOARD_FAB2_LIB.BASEBOARD_FAB2(SCH_1):LED_P5V_STBY
  DS9A6    1      A  LED_A1LF    I31
  R1L37    2      B  RES         I33

LED_PCH_SATA_HDD_N   @BASEBOARD_FAB2_LIB.BASEBOARD_FAB2(SCH_1):LED_PCH_SATA_HDD_N
  R1M10    1      A  RES          I6
  U7C1   AV56  GPP_E8_SATA_LED_N  LBG_CORE_QAT_EXT_D  I147

LED_PCH_SSATA_HDD_N   @BASEBOARD_FAB2_LIB.BASEBOARD_FAB2(SCH_1):LED_PCH_SSATA_HDD_N
  R1M13    1      A  RES          I3
  U7C1   AL11  GPP_F14_SSATA_LED_N  LBG_CORE_QAT_EXT_D  I147

LED_POSTCODE_0   @BASEBOARD_FAB2_LIB.BASEBOARD_FAB2(SCH_1):LED_POSTCODE_0
  R1L32    1      A  RES         I65
  U7C1   AV3  GPP_H2_SRCCLKREQ8_N  LBG_CORE_QAT_EXT_D  I147
  U9F4    A8  GPIOH0_ROMD8_NCTS6  AST1250_BGA   I1

LED_POSTCODE_0_R   @BASEBOARD_FAB2_LIB.BASEBOARD_FAB2(SCH_1):LED_POSTCODE_0_R
  J9A2     1    IO1  CONN14_H54902001_PIP  I171
  R1L32    2      B  RES         I65

LED_POSTCODE_1   @BASEBOARD_FAB2_LIB.BASEBOARD_FAB2(SCH_1):LED_POSTCODE_1
  R1L30    1      A  RES         I66
  U7C1   AR1  GPP_H3_SRCCLKREQ9_N  LBG_CORE_QAT_EXT_D  I147
  U9F4    C7  GPIOH1_ROMD9_NDCD6  AST1250_BGA   I1

LED_POSTCODE_1_R   @BASEBOARD_FAB2_LIB.BASEBOARD_FAB2(SCH_1):LED_POSTCODE_1_R
  J9A2     2    IO2  CONN14_H54902001_PIP  I171
  R1L30    2      B  RES         I66

LED_POSTCODE_2   @BASEBOARD_FAB2_LIB.BASEBOARD_FAB2(SCH_1):LED_POSTCODE_2
  R1L25    1      A  RES         I67
  U7C1   AT2  GPP_H4_SRCCLKREQ10_N  LBG_CORE_QAT_EXT_D  I147
  U9F4    B7  GPIOH2_ROMD10_NDSR6  AST1250_BGA   I1

LED_POSTCODE_2_R   @BASEBOARD_FAB2_LIB.BASEBOARD_FAB2(SCH_1):LED_POSTCODE_2_R
  J9A2     3    IO3  CONN14_H54902001_PIP  I171
  R1L25    2      B  RES         I67

LED_POSTCODE_3   @BASEBOARD_FAB2_LIB.BASEBOARD_FAB2(SCH_1):LED_POSTCODE_3
  R1L24    1      A  RES         I68
  U7C1   AY3  GPP_H5_SRCCLKREQ11_N  LBG_CORE_QAT_EXT_D  I147
  U9F4    A7  GPIOH3_ROMD11_NRI6  AST1250_BGA   I1

LED_POSTCODE_3_R   @BASEBOARD_FAB2_LIB.BASEBOARD_FAB2(SCH_1):LED_POSTCODE_3_R
  J9A2     4    IO4  CONN14_H54902001_PIP  I171
  R1L24    2      B  RES         I68

LED_POSTCODE_4   @BASEBOARD_FAB2_LIB.BASEBOARD_FAB2(SCH_1):LED_POSTCODE_4
  R1L20    1      A  RES         I73
  U7C1   AW2  GPP_H6_SRCCLKREQ12_N  LBG_CORE_QAT_EXT_D  I147
  U9F4    D7  GPIOH4_ROMD12_NDTR6  AST1250_BGA   I1

LED_POSTCODE_4_R   @BASEBOARD_FAB2_LIB.BASEBOARD_FAB2(SCH_1):LED_POSTCODE_4_R
  J9A2     5    IO5  CONN14_H54902001_PIP  I171
  R1L20    2      B  RES         I73

LED_POSTCODE_5   @BASEBOARD_FAB2_LIB.BASEBOARD_FAB2(SCH_1):LED_POSTCODE_5
  R1L18    1      A  RES         I74
  U7C1   AV1  GPP_H7_SRCCLKREQ13_N  LBG_CORE_QAT_EXT_D  I147
  U9F4    B6  GPIOH5_ROMD13_NRTS6  AST1250_BGA   I1

LED_POSTCODE_5_R   @BASEBOARD_FAB2_LIB.BASEBOARD_FAB2(SCH_1):LED_POSTCODE_5_R
  J9A2     6    IO6  CONN14_H54902001_PIP  I171
  R1L18    2      B  RES         I74

LED_POSTCODE_6   @BASEBOARD_FAB2_LIB.BASEBOARD_FAB2(SCH_1):LED_POSTCODE_6
  R1L14    1      A  RES         I75
  U7C1   AR3  GPP_H8_SRCCLKREQ14_N  LBG_CORE_QAT_EXT_D  I147
  U9F4    A6  GPIOH6_ROMD14_TXD6  AST1250_BGA   I1

LED_POSTCODE_6_R   @BASEBOARD_FAB2_LIB.BASEBOARD_FAB2(SCH_1):LED_POSTCODE_6_R
  J9A2     7    IO7  CONN14_H54902001_PIP  I171
  R1L14    2      B  RES         I75

LED_POSTCODE_7   @BASEBOARD_FAB2_LIB.BASEBOARD_FAB2(SCH_1):LED_POSTCODE_7
  R1L11    1      A  RES         I76
  U7C1   BE2  GPP_H9_SRCCLKREQ15_N  LBG_CORE_QAT_EXT_D  I147
  U9F4    E7  GPIOH7_ROMD15_RXD6  AST1250_BGA   I1

LED_POSTCODE_7_R   @BASEBOARD_FAB2_LIB.BASEBOARD_FAB2(SCH_1):LED_POSTCODE_7_R
  J9A2     8    IO8  CONN14_H54902001_PIP  I171
  R1L11    2      B  RES         I76

LED_SAS_ACT_R_N   @BASEBOARD_FAB2_LIB.BASEBOARD_FAB2(SCH_1):LED_SAS_ACT_R_N
  R1M12    2      B  RES          I8
  R1M13    2      B  RES          I3
  U1M1     2   B<0>  TTL1G08     I70

LED_SATA_ACT_R_N   @BASEBOARD_FAB2_LIB.BASEBOARD_FAB2(SCH_1):LED_SATA_ACT_R_N
  R1M10    2      B  RES          I6
  R1M11    2      B  RES          I9
  U1M1     1   A<0>  TTL1G08     I70

LPC_LAD0_IO0    @BASEBOARD_FAB2_LIB.BASEBOARD_FAB2(SCH_1):LPC_LAD0_IO0
  R3N26    1      A  RES         I555
  U7C1    Y3  GPP_A1_LAD0_ESPI_IO0  LBG_CORE_QAT_EXT_D  I115

LPC_LAD0_IO0_R   @BASEBOARD_FAB2_LIB.BASEBOARD_FAB2(SCH_1):LPC_LAD0_IO0_R
  R3N26    2      B  RES         I555
  U9F4   B21  LAD<0>  AST1250_BGA  I347

LPC_LAD1_IO1    @BASEBOARD_FAB2_LIB.BASEBOARD_FAB2(SCH_1):LPC_LAD1_IO1
  R3N28    1      A  RES         I554
  U7C1    N1  GPP_A2_LAD1_ESPI_IO1  LBG_CORE_QAT_EXT_D  I115

LPC_LAD1_IO1_R   @BASEBOARD_FAB2_LIB.BASEBOARD_FAB2(SCH_1):LPC_LAD1_IO1_R
  R3N28    2      B  RES         I554
  U9F4   A22  LAD<1>  AST1250_BGA  I347

LPC_LAD2_IO2    @BASEBOARD_FAB2_LIB.BASEBOARD_FAB2(SCH_1):LPC_LAD2_IO2
  R3N24    1      A  RES         I553
  U7C1    W2  GPP_A3_LAD2_ESPI_IO2  LBG_CORE_QAT_EXT_D  I115

LPC_LAD2_IO2_R   @BASEBOARD_FAB2_LIB.BASEBOARD_FAB2(SCH_1):LPC_LAD2_IO2_R
  R3N24    2      B  RES         I553
  U9F4   F19  LAD<2>  AST1250_BGA  I347

LPC_LAD3_IO3    @BASEBOARD_FAB2_LIB.BASEBOARD_FAB2(SCH_1):LPC_LAD3_IO3
  R3N25    1      A  RES         I527
  U7C1    Y1  GPP_A4_LAD3_ESPI_IO3  LBG_CORE_QAT_EXT_D  I115

LPC_LAD3_IO3_R   @BASEBOARD_FAB2_LIB.BASEBOARD_FAB2(SCH_1):LPC_LAD3_IO3_R
  R3N25    2      B  RES         I527
  U9F4   C19  LAD<3>  AST1250_BGA  I347

LPC_LFRAME_N_CS0_N   @BASEBOARD_FAB2_LIB.BASEBOARD_FAB2(SCH_1):LPC_LFRAME_N_CS0_N
  R3N27    1      A  RES         I521
  U7C1    P4  GPP_A5_LFRAME_N_ESPI_CS0_N  LBG_CORE_QAT_EXT_D  I115

LPC_LFRAME_N_CS0_R_N   @BASEBOARD_FAB2_LIB.BASEBOARD_FAB2(SCH_1):LPC_LFRAME_N_CS0_R_N
  R3N27    2      B  RES         I521
  U9F4   A21  LFRAME_N  AST1250_BGA  I347

M_ABC_RST_N     @BASEBOARD_FAB2_LIB.BASEBOARD_FAB2(SCH_1):M_ABC_RST_N
  J4G1    58  RESET_N  SCONN288_H44441004_PIP   I1
  J4G2    58  RESET_N  SCONN288_H44441004_PIP  I111
  J4G3    58  RESET_N  SCONN288_H44441004_PIP  I111
  J6T1    58  RESET_N  SCONN288_H44441003_PIP  I13
  J6U1    58  RESET_N  SCONN288_H44441003_PIP  I14
  J6U2    58  RESET_N  SCONN288_H44441003_PIP  I111
  U5D1   U64  DDR012_RESET_N  SKX_EXT_B_BGA1  I259

M_A_ACT_N       @BASEBOARD_FAB2_LIB.BASEBOARD_FAB2(SCH_1):M_A_ACT_N
  J4G1    62  ACT_N  SCONN288_H44441004_PIP   I1
  J6T1    62  ACT_N  SCONN288_H44441003_PIP  I13
  U5D1   J60  DDR0_ACT_N  SKX_EXT_B_BGA1  I172

M_A_ALERT_N     @BASEBOARD_FAB2_LIB.BASEBOARD_FAB2(SCH_1):M_A_ALERT_N
  J4G1   208  ALERT_N  SCONN288_H44441004_PIP   I1
  J6T1   208  ALERT_N  SCONN288_H44441003_PIP  I13
  U5D1   B61  DDR0_ALERT_N  SKX_EXT_B_BGA1  I172

M_A_BA<0>       @BASEBOARD_FAB2_LIB.BASEBOARD_FAB2(SCH_1):M_A_BA<0>
  J4G1    81  BA<0>  SCONN288_H44441004_PIP   I1
  J6T1    81  BA<0>  SCONN288_H44441003_PIP  I13
  U5D1   C52  DDR0_BA<0>  SKX_EXT_B_BGA1  I172

M_A_BA<1>       @BASEBOARD_FAB2_LIB.BASEBOARD_FAB2(SCH_1):M_A_BA<1>
  J4G1   224  BA<1>  SCONN288_H44441004_PIP   I1
  J6T1   224  BA<1>  SCONN288_H44441003_PIP  I13
  U5D1   G54  DDR0_BA<1>  SKX_EXT_B_BGA1  I172

M_A_BG<0>       @BASEBOARD_FAB2_LIB.BASEBOARD_FAB2(SCH_1):M_A_BG<0>
  J4G1    63  BG<0>  SCONN288_H44441004_PIP   I1
  J6T1    63  BG<0>  SCONN288_H44441003_PIP  I13
  U5D1   D61  DDR0_BG<0>  SKX_EXT_B_BGA1  I172

M_A_BG<1>       @BASEBOARD_FAB2_LIB.BASEBOARD_FAB2(SCH_1):M_A_BG<1>
  J4G1   207  BG<1>  SCONN288_H44441004_PIP   I1
  J6T1   207  BG<1>  SCONN288_H44441003_PIP  I13
  U5D1   F63  DDR0_BG<1>  SKX_EXT_B_BGA1  I172

M_A_C<2>        @BASEBOARD_FAB2_LIB.BASEBOARD_FAB2(SCH_1):M_A_C<2>
  J4G1   235   C<2>  SCONN288_H44441004_PIP   I1
  J6T1   235   C<2>  SCONN288_H44441003_PIP  I13
  U5D1   G46  DDR0_CID<2>  SKX_EXT_B_BGA1  I172

M_A_CKE<0>      @BASEBOARD_FAB2_LIB.BASEBOARD_FAB2(SCH_1):M_A_CKE<0>
  J4G1    60  CKE<0>  SCONN288_H44441004_PIP   I1
  U5D1   C62  DDR0_CKE<0>  SKX_EXT_B_BGA1  I172

M_A_CKE<1>      @BASEBOARD_FAB2_LIB.BASEBOARD_FAB2(SCH_1):M_A_CKE<1>
  J4G1   203  CKE<1>  SCONN288_H44441004_PIP   I1
  U5D1   C64  DDR0_CKE<1>  SKX_EXT_B_BGA1  I172

M_A_CKE<2>      @BASEBOARD_FAB2_LIB.BASEBOARD_FAB2(SCH_1):M_A_CKE<2>
  J6T1    60  CKE<0>  SCONN288_H44441003_PIP  I13
  U5D1   B63  DDR0_CKE<2>  SKX_EXT_B_BGA1  I172

M_A_CKE<3>      @BASEBOARD_FAB2_LIB.BASEBOARD_FAB2(SCH_1):M_A_CKE<3>
  J6T1   203  CKE<1>  SCONN288_H44441003_PIP  I13
  U5D1   D63  DDR0_CKE<3>  SKX_EXT_B_BGA1  I172

M_A_CLK_DN<0>   @BASEBOARD_FAB2_LIB.BASEBOARD_FAB2(SCH_1):M_A_CLK_DN<0>
  J4G1    75   CK0N  SCONN288_H44441004_PIP   I1
  U5D1   F55  DDR0_CLK_DN<0>  SKX_EXT_B_BGA1  I172

M_A_CLK_DN<1>   @BASEBOARD_FAB2_LIB.BASEBOARD_FAB2(SCH_1):M_A_CLK_DN<1>
  J4G1   219   CK1N  SCONN288_H44441004_PIP   I1
  U5D1   C54  DDR0_CLK_DN<1>  SKX_EXT_B_BGA1  I172

M_A_CLK_DN<2>   @BASEBOARD_FAB2_LIB.BASEBOARD_FAB2(SCH_1):M_A_CLK_DN<2>
  J6T1    75   CK0N  SCONN288_H44441003_PIP  I13
  U5D1   J56  DDR0_CLK_DN<2>  SKX_EXT_B_BGA1  I172

M_A_CLK_DN<3>   @BASEBOARD_FAB2_LIB.BASEBOARD_FAB2(SCH_1):M_A_CLK_DN<3>
  J6T1   219   CK1N  SCONN288_H44441003_PIP  I13
  U5D1   C56  DDR0_CLK_DN<3>  SKX_EXT_B_BGA1  I172

M_A_CLK_DP<0>   @BASEBOARD_FAB2_LIB.BASEBOARD_FAB2(SCH_1):M_A_CLK_DP<0>
  J4G1    74   CK0P  SCONN288_H44441004_PIP   I1
  U5D1   D55  DDR0_CLK_DP<0>  SKX_EXT_B_BGA1  I172

M_A_CLK_DP<1>   @BASEBOARD_FAB2_LIB.BASEBOARD_FAB2(SCH_1):M_A_CLK_DP<1>
  J4G1   218   CK1P  SCONN288_H44441004_PIP   I1
  U5D1   B55  DDR0_CLK_DP<1>  SKX_EXT_B_BGA1  I172

M_A_CLK_DP<2>   @BASEBOARD_FAB2_LIB.BASEBOARD_FAB2(SCH_1):M_A_CLK_DP<2>
  J6T1    74   CK0P  SCONN288_H44441003_PIP  I13
  U5D1   G56  DDR0_CLK_DP<2>  SKX_EXT_B_BGA1  I172

M_A_CLK_DP<3>   @BASEBOARD_FAB2_LIB.BASEBOARD_FAB2(SCH_1):M_A_CLK_DP<3>
  J6T1   218   CK1P  SCONN288_H44441003_PIP  I13
  U5D1   B57  DDR0_CLK_DP<3>  SKX_EXT_B_BGA1  I172

M_A_CPU_VREF    @BASEBOARD_FAB2_LIB.BASEBOARD_FAB2(SCH_1):M_A_CPU_VREF
  C4F9     1      A  CAP_A        I7
  R4F3     1      A  RES          I5
  U5D1   AJ64  DDR0_CAVREF  SKX_EXT_B_BGA1  I259

M_A_CS_N<0>     @BASEBOARD_FAB2_LIB.BASEBOARD_FAB2(SCH_1):M_A_CS_N<0>
  J4G1    84   S0_N  SCONN288_H44441004_PIP   I1
  U5D1   G52  DDR0_CS_N<0>  SKX_EXT_B_BGA1  I172

M_A_CS_N<1>     @BASEBOARD_FAB2_LIB.BASEBOARD_FAB2(SCH_1):M_A_CS_N<1>
  J4G1    89   S1_N  SCONN288_H44441004_PIP   I1
  U5D1   F49  DDR0_CS_N<1>  SKX_EXT_B_BGA1  I172

M_A_CS_N<2>     @BASEBOARD_FAB2_LIB.BASEBOARD_FAB2(SCH_1):M_A_CS_N<2>
  J4G1    93  S2_N_C<0>  SCONN288_H44441004_PIP   I1
  U5D1   D47  DDR0_CS_N<2>  SKX_EXT_B_BGA1  I172

M_A_CS_N<3>     @BASEBOARD_FAB2_LIB.BASEBOARD_FAB2(SCH_1):M_A_CS_N<3>
  J4G1   237  S3_N_C<1>  SCONN288_H44441004_PIP   I1
  U5D1   F47  DDR0_CS_N<3>  SKX_EXT_B_BGA1  I172

M_A_CS_N<4>     @BASEBOARD_FAB2_LIB.BASEBOARD_FAB2(SCH_1):M_A_CS_N<4>
  J6T1    84   S0_N  SCONN288_H44441003_PIP  I13
  U5D1   B51  DDR0_CS_N<4>  SKX_EXT_B_BGA1  I172

M_A_CS_N<5>     @BASEBOARD_FAB2_LIB.BASEBOARD_FAB2(SCH_1):M_A_CS_N<5>
  J6T1    89   S1_N  SCONN288_H44441003_PIP  I13
  U5D1   D49  DDR0_CS_N<5>  SKX_EXT_B_BGA1  I172

M_A_CS_N<6>     @BASEBOARD_FAB2_LIB.BASEBOARD_FAB2(SCH_1):M_A_CS_N<6>
  J6T1    93  S2_N_C<0>  SCONN288_H44441003_PIP  I13
  U5D1   F45  DDR0_CS_N<6>  SKX_EXT_B_BGA1  I172

M_A_CS_N<7>     @BASEBOARD_FAB2_LIB.BASEBOARD_FAB2(SCH_1):M_A_CS_N<7>
  J6T1   237  S3_N_C<1>  SCONN288_H44441003_PIP  I13
  U5D1   K45  DDR0_CS_N<7>  SKX_EXT_B_BGA1  I172

M_A_DQ<0>       @BASEBOARD_FAB2_LIB.BASEBOARD_FAB2(SCH_1):M_A_DQ<0>
  J4G1   150  DQ<1>  SCONN288_H44441004_PIP   I1
  J6T1     5  DQ<0>  SCONN288_H44441003_PIP  I13
  U5D1   AN86  DDR0_DQ<0>  SKX_EXT_B_BGA1  I172

M_A_DQ<1>       @BASEBOARD_FAB2_LIB.BASEBOARD_FAB2(SCH_1):M_A_DQ<1>
  J4G1     5  DQ<0>  SCONN288_H44441004_PIP   I1
  J6T1   150  DQ<1>  SCONN288_H44441003_PIP  I13
  U5D1   AN84  DDR0_DQ<1>  SKX_EXT_B_BGA1  I172

M_A_DQ<2>       @BASEBOARD_FAB2_LIB.BASEBOARD_FAB2(SCH_1):M_A_DQ<2>
  J4G1   157  DQ<3>  SCONN288_H44441004_PIP   I1
  J6T1    12  DQ<2>  SCONN288_H44441003_PIP  I13
  U5D1   AE86  DDR0_DQ<2>  SKX_EXT_B_BGA1  I172

M_A_DQ<3>       @BASEBOARD_FAB2_LIB.BASEBOARD_FAB2(SCH_1):M_A_DQ<3>
  J4G1    12  DQ<2>  SCONN288_H44441004_PIP   I1
  J6T1   157  DQ<3>  SCONN288_H44441003_PIP  I13
  U5D1   AE84  DDR0_DQ<3>  SKX_EXT_B_BGA1  I172

M_A_DQ<4>       @BASEBOARD_FAB2_LIB.BASEBOARD_FAB2(SCH_1):M_A_DQ<4>
  J4G1   148  DQ<5>  SCONN288_H44441004_PIP   I1
  J6T1     3  DQ<4>  SCONN288_H44441003_PIP  I13
  U5D1   AR86  DDR0_DQ<4>  SKX_EXT_B_BGA1  I172

M_A_DQ<5>       @BASEBOARD_FAB2_LIB.BASEBOARD_FAB2(SCH_1):M_A_DQ<5>
  J4G1     3  DQ<4>  SCONN288_H44441004_PIP   I1
  J6T1   148  DQ<5>  SCONN288_H44441003_PIP  I13
  U5D1   AR84  DDR0_DQ<5>  SKX_EXT_B_BGA1  I172

M_A_DQ<6>       @BASEBOARD_FAB2_LIB.BASEBOARD_FAB2(SCH_1):M_A_DQ<6>
  J4G1   155  DQ<7>  SCONN288_H44441004_PIP   I1
  J6T1    10  DQ<6>  SCONN288_H44441003_PIP  I13
  U5D1   AG86  DDR0_DQ<6>  SKX_EXT_B_BGA1  I172

M_A_DQ<7>       @BASEBOARD_FAB2_LIB.BASEBOARD_FAB2(SCH_1):M_A_DQ<7>
  J4G1    10  DQ<6>  SCONN288_H44441004_PIP   I1
  J6T1   155  DQ<7>  SCONN288_H44441003_PIP  I13
  U5D1   AG84  DDR0_DQ<7>  SKX_EXT_B_BGA1  I172

M_A_DQ<8>       @BASEBOARD_FAB2_LIB.BASEBOARD_FAB2(SCH_1):M_A_DQ<8>
  J4G1   161  DQ<9>  SCONN288_H44441004_PIP   I1
  J6T1    16  DQ<8>  SCONN288_H44441003_PIP  I13
  U5D1   W86  DDR0_DQ<8>  SKX_EXT_B_BGA1  I172

M_A_DQ<9>       @BASEBOARD_FAB2_LIB.BASEBOARD_FAB2(SCH_1):M_A_DQ<9>
  J4G1    16  DQ<8>  SCONN288_H44441004_PIP   I1
  J6T1   161  DQ<9>  SCONN288_H44441003_PIP  I13
  U5D1   W84  DDR0_DQ<9>  SKX_EXT_B_BGA1  I172

M_A_DQ<10>      @BASEBOARD_FAB2_LIB.BASEBOARD_FAB2(SCH_1):M_A_DQ<10>
  J4G1   168  DQ<11>  SCONN288_H44441004_PIP   I1
  J6T1    23  DQ<10>  SCONN288_H44441003_PIP  I13
  U5D1   L86  DDR0_DQ<10>  SKX_EXT_B_BGA1  I172

M_A_DQ<11>      @BASEBOARD_FAB2_LIB.BASEBOARD_FAB2(SCH_1):M_A_DQ<11>
  J4G1    23  DQ<10>  SCONN288_H44441004_PIP   I1
  J6T1   168  DQ<11>  SCONN288_H44441003_PIP  I13
  U5D1   L84  DDR0_DQ<11>  SKX_EXT_B_BGA1  I172

M_A_DQ<12>      @BASEBOARD_FAB2_LIB.BASEBOARD_FAB2(SCH_1):M_A_DQ<12>
  J4G1   159  DQ<13>  SCONN288_H44441004_PIP   I1
  J6T1    14  DQ<12>  SCONN288_H44441003_PIP  I13
  U5D1   AA86  DDR0_DQ<12>  SKX_EXT_B_BGA1  I172

M_A_DQ<13>      @BASEBOARD_FAB2_LIB.BASEBOARD_FAB2(SCH_1):M_A_DQ<13>
  J4G1    14  DQ<12>  SCONN288_H44441004_PIP   I1
  J6T1   159  DQ<13>  SCONN288_H44441003_PIP  I13
  U5D1   AA84  DDR0_DQ<13>  SKX_EXT_B_BGA1  I172

M_A_DQ<14>      @BASEBOARD_FAB2_LIB.BASEBOARD_FAB2(SCH_1):M_A_DQ<14>
  J4G1   166  DQ<15>  SCONN288_H44441004_PIP   I1
  J6T1    21  DQ<14>  SCONN288_H44441003_PIP  I13
  U5D1   N86  DDR0_DQ<14>  SKX_EXT_B_BGA1  I172

M_A_DQ<15>      @BASEBOARD_FAB2_LIB.BASEBOARD_FAB2(SCH_1):M_A_DQ<15>
  J4G1    21  DQ<14>  SCONN288_H44441004_PIP   I1
  J6T1   166  DQ<15>  SCONN288_H44441003_PIP  I13
  U5D1   N84  DDR0_DQ<15>  SKX_EXT_B_BGA1  I172

M_A_DQ<16>      @BASEBOARD_FAB2_LIB.BASEBOARD_FAB2(SCH_1):M_A_DQ<16>
  J4G1   172  DQ<17>  SCONN288_H44441004_PIP   I1
  J6T1    27  DQ<16>  SCONN288_H44441003_PIP  I13
  U5D1   V81  DDR0_DQ<16>  SKX_EXT_B_BGA1  I172

M_A_DQ<17>      @BASEBOARD_FAB2_LIB.BASEBOARD_FAB2(SCH_1):M_A_DQ<17>
  J4G1    27  DQ<16>  SCONN288_H44441004_PIP   I1
  J6T1   172  DQ<17>  SCONN288_H44441003_PIP  I13
  U5D1   T79  DDR0_DQ<17>  SKX_EXT_B_BGA1  I172

M_A_DQ<18>      @BASEBOARD_FAB2_LIB.BASEBOARD_FAB2(SCH_1):M_A_DQ<18>
  J4G1   179  DQ<19>  SCONN288_H44441004_PIP   I1
  J6T1    34  DQ<18>  SCONN288_H44441003_PIP  I13
  U5D1   N82  DDR0_DQ<18>  SKX_EXT_B_BGA1  I172

M_A_DQ<19>      @BASEBOARD_FAB2_LIB.BASEBOARD_FAB2(SCH_1):M_A_DQ<19>
  J4G1    34  DQ<18>  SCONN288_H44441004_PIP   I1
  J6T1   179  DQ<19>  SCONN288_H44441003_PIP  I13
  U5D1   M81  DDR0_DQ<19>  SKX_EXT_B_BGA1  I172

M_A_DQ<20>      @BASEBOARD_FAB2_LIB.BASEBOARD_FAB2(SCH_1):M_A_DQ<20>
  J4G1   170  DQ<21>  SCONN288_H44441004_PIP   I1
  J6T1    25  DQ<20>  SCONN288_H44441003_PIP  I13
  U5D1   W80  DDR0_DQ<20>  SKX_EXT_B_BGA1  I172

M_A_DQ<21>      @BASEBOARD_FAB2_LIB.BASEBOARD_FAB2(SCH_1):M_A_DQ<21>
  J4G1    25  DQ<20>  SCONN288_H44441004_PIP   I1
  J6T1   170  DQ<21>  SCONN288_H44441003_PIP  I13
  U5D1   V79  DDR0_DQ<21>  SKX_EXT_B_BGA1  I172

M_A_DQ<22>      @BASEBOARD_FAB2_LIB.BASEBOARD_FAB2(SCH_1):M_A_DQ<22>
  J4G1   177  DQ<23>  SCONN288_H44441004_PIP   I1
  J6T1    32  DQ<22>  SCONN288_H44441003_PIP  I13
  U5D1   R82  DDR0_DQ<22>  SKX_EXT_B_BGA1  I172

M_A_DQ<23>      @BASEBOARD_FAB2_LIB.BASEBOARD_FAB2(SCH_1):M_A_DQ<23>
  J4G1    32  DQ<22>  SCONN288_H44441004_PIP   I1
  J6T1   177  DQ<23>  SCONN288_H44441003_PIP  I13
  U5D1   N80  DDR0_DQ<23>  SKX_EXT_B_BGA1  I172

M_A_DQ<24>      @BASEBOARD_FAB2_LIB.BASEBOARD_FAB2(SCH_1):M_A_DQ<24>
  J4G1   183  DQ<25>  SCONN288_H44441004_PIP   I1
  J6T1    38  DQ<24>  SCONN288_H44441003_PIP  I13
  U5D1   L76  DDR0_DQ<24>  SKX_EXT_B_BGA1  I172

M_A_DQ<25>      @BASEBOARD_FAB2_LIB.BASEBOARD_FAB2(SCH_1):M_A_DQ<25>
  J4G1    38  DQ<24>  SCONN288_H44441004_PIP   I1
  J6T1   183  DQ<25>  SCONN288_H44441003_PIP  I13
  U5D1   R76  DDR0_DQ<25>  SKX_EXT_B_BGA1  I172

M_A_DQ<26>      @BASEBOARD_FAB2_LIB.BASEBOARD_FAB2(SCH_1):M_A_DQ<26>
  J4G1   190  DQ<27>  SCONN288_H44441004_PIP   I1
  J6T1    45  DQ<26>  SCONN288_H44441003_PIP  I13
  U5D1   M73  DDR0_DQ<26>  SKX_EXT_B_BGA1  I172

M_A_DQ<27>      @BASEBOARD_FAB2_LIB.BASEBOARD_FAB2(SCH_1):M_A_DQ<27>
  J4G1    45  DQ<26>  SCONN288_H44441004_PIP   I1
  J6T1   190  DQ<27>  SCONN288_H44441003_PIP  I13
  U5D1   P73  DDR0_DQ<27>  SKX_EXT_B_BGA1  I172

M_A_DQ<28>      @BASEBOARD_FAB2_LIB.BASEBOARD_FAB2(SCH_1):M_A_DQ<28>
  J4G1   181  DQ<29>  SCONN288_H44441004_PIP   I1
  J6T1    36  DQ<28>  SCONN288_H44441003_PIP  I13
  U5D1   M77  DDR0_DQ<28>  SKX_EXT_B_BGA1  I172

M_A_DQ<29>      @BASEBOARD_FAB2_LIB.BASEBOARD_FAB2(SCH_1):M_A_DQ<29>
  J4G1    36  DQ<28>  SCONN288_H44441004_PIP   I1
  J6T1   181  DQ<29>  SCONN288_H44441003_PIP  I13
  U5D1   P77  DDR0_DQ<29>  SKX_EXT_B_BGA1  I172

M_A_DQ<30>      @BASEBOARD_FAB2_LIB.BASEBOARD_FAB2(SCH_1):M_A_DQ<30>
  J4G1   188  DQ<31>  SCONN288_H44441004_PIP   I1
  J6T1    43  DQ<30>  SCONN288_H44441003_PIP  I13
  U5D1   L74  DDR0_DQ<30>  SKX_EXT_B_BGA1  I172

M_A_DQ<31>      @BASEBOARD_FAB2_LIB.BASEBOARD_FAB2(SCH_1):M_A_DQ<31>
  J4G1    43  DQ<30>  SCONN288_H44441004_PIP   I1
  J6T1   188  DQ<31>  SCONN288_H44441003_PIP  I13
  U5D1   R74  DDR0_DQ<31>  SKX_EXT_B_BGA1  I172

M_A_DQ<32>      @BASEBOARD_FAB2_LIB.BASEBOARD_FAB2(SCH_1):M_A_DQ<32>
  J4G1   242  DQ<33>  SCONN288_H44441004_PIP   I1
  J6T1    97  DQ<32>  SCONN288_H44441003_PIP  I13
  U5D1   C42  DDR0_DQ<32>  SKX_EXT_B_BGA1  I172

M_A_DQ<33>      @BASEBOARD_FAB2_LIB.BASEBOARD_FAB2(SCH_1):M_A_DQ<33>
  J4G1    97  DQ<32>  SCONN288_H44441004_PIP   I1
  J6T1   242  DQ<33>  SCONN288_H44441003_PIP  I13
  U5D1   B41  DDR0_DQ<33>  SKX_EXT_B_BGA1  I172

M_A_DQ<34>      @BASEBOARD_FAB2_LIB.BASEBOARD_FAB2(SCH_1):M_A_DQ<34>
  J4G1   249  DQ<35>  SCONN288_H44441004_PIP   I1
  J6T1   104  DQ<34>  SCONN288_H44441003_PIP  I13
  U5D1   C38  DDR0_DQ<34>  SKX_EXT_B_BGA1  I172

M_A_DQ<35>      @BASEBOARD_FAB2_LIB.BASEBOARD_FAB2(SCH_1):M_A_DQ<35>
  J4G1   104  DQ<34>  SCONN288_H44441004_PIP   I1
  J6T1   249  DQ<35>  SCONN288_H44441003_PIP  I13
  U5D1   E38  DDR0_DQ<35>  SKX_EXT_B_BGA1  I172

M_A_DQ<36>      @BASEBOARD_FAB2_LIB.BASEBOARD_FAB2(SCH_1):M_A_DQ<36>
  J4G1   240  DQ<37>  SCONN288_H44441004_PIP   I1
  J6T1    95  DQ<36>  SCONN288_H44441003_PIP  I13
  U5D1   E42  DDR0_DQ<36>  SKX_EXT_B_BGA1  I172

M_A_DQ<37>      @BASEBOARD_FAB2_LIB.BASEBOARD_FAB2(SCH_1):M_A_DQ<37>
  J4G1    95  DQ<36>  SCONN288_H44441004_PIP   I1
  J6T1   240  DQ<37>  SCONN288_H44441003_PIP  I13
  U5D1   F41  DDR0_DQ<37>  SKX_EXT_B_BGA1  I172

M_A_DQ<38>      @BASEBOARD_FAB2_LIB.BASEBOARD_FAB2(SCH_1):M_A_DQ<38>
  J4G1   247  DQ<39>  SCONN288_H44441004_PIP   I1
  J6T1   102  DQ<38>  SCONN288_H44441003_PIP  I13
  U5D1   B39  DDR0_DQ<38>  SKX_EXT_B_BGA1  I172

M_A_DQ<39>      @BASEBOARD_FAB2_LIB.BASEBOARD_FAB2(SCH_1):M_A_DQ<39>
  J4G1   102  DQ<38>  SCONN288_H44441004_PIP   I1
  J6T1   247  DQ<39>  SCONN288_H44441003_PIP  I13
  U5D1   F39  DDR0_DQ<39>  SKX_EXT_B_BGA1  I172

M_A_DQ<40>      @BASEBOARD_FAB2_LIB.BASEBOARD_FAB2(SCH_1):M_A_DQ<40>
  J4G1   253  DQ<41>  SCONN288_H44441004_PIP   I1
  J6T1   108  DQ<40>  SCONN288_H44441003_PIP  I13
  U5D1   K37  DDR0_DQ<40>  SKX_EXT_B_BGA1  I172

M_A_DQ<41>      @BASEBOARD_FAB2_LIB.BASEBOARD_FAB2(SCH_1):M_A_DQ<41>
  J4G1   108  DQ<40>  SCONN288_H44441004_PIP   I1
  J6T1   253  DQ<41>  SCONN288_H44441003_PIP  I13
  U5D1   P37  DDR0_DQ<41>  SKX_EXT_B_BGA1  I172

M_A_DQ<42>      @BASEBOARD_FAB2_LIB.BASEBOARD_FAB2(SCH_1):M_A_DQ<42>
  J4G1   260  DQ<43>  SCONN288_H44441004_PIP   I1
  J6T1   115  DQ<42>  SCONN288_H44441003_PIP  I13
  U5D1   L34  DDR0_DQ<42>  SKX_EXT_B_BGA1  I172

M_A_DQ<43>      @BASEBOARD_FAB2_LIB.BASEBOARD_FAB2(SCH_1):M_A_DQ<43>
  J4G1   115  DQ<42>  SCONN288_H44441004_PIP   I1
  J6T1   260  DQ<43>  SCONN288_H44441003_PIP  I13
  U5D1   N34  DDR0_DQ<43>  SKX_EXT_B_BGA1  I172

M_A_DQ<44>      @BASEBOARD_FAB2_LIB.BASEBOARD_FAB2(SCH_1):M_A_DQ<44>
  J4G1   251  DQ<45>  SCONN288_H44441004_PIP   I1
  J6T1   106  DQ<44>  SCONN288_H44441003_PIP  I13
  U5D1   L38  DDR0_DQ<44>  SKX_EXT_B_BGA1  I172

M_A_DQ<45>      @BASEBOARD_FAB2_LIB.BASEBOARD_FAB2(SCH_1):M_A_DQ<45>
  J4G1   106  DQ<44>  SCONN288_H44441004_PIP   I1
  J6T1   251  DQ<45>  SCONN288_H44441003_PIP  I13
  U5D1   N38  DDR0_DQ<45>  SKX_EXT_B_BGA1  I172

M_A_DQ<46>      @BASEBOARD_FAB2_LIB.BASEBOARD_FAB2(SCH_1):M_A_DQ<46>
  J4G1   258  DQ<47>  SCONN288_H44441004_PIP   I1
  J6T1   113  DQ<46>  SCONN288_H44441003_PIP  I13
  U5D1   K35  DDR0_DQ<46>  SKX_EXT_B_BGA1  I172

M_A_DQ<47>      @BASEBOARD_FAB2_LIB.BASEBOARD_FAB2(SCH_1):M_A_DQ<47>
  J4G1   113  DQ<46>  SCONN288_H44441004_PIP   I1
  J6T1   258  DQ<47>  SCONN288_H44441003_PIP  I13
  U5D1   P35  DDR0_DQ<47>  SKX_EXT_B_BGA1  I172

M_A_DQ<48>      @BASEBOARD_FAB2_LIB.BASEBOARD_FAB2(SCH_1):M_A_DQ<48>
  J4G1   264  DQ<49>  SCONN288_H44441004_PIP   I1
  J6T1   119  DQ<48>  SCONN288_H44441003_PIP  I13
  U5D1   K31  DDR0_DQ<48>  SKX_EXT_B_BGA1  I172

M_A_DQ<49>      @BASEBOARD_FAB2_LIB.BASEBOARD_FAB2(SCH_1):M_A_DQ<49>
  J4G1   119  DQ<48>  SCONN288_H44441004_PIP   I1
  J6T1   264  DQ<49>  SCONN288_H44441003_PIP  I13
  U5D1   P31  DDR0_DQ<49>  SKX_EXT_B_BGA1  I172

M_A_DQ<50>      @BASEBOARD_FAB2_LIB.BASEBOARD_FAB2(SCH_1):M_A_DQ<50>
  J4G1   271  DQ<51>  SCONN288_H44441004_PIP   I1
  J6T1   126  DQ<50>  SCONN288_H44441003_PIP  I13
  U5D1   L28  DDR0_DQ<50>  SKX_EXT_B_BGA1  I172

M_A_DQ<51>      @BASEBOARD_FAB2_LIB.BASEBOARD_FAB2(SCH_1):M_A_DQ<51>
  J4G1   126  DQ<50>  SCONN288_H44441004_PIP   I1
  J6T1   271  DQ<51>  SCONN288_H44441003_PIP  I13
  U5D1   N28  DDR0_DQ<51>  SKX_EXT_B_BGA1  I172

M_A_DQ<52>      @BASEBOARD_FAB2_LIB.BASEBOARD_FAB2(SCH_1):M_A_DQ<52>
  J4G1   262  DQ<53>  SCONN288_H44441004_PIP   I1
  J6T1   117  DQ<52>  SCONN288_H44441003_PIP  I13
  U5D1   L32  DDR0_DQ<52>  SKX_EXT_B_BGA1  I172

M_A_DQ<53>      @BASEBOARD_FAB2_LIB.BASEBOARD_FAB2(SCH_1):M_A_DQ<53>
  J4G1   117  DQ<52>  SCONN288_H44441004_PIP   I1
  J6T1   262  DQ<53>  SCONN288_H44441003_PIP  I13
  U5D1   N32  DDR0_DQ<53>  SKX_EXT_B_BGA1  I172

M_A_DQ<54>      @BASEBOARD_FAB2_LIB.BASEBOARD_FAB2(SCH_1):M_A_DQ<54>
  J4G1   269  DQ<55>  SCONN288_H44441004_PIP   I1
  J6T1   124  DQ<54>  SCONN288_H44441003_PIP  I13
  U5D1   K29  DDR0_DQ<54>  SKX_EXT_B_BGA1  I172

M_A_DQ<55>      @BASEBOARD_FAB2_LIB.BASEBOARD_FAB2(SCH_1):M_A_DQ<55>
  J4G1   124  DQ<54>  SCONN288_H44441004_PIP   I1
  J6T1   269  DQ<55>  SCONN288_H44441003_PIP  I13
  U5D1   P29  DDR0_DQ<55>  SKX_EXT_B_BGA1  I172

M_A_DQ<56>      @BASEBOARD_FAB2_LIB.BASEBOARD_FAB2(SCH_1):M_A_DQ<56>
  J4G1   275  DQ<57>  SCONN288_H44441004_PIP   I1
  J6T1   130  DQ<56>  SCONN288_H44441003_PIP  I13
  U5D1   K25  DDR0_DQ<56>  SKX_EXT_B_BGA1  I172

M_A_DQ<57>      @BASEBOARD_FAB2_LIB.BASEBOARD_FAB2(SCH_1):M_A_DQ<57>
  J4G1   130  DQ<56>  SCONN288_H44441004_PIP   I1
  J6T1   275  DQ<57>  SCONN288_H44441003_PIP  I13
  U5D1   P25  DDR0_DQ<57>  SKX_EXT_B_BGA1  I172

M_A_DQ<58>      @BASEBOARD_FAB2_LIB.BASEBOARD_FAB2(SCH_1):M_A_DQ<58>
  J4G1   282  DQ<59>  SCONN288_H44441004_PIP   I1
  J6T1   137  DQ<58>  SCONN288_H44441003_PIP  I13
  U5D1   P23  DDR0_DQ<58>  SKX_EXT_B_BGA1  I172

M_A_DQ<59>      @BASEBOARD_FAB2_LIB.BASEBOARD_FAB2(SCH_1):M_A_DQ<59>
  J4G1   137  DQ<58>  SCONN288_H44441004_PIP   I1
  J6T1   282  DQ<59>  SCONN288_H44441003_PIP  I13
  U5D1   T23  DDR0_DQ<59>  SKX_EXT_B_BGA1  I172

M_A_DQ<60>      @BASEBOARD_FAB2_LIB.BASEBOARD_FAB2(SCH_1):M_A_DQ<60>
  J4G1   273  DQ<61>  SCONN288_H44441004_PIP   I1
  J6T1   128  DQ<60>  SCONN288_H44441003_PIP  I13
  U5D1   L26  DDR0_DQ<60>  SKX_EXT_B_BGA1  I172

M_A_DQ<61>      @BASEBOARD_FAB2_LIB.BASEBOARD_FAB2(SCH_1):M_A_DQ<61>
  J4G1   128  DQ<60>  SCONN288_H44441004_PIP   I1
  J6T1   273  DQ<61>  SCONN288_H44441003_PIP  I13
  U5D1   N26  DDR0_DQ<61>  SKX_EXT_B_BGA1  I172

M_A_DQ<62>      @BASEBOARD_FAB2_LIB.BASEBOARD_FAB2(SCH_1):M_A_DQ<62>
  J4G1   280  DQ<63>  SCONN288_H44441004_PIP   I1
  J6T1   135  DQ<62>  SCONN288_H44441003_PIP  I13
  U5D1   H23  DDR0_DQ<62>  SKX_EXT_B_BGA1  I172

M_A_DQ<63>      @BASEBOARD_FAB2_LIB.BASEBOARD_FAB2(SCH_1):M_A_DQ<63>
  J4G1   135  DQ<62>  SCONN288_H44441004_PIP   I1
  J6T1   280  DQ<63>  SCONN288_H44441003_PIP  I13
  U5D1   K23  DDR0_DQ<63>  SKX_EXT_B_BGA1  I172

M_A_DQS_DN<0>   @BASEBOARD_FAB2_LIB.BASEBOARD_FAB2(SCH_1):M_A_DQS_DN<0>
  J4G1   152  DQS0N  SCONN288_H44441004_PIP   I2
  J6T1   152  DQS0N  SCONN288_H44441003_PIP  I120
  U5D1   AJ84  DDR0_DQS_DN<0>  SKX_EXT_B_BGA1  I172

M_A_DQS_DN<1>   @BASEBOARD_FAB2_LIB.BASEBOARD_FAB2(SCH_1):M_A_DQS_DN<1>
  J4G1   163  DQS1N  SCONN288_H44441004_PIP   I2
  J6T1   163  DQS1N  SCONN288_H44441003_PIP  I120
  U5D1   R84  DDR0_DQS_DN<1>  SKX_EXT_B_BGA1  I172

M_A_DQS_DN<2>   @BASEBOARD_FAB2_LIB.BASEBOARD_FAB2(SCH_1):M_A_DQS_DN<2>
  J4G1   174  DQS2N  SCONN288_H44441004_PIP   I2
  J6T1   174  DQS2N  SCONN288_H44441003_PIP  I120
  U5D1   P79  DDR0_DQS_DN<2>  SKX_EXT_B_BGA1  I172

M_A_DQS_DN<3>   @BASEBOARD_FAB2_LIB.BASEBOARD_FAB2(SCH_1):M_A_DQS_DN<3>
  J4G1   185  DQS3N  SCONN288_H44441004_PIP   I2
  J6T1   185  DQS3N  SCONN288_H44441003_PIP  I120
  U5D1   T75  DDR0_DQS_DN<3>  SKX_EXT_B_BGA1  I172

M_A_DQS_DN<4>   @BASEBOARD_FAB2_LIB.BASEBOARD_FAB2(SCH_1):M_A_DQS_DN<4>
  J4G1   244  DQS4N  SCONN288_H44441004_PIP   I2
  J6T1   244  DQS4N  SCONN288_H44441003_PIP  I120
  U5D1   G40  DDR0_DQS_DN<4>  SKX_EXT_B_BGA1  I172

M_A_DQS_DN<5>   @BASEBOARD_FAB2_LIB.BASEBOARD_FAB2(SCH_1):M_A_DQS_DN<5>
  J4G1   255  DQS5N  SCONN288_H44441004_PIP   I2
  J6T1   255  DQS5N  SCONN288_H44441003_PIP  I120
  U5D1   R36  DDR0_DQS_DN<5>  SKX_EXT_B_BGA1  I172

M_A_DQS_DN<6>   @BASEBOARD_FAB2_LIB.BASEBOARD_FAB2(SCH_1):M_A_DQS_DN<6>
  J4G1   266  DQS6N  SCONN288_H44441004_PIP   I2
  J6T1   266  DQS6N  SCONN288_H44441003_PIP  I120
  U5D1   R30  DDR0_DQS_DN<6>  SKX_EXT_B_BGA1  I172

M_A_DQS_DN<7>   @BASEBOARD_FAB2_LIB.BASEBOARD_FAB2(SCH_1):M_A_DQS_DN<7>
  J4G1   277  DQS7N  SCONN288_H44441004_PIP   I2
  J6T1   277  DQS7N  SCONN288_H44441003_PIP  I120
  U5D1   N24  DDR0_DQS_DN<7>  SKX_EXT_B_BGA1  I172

M_A_DQS_DN<8>   @BASEBOARD_FAB2_LIB.BASEBOARD_FAB2(SCH_1):M_A_DQS_DN<8>
  J4G1   196  DQS8N  SCONN288_H44441004_PIP   I2
  J6T1   196  DQS8N  SCONN288_H44441003_PIP  I120
  U5D1   AH67  DDR0_DQS_DN<8>  SKX_EXT_B_BGA1  I172

M_A_DQS_DN<9>   @BASEBOARD_FAB2_LIB.BASEBOARD_FAB2(SCH_1):M_A_DQS_DN<9>
  J4G1     8  DQS9N  SCONN288_H44441004_PIP   I2
  J6T1     8  DQS9N  SCONN288_H44441003_PIP  I120
  U5D1   AL84  DDR0_DQS_DN<9>  SKX_EXT_B_BGA1  I172

M_A_DQS_DN<10>   @BASEBOARD_FAB2_LIB.BASEBOARD_FAB2(SCH_1):M_A_DQS_DN<10>
  J4G1    19  DQS10N  SCONN288_H44441004_PIP   I2
  J6T1    19  DQS10N  SCONN288_H44441003_PIP  I120
  U5D1   U84  DDR0_DQS_DN<10>  SKX_EXT_B_BGA1  I172

M_A_DQS_DN<11>   @BASEBOARD_FAB2_LIB.BASEBOARD_FAB2(SCH_1):M_A_DQS_DN<11>
  J4G1    30  DQS11N  SCONN288_H44441004_PIP   I2
  J6T1    30  DQS11N  SCONN288_H44441003_PIP  I120
  U5D1   U82  DDR0_DQS_DN<11>  SKX_EXT_B_BGA1  I172

M_A_DQS_DN<12>   @BASEBOARD_FAB2_LIB.BASEBOARD_FAB2(SCH_1):M_A_DQS_DN<12>
  J4G1    41  DQS12N  SCONN288_H44441004_PIP   I2
  J6T1    41  DQS12N  SCONN288_H44441003_PIP  I120
  U5D1   K75  DDR0_DQS_DN<12>  SKX_EXT_B_BGA1  I172

M_A_DQS_DN<13>   @BASEBOARD_FAB2_LIB.BASEBOARD_FAB2(SCH_1):M_A_DQS_DN<13>
  J4G1   100  DQS13N  SCONN288_H44441004_PIP   I2
  J6T1   100  DQS13N  SCONN288_H44441003_PIP  I120
  U5D1   A40  DDR0_DQS_DN<13>  SKX_EXT_B_BGA1  I172

M_A_DQS_DN<14>   @BASEBOARD_FAB2_LIB.BASEBOARD_FAB2(SCH_1):M_A_DQS_DN<14>
  J4G1   111  DQS14N  SCONN288_H44441004_PIP   I2
  J6T1   111  DQS14N  SCONN288_H44441003_PIP  I120
  U5D1   J36  DDR0_DQS_DN<14>  SKX_EXT_B_BGA1  I172

M_A_DQS_DN<15>   @BASEBOARD_FAB2_LIB.BASEBOARD_FAB2(SCH_1):M_A_DQS_DN<15>
  J4G1   122  DQS15N  SCONN288_H44441004_PIP   I2
  J6T1   122  DQS15N  SCONN288_H44441003_PIP  I120
  U5D1   J30  DDR0_DQS_DN<15>  SKX_EXT_B_BGA1  I172

M_A_DQS_DN<16>   @BASEBOARD_FAB2_LIB.BASEBOARD_FAB2(SCH_1):M_A_DQS_DN<16>
  J4G1   133  DQS16N  SCONN288_H44441004_PIP   I2
  J6T1   133  DQS16N  SCONN288_H44441003_PIP  I120
  U5D1   J24  DDR0_DQS_DN<16>  SKX_EXT_B_BGA1  I172

M_A_DQS_DN<17>   @BASEBOARD_FAB2_LIB.BASEBOARD_FAB2(SCH_1):M_A_DQS_DN<17>
  J4G1    52  DQS17N  SCONN288_H44441004_PIP   I2
  J6T1    52  DQS17N  SCONN288_H44441003_PIP  I120
  U5D1   AB67  DDR0_DQS_DN<17>  SKX_EXT_B_BGA1  I172

M_A_DQS_DP<0>   @BASEBOARD_FAB2_LIB.BASEBOARD_FAB2(SCH_1):M_A_DQS_DP<0>
  J4G1   153  DQS0P  SCONN288_H44441004_PIP   I2
  J6T1   153  DQS0P  SCONN288_H44441003_PIP  I120
  U5D1   AH85  DDR0_DQS_DP<0>  SKX_EXT_B_BGA1  I172

M_A_DQS_DP<1>   @BASEBOARD_FAB2_LIB.BASEBOARD_FAB2(SCH_1):M_A_DQS_DP<1>
  J4G1   164  DQS1P  SCONN288_H44441004_PIP   I2
  J6T1   164  DQS1P  SCONN288_H44441003_PIP  I120
  U5D1   P85  DDR0_DQS_DP<1>  SKX_EXT_B_BGA1  I172

M_A_DQS_DP<2>   @BASEBOARD_FAB2_LIB.BASEBOARD_FAB2(SCH_1):M_A_DQS_DP<2>
  J4G1   175  DQS2P  SCONN288_H44441004_PIP   I2
  J6T1   175  DQS2P  SCONN288_H44441003_PIP  I120
  U5D1   R80  DDR0_DQS_DP<2>  SKX_EXT_B_BGA1  I172

M_A_DQS_DP<3>   @BASEBOARD_FAB2_LIB.BASEBOARD_FAB2(SCH_1):M_A_DQS_DP<3>
  J4G1   186  DQS3P  SCONN288_H44441004_PIP   I2
  J6T1   186  DQS3P  SCONN288_H44441003_PIP  I120
  U5D1   P75  DDR0_DQS_DP<3>  SKX_EXT_B_BGA1  I172

M_A_DQS_DP<4>   @BASEBOARD_FAB2_LIB.BASEBOARD_FAB2(SCH_1):M_A_DQS_DP<4>
  J4G1   245  DQS4P  SCONN288_H44441004_PIP   I2
  J6T1   245  DQS4P  SCONN288_H44441003_PIP  I120
  U5D1   E40  DDR0_DQS_DP<4>  SKX_EXT_B_BGA1  I172

M_A_DQS_DP<5>   @BASEBOARD_FAB2_LIB.BASEBOARD_FAB2(SCH_1):M_A_DQS_DP<5>
  J4G1   256  DQS5P  SCONN288_H44441004_PIP   I2
  J6T1   256  DQS5P  SCONN288_H44441003_PIP  I120
  U5D1   N36  DDR0_DQS_DP<5>  SKX_EXT_B_BGA1  I172

M_A_DQS_DP<6>   @BASEBOARD_FAB2_LIB.BASEBOARD_FAB2(SCH_1):M_A_DQS_DP<6>
  J4G1   267  DQS6P  SCONN288_H44441004_PIP   I2
  J6T1   267  DQS6P  SCONN288_H44441003_PIP  I120
  U5D1   N30  DDR0_DQS_DP<6>  SKX_EXT_B_BGA1  I172

M_A_DQS_DP<7>   @BASEBOARD_FAB2_LIB.BASEBOARD_FAB2(SCH_1):M_A_DQS_DP<7>
  J4G1   278  DQS7P  SCONN288_H44441004_PIP   I2
  J6T1   278  DQS7P  SCONN288_H44441003_PIP  I120
  U5D1   R24  DDR0_DQS_DP<7>  SKX_EXT_B_BGA1  I172

M_A_DQS_DP<8>   @BASEBOARD_FAB2_LIB.BASEBOARD_FAB2(SCH_1):M_A_DQS_DP<8>
  J4G1   197  DQS8P  SCONN288_H44441004_PIP   I2
  J6T1   197  DQS8P  SCONN288_H44441003_PIP  I120
  U5D1   AF67  DDR0_DQS_DP<8>  SKX_EXT_B_BGA1  I172

M_A_DQS_DP<9>   @BASEBOARD_FAB2_LIB.BASEBOARD_FAB2(SCH_1):M_A_DQS_DP<9>
  J4G1     7  DQS9P  SCONN288_H44441004_PIP   I2
  J6T1     7  DQS9P  SCONN288_H44441003_PIP  I120
  U5D1   AM85  DDR0_DQS_DP<9>  SKX_EXT_B_BGA1  I172

M_A_DQS_DP<10>   @BASEBOARD_FAB2_LIB.BASEBOARD_FAB2(SCH_1):M_A_DQS_DP<10>
  J4G1    18  DQS10P  SCONN288_H44441004_PIP   I2
  J6T1    18  DQS10P  SCONN288_H44441003_PIP  I120
  U5D1   V85  DDR0_DQS_DP<10>  SKX_EXT_B_BGA1  I172

M_A_DQS_DP<11>   @BASEBOARD_FAB2_LIB.BASEBOARD_FAB2(SCH_1):M_A_DQS_DP<11>
  J4G1    29  DQS11P  SCONN288_H44441004_PIP   I2
  J6T1    29  DQS11P  SCONN288_H44441003_PIP  I120
  U5D1   T81  DDR0_DQS_DP<11>  SKX_EXT_B_BGA1  I172

M_A_DQS_DP<12>   @BASEBOARD_FAB2_LIB.BASEBOARD_FAB2(SCH_1):M_A_DQS_DP<12>
  J4G1    40  DQS12P  SCONN288_H44441004_PIP   I2
  J6T1    40  DQS12P  SCONN288_H44441003_PIP  I120
  U5D1   M75  DDR0_DQS_DP<12>  SKX_EXT_B_BGA1  I172

M_A_DQS_DP<13>   @BASEBOARD_FAB2_LIB.BASEBOARD_FAB2(SCH_1):M_A_DQS_DP<13>
  J4G1    99  DQS13P  SCONN288_H44441004_PIP   I2
  J6T1    99  DQS13P  SCONN288_H44441003_PIP  I120
  U5D1   C40  DDR0_DQS_DP<13>  SKX_EXT_B_BGA1  I172

M_A_DQS_DP<14>   @BASEBOARD_FAB2_LIB.BASEBOARD_FAB2(SCH_1):M_A_DQS_DP<14>
  J4G1   110  DQS14P  SCONN288_H44441004_PIP   I2
  J6T1   110  DQS14P  SCONN288_H44441003_PIP  I120
  U5D1   L36  DDR0_DQS_DP<14>  SKX_EXT_B_BGA1  I172

M_A_DQS_DP<15>   @BASEBOARD_FAB2_LIB.BASEBOARD_FAB2(SCH_1):M_A_DQS_DP<15>
  J4G1   121  DQS15P  SCONN288_H44441004_PIP   I2
  J6T1   121  DQS15P  SCONN288_H44441003_PIP  I120
  U5D1   L30  DDR0_DQS_DP<15>  SKX_EXT_B_BGA1  I172

M_A_DQS_DP<16>   @BASEBOARD_FAB2_LIB.BASEBOARD_FAB2(SCH_1):M_A_DQS_DP<16>
  J4G1   132  DQS16P  SCONN288_H44441004_PIP   I2
  J6T1   132  DQS16P  SCONN288_H44441003_PIP  I120
  U5D1   L24  DDR0_DQS_DP<16>  SKX_EXT_B_BGA1  I172

M_A_DQS_DP<17>   @BASEBOARD_FAB2_LIB.BASEBOARD_FAB2(SCH_1):M_A_DQS_DP<17>
  J4G1    51  DQS17P  SCONN288_H44441004_PIP   I2
  J6T1    51  DQS17P  SCONN288_H44441003_PIP  I120
  U5D1   AD67  DDR0_DQS_DP<17>  SKX_EXT_B_BGA1  I172

M_A_ECC<0>      @BASEBOARD_FAB2_LIB.BASEBOARD_FAB2(SCH_1):M_A_ECC<0>
  J4G1   194  CB<1>  SCONN288_H44441004_PIP   I1
  J6T1    49  CB<0>  SCONN288_H44441003_PIP  I13
  U5D1   AC68  DDR0_ECC<0>  SKX_EXT_B_BGA1  I172

M_A_ECC<1>      @BASEBOARD_FAB2_LIB.BASEBOARD_FAB2(SCH_1):M_A_ECC<1>
  J4G1    49  CB<0>  SCONN288_H44441004_PIP   I1
  J6T1   194  CB<1>  SCONN288_H44441003_PIP  I13
  U5D1   AG68  DDR0_ECC<1>  SKX_EXT_B_BGA1  I172

M_A_ECC<2>      @BASEBOARD_FAB2_LIB.BASEBOARD_FAB2(SCH_1):M_A_ECC<2>
  J4G1   201  CB<3>  SCONN288_H44441004_PIP   I1
  J6T1    56  CB<2>  SCONN288_H44441003_PIP  I13
  U5D1   AD65  DDR0_ECC<2>  SKX_EXT_B_BGA1  I172

M_A_ECC<3>      @BASEBOARD_FAB2_LIB.BASEBOARD_FAB2(SCH_1):M_A_ECC<3>
  J4G1    56  CB<2>  SCONN288_H44441004_PIP   I1
  J6T1   201  CB<3>  SCONN288_H44441003_PIP  I13
  U5D1   AF65  DDR0_ECC<3>  SKX_EXT_B_BGA1  I172

M_A_ECC<4>      @BASEBOARD_FAB2_LIB.BASEBOARD_FAB2(SCH_1):M_A_ECC<4>
  J4G1   192  CB<5>  SCONN288_H44441004_PIP   I1
  J6T1    47  CB<4>  SCONN288_H44441003_PIP  I13
  U5D1   AD69  DDR0_ECC<4>  SKX_EXT_B_BGA1  I172

M_A_ECC<5>      @BASEBOARD_FAB2_LIB.BASEBOARD_FAB2(SCH_1):M_A_ECC<5>
  J4G1    47  CB<4>  SCONN288_H44441004_PIP   I1
  J6T1   192  CB<5>  SCONN288_H44441003_PIP  I13
  U5D1   AF69  DDR0_ECC<5>  SKX_EXT_B_BGA1  I172

M_A_ECC<6>      @BASEBOARD_FAB2_LIB.BASEBOARD_FAB2(SCH_1):M_A_ECC<6>
  J4G1   199  CB<7>  SCONN288_H44441004_PIP   I1
  J6T1    54  CB<6>  SCONN288_H44441003_PIP  I13
  U5D1   AC66  DDR0_ECC<6>  SKX_EXT_B_BGA1  I172

M_A_ECC<7>      @BASEBOARD_FAB2_LIB.BASEBOARD_FAB2(SCH_1):M_A_ECC<7>
  J4G1    54  CB<6>  SCONN288_H44441004_PIP   I1
  J6T1   199  CB<7>  SCONN288_H44441003_PIP  I13
  U5D1   AG66  DDR0_ECC<7>  SKX_EXT_B_BGA1  I172

M_A_MA<0>       @BASEBOARD_FAB2_LIB.BASEBOARD_FAB2(SCH_1):M_A_MA<0>
  J4G1    79     A0  SCONN288_H44441004_PIP   I1
  J6T1    79     A0  SCONN288_H44441003_PIP  I13
  U5D1   F53  DDR0_MA<0>  SKX_EXT_B_BGA1  I172

M_A_MA<1>       @BASEBOARD_FAB2_LIB.BASEBOARD_FAB2(SCH_1):M_A_MA<1>
  J4G1    72     A1  SCONN288_H44441004_PIP   I1
  J6T1    72     A1  SCONN288_H44441003_PIP  I13
  U5D1   F57  DDR0_MA<1>  SKX_EXT_B_BGA1  I172

M_A_MA<2>       @BASEBOARD_FAB2_LIB.BASEBOARD_FAB2(SCH_1):M_A_MA<2>
  J4G1   216     A2  SCONN288_H44441004_PIP   I1
  J6T1   216     A2  SCONN288_H44441003_PIP  I13
  U5D1   D57  DDR0_MA<2>  SKX_EXT_B_BGA1  I172

M_A_MA<3>       @BASEBOARD_FAB2_LIB.BASEBOARD_FAB2(SCH_1):M_A_MA<3>
  J4G1    71     A3  SCONN288_H44441004_PIP   I1
  J6T1    71     A3  SCONN288_H44441003_PIP  I13
  U5D1   C58  DDR0_MA<3>  SKX_EXT_B_BGA1  I172

M_A_MA<4>       @BASEBOARD_FAB2_LIB.BASEBOARD_FAB2(SCH_1):M_A_MA<4>
  J4G1   214     A4  SCONN288_H44441004_PIP   I1
  J6T1   214     A4  SCONN288_H44441003_PIP  I13
  U5D1   G58  DDR0_MA<4>  SKX_EXT_B_BGA1  I172

M_A_MA<5>       @BASEBOARD_FAB2_LIB.BASEBOARD_FAB2(SCH_1):M_A_MA<5>
  J4G1   213     A5  SCONN288_H44441004_PIP   I1
  J6T1   213     A5  SCONN288_H44441003_PIP  I13
  U5D1   F59  DDR0_MA<5>  SKX_EXT_B_BGA1  I172

M_A_MA<6>       @BASEBOARD_FAB2_LIB.BASEBOARD_FAB2(SCH_1):M_A_MA<6>
  J4G1    69     A6  SCONN288_H44441004_PIP   I1
  J6T1    69     A6  SCONN288_H44441003_PIP  I13
  U5D1   D59  DDR0_MA<6>  SKX_EXT_B_BGA1  I172

M_A_MA<7>       @BASEBOARD_FAB2_LIB.BASEBOARD_FAB2(SCH_1):M_A_MA<7>
  J4G1   211     A7  SCONN288_H44441004_PIP   I1
  J6T1   211     A7  SCONN288_H44441003_PIP  I13
  U5D1   G60  DDR0_MA<7>  SKX_EXT_B_BGA1  I172

M_A_MA<8>       @BASEBOARD_FAB2_LIB.BASEBOARD_FAB2(SCH_1):M_A_MA<8>
  J4G1    68     A8  SCONN288_H44441004_PIP   I1
  J6T1    68     A8  SCONN288_H44441003_PIP  I13
  U5D1   C60  DDR0_MA<8>  SKX_EXT_B_BGA1  I172

M_A_MA<9>       @BASEBOARD_FAB2_LIB.BASEBOARD_FAB2(SCH_1):M_A_MA<9>
  J4G1    66     A9  SCONN288_H44441004_PIP   I1
  J6T1    66     A9  SCONN288_H44441003_PIP  I13
  U5D1   F61  DDR0_MA<9>  SKX_EXT_B_BGA1  I172

M_A_MA<10>      @BASEBOARD_FAB2_LIB.BASEBOARD_FAB2(SCH_1):M_A_MA<10>
  J4G1   225    A10  SCONN288_H44441004_PIP   I1
  J6T1   225    A10  SCONN288_H44441003_PIP  I13
  U5D1   J54  DDR0_MA<10>  SKX_EXT_B_BGA1  I172

M_A_MA<11>      @BASEBOARD_FAB2_LIB.BASEBOARD_FAB2(SCH_1):M_A_MA<11>
  J4G1   210    A11  SCONN288_H44441004_PIP   I1
  J6T1   210    A11  SCONN288_H44441003_PIP  I13
  U5D1   G62  DDR0_MA<11>  SKX_EXT_B_BGA1  I172

M_A_MA<12>      @BASEBOARD_FAB2_LIB.BASEBOARD_FAB2(SCH_1):M_A_MA<12>
  J4G1    65    A12  SCONN288_H44441004_PIP   I1
  J6T1    65    A12  SCONN288_H44441003_PIP  I13
  U5D1   J64  DDR0_MA<12>  SKX_EXT_B_BGA1  I172

M_A_MA<13>      @BASEBOARD_FAB2_LIB.BASEBOARD_FAB2(SCH_1):M_A_MA<13>
  J4G1   232    A13  SCONN288_H44441004_PIP   I1
  J6T1   232    A13  SCONN288_H44441003_PIP  I13
  U5D1   J48  DDR0_MA<13>  SKX_EXT_B_BGA1  I172

M_A_MA<14>      @BASEBOARD_FAB2_LIB.BASEBOARD_FAB2(SCH_1):M_A_MA<14>
  J4G1   228  A14_WE_N  SCONN288_H44441004_PIP   I1
  J6T1   228  A14_WE_N  SCONN288_H44441003_PIP  I13
  U5D1   F51  DDR0_MA<14>  SKX_EXT_B_BGA1  I172

M_A_MA<15>      @BASEBOARD_FAB2_LIB.BASEBOARD_FAB2(SCH_1):M_A_MA<15>
  J4G1    86  A15_CAS_N  SCONN288_H44441004_PIP   I1
  J6T1    86  A15_CAS_N  SCONN288_H44441003_PIP  I13
  U5D1   K49  DDR0_MA<15>  SKX_EXT_B_BGA1  I172

M_A_MA<16>      @BASEBOARD_FAB2_LIB.BASEBOARD_FAB2(SCH_1):M_A_MA<16>
  J4G1    82  A16_RAS_N  SCONN288_H44441004_PIP   I1
  J6T1    82  A16_RAS_N  SCONN288_H44441003_PIP  I13
  U5D1   D51  DDR0_MA<16>  SKX_EXT_B_BGA1  I172

M_A_MA<17>      @BASEBOARD_FAB2_LIB.BASEBOARD_FAB2(SCH_1):M_A_MA<17>
  J4G1   234    A17  SCONN288_H44441004_PIP   I1
  J6T1   234    A17  SCONN288_H44441003_PIP  I13
  U5D1   K47  DDR0_MA<17>  SKX_EXT_B_BGA1  I172

M_A_ODT<0>      @BASEBOARD_FAB2_LIB.BASEBOARD_FAB2(SCH_1):M_A_ODT<0>
  J4G1    87  ODT<0>  SCONN288_H44441004_PIP   I1
  U5D1   C50  DDR0_ODT<0>  SKX_EXT_B_BGA1  I172

M_A_ODT<1>      @BASEBOARD_FAB2_LIB.BASEBOARD_FAB2(SCH_1):M_A_ODT<1>
  J4G1    91  ODT<1>  SCONN288_H44441004_PIP   I1
  U5D1   C48  DDR0_ODT<1>  SKX_EXT_B_BGA1  I172

M_A_ODT<2>      @BASEBOARD_FAB2_LIB.BASEBOARD_FAB2(SCH_1):M_A_ODT<2>
  J6T1    87  ODT<0>  SCONN288_H44441003_PIP  I13
  U5D1   G50  DDR0_ODT<2>  SKX_EXT_B_BGA1  I172

M_A_ODT<3>      @BASEBOARD_FAB2_LIB.BASEBOARD_FAB2(SCH_1):M_A_ODT<3>
  J6T1    91  ODT<1>  SCONN288_H44441003_PIP  I13
  U5D1   G48  DDR0_ODT<3>  SKX_EXT_B_BGA1  I172

M_A_PAR         @BASEBOARD_FAB2_LIB.BASEBOARD_FAB2(SCH_1):M_A_PAR
  J4G1   222    PAR  SCONN288_H44441004_PIP   I1
  J6T1   222    PAR  SCONN288_H44441003_PIP  I13
  U5D1   D53  DDR0_PAR  SKX_EXT_B_BGA1  I172

M_A_VREF        @BASEBOARD_FAB2_LIB.BASEBOARD_FAB2(SCH_1):M_A_VREF
  C4F10    1      A  CAP_A       I272
  C6T1     1      A  CAP_A        I2
  J4G1   146  VREFCA  SCONN288_H44441004_PIP   I1
  J6T1   146  VREFCA  SCONN288_H44441003_PIP  I13
  R4F3     2      B  RES          I5
  R4F4     2      B  RES         I36
  R4F5     1      A  RES          I4

M_BMC_DDR3_DQ<0>   @BASEBOARD_FAB2_LIB.BASEBOARD_FAB2(SCH_1):M_BMC_DDR3_DQ<0>
  U9F4   W12  MDQ<0>  AST1250_BGA  I281
  U9F5    H7   DQL7  K4B1G16_BGA1   I1

M_BMC_DDR3_DQ<1>   @BASEBOARD_FAB2_LIB.BASEBOARD_FAB2(SCH_1):M_BMC_DDR3_DQ<1>
  U9F4   V12  MDQ<1>  AST1250_BGA  I281
  U9F5    H3   DQL4  K4B1G16_BGA1   I1

M_BMC_DDR3_DQ<2>   @BASEBOARD_FAB2_LIB.BASEBOARD_FAB2(SCH_1):M_BMC_DDR3_DQ<2>
  U9F4   AB11  MDQ<2>  AST1250_BGA  I281
  U9F5    F8   DQL3  K4B1G16_BGA1   I1

M_BMC_DDR3_DQ<3>   @BASEBOARD_FAB2_LIB.BASEBOARD_FAB2(SCH_1):M_BMC_DDR3_DQ<3>
  U9F4   AA11  MDQ<3>  AST1250_BGA  I281
  U9F5    F7   DQL1  K4B1G16_BGA1   I1

M_BMC_DDR3_DQ<4>   @BASEBOARD_FAB2_LIB.BASEBOARD_FAB2(SCH_1):M_BMC_DDR3_DQ<4>
  U9F4   Y11  MDQ<4>  AST1250_BGA  I281
  U9F5    F2   DQL2  K4B1G16_BGA1   I1

M_BMC_DDR3_DQ<5>   @BASEBOARD_FAB2_LIB.BASEBOARD_FAB2(SCH_1):M_BMC_DDR3_DQ<5>
  U9F4   W11  MDQ<5>  AST1250_BGA  I281
  U9F5    G2   DQL6  K4B1G16_BGA1   I1

M_BMC_DDR3_DQ<6>   @BASEBOARD_FAB2_LIB.BASEBOARD_FAB2(SCH_1):M_BMC_DDR3_DQ<6>
  U9F4   V11  MDQ<6>  AST1250_BGA  I281
  U9F5    H8   DQL5  K4B1G16_BGA1   I1

M_BMC_DDR3_DQ<7>   @BASEBOARD_FAB2_LIB.BASEBOARD_FAB2(SCH_1):M_BMC_DDR3_DQ<7>
  U9F4   Y10  MDQ<7>  AST1250_BGA  I281
  U9F5    E3   DQL0  K4B1G16_BGA1   I1

M_BMC_DDR3_DQ<8>   @BASEBOARD_FAB2_LIB.BASEBOARD_FAB2(SCH_1):M_BMC_DDR3_DQ<8>
  U9F4   V10  MDQ<8>  AST1250_BGA  I281
  U9F5    D7   DQU0  K4B1G16_BGA1   I1

M_BMC_DDR3_DQ<9>   @BASEBOARD_FAB2_LIB.BASEBOARD_FAB2(SCH_1):M_BMC_DDR3_DQ<9>
  U9F4   AB9  MDQ<9>  AST1250_BGA  I281
  U9F5    B8   DQU6  K4B1G16_BGA1   I1

M_BMC_DDR3_DQ<10>   @BASEBOARD_FAB2_LIB.BASEBOARD_FAB2(SCH_1):M_BMC_DDR3_DQ<10>
  U9F4   AA9  MDQ<10>  AST1250_BGA  I281
  U9F5    A7   DQU4  K4B1G16_BGA1   I1

M_BMC_DDR3_DQ<11>   @BASEBOARD_FAB2_LIB.BASEBOARD_FAB2(SCH_1):M_BMC_DDR3_DQ<11>
  U9F4    Y9  MDQ<11>  AST1250_BGA  I281
  U9F5    C3   DQU1  K4B1G16_BGA1   I1

M_BMC_DDR3_DQ<12>   @BASEBOARD_FAB2_LIB.BASEBOARD_FAB2(SCH_1):M_BMC_DDR3_DQ<12>
  U9F4    W9  MDQ<12>  AST1250_BGA  I281
  U9F5    C2   DQU3  K4B1G16_BGA1   I1

M_BMC_DDR3_DQ<13>   @BASEBOARD_FAB2_LIB.BASEBOARD_FAB2(SCH_1):M_BMC_DDR3_DQ<13>
  U9F4    V9  MDQ<13>  AST1250_BGA  I281
  U9F5    C8   DQU2  K4B1G16_BGA1   I1

M_BMC_DDR3_DQ<14>   @BASEBOARD_FAB2_LIB.BASEBOARD_FAB2(SCH_1):M_BMC_DDR3_DQ<14>
  U9F4    Y8  MDQ<14>  AST1250_BGA  I281
  U9F5    A3   DQU7  K4B1G16_BGA1   I1

M_BMC_DDR3_DQ<15>   @BASEBOARD_FAB2_LIB.BASEBOARD_FAB2(SCH_1):M_BMC_DDR3_DQ<15>
  U9F4    W8  MDQ<15>  AST1250_BGA  I281
  U9F5    A2   DQU5  K4B1G16_BGA1   I1

M_BMC_DDR3_MA<0>   @BASEBOARD_FAB2_LIB.BASEBOARD_FAB2(SCH_1):M_BMC_DDR3_MA<0>
  U9F4   AB14  MA<0>  AST1250_BGA  I281
  U9F5    N3     A0  K4B1G16_BGA1   I1

M_BMC_DDR3_MA<1>   @BASEBOARD_FAB2_LIB.BASEBOARD_FAB2(SCH_1):M_BMC_DDR3_MA<1>
  U9F4   W15  MA<1>  AST1250_BGA  I281
  U9F5    P7     A1  K4B1G16_BGA1   I1

M_BMC_DDR3_MA<2>   @BASEBOARD_FAB2_LIB.BASEBOARD_FAB2(SCH_1):M_BMC_DDR3_MA<2>
  U9F4   V15  MA<2>  AST1250_BGA  I281
  U9F5    P3     A2  K4B1G16_BGA1   I1

M_BMC_DDR3_MA<3>   @BASEBOARD_FAB2_LIB.BASEBOARD_FAB2(SCH_1):M_BMC_DDR3_MA<3>
  U9F4   Y16  MA<3>  AST1250_BGA  I281
  U9F5    N2     A3  K4B1G16_BGA1   I1

M_BMC_DDR3_MA<4>   @BASEBOARD_FAB2_LIB.BASEBOARD_FAB2(SCH_1):M_BMC_DDR3_MA<4>
  U9F4   AB15  MA<4>  AST1250_BGA  I281
  U9F5    P8     A4  K4B1G16_BGA1   I1

M_BMC_DDR3_MA<5>   @BASEBOARD_FAB2_LIB.BASEBOARD_FAB2(SCH_1):M_BMC_DDR3_MA<5>
  U9F4   W16  MA<5>  AST1250_BGA  I281
  U9F5    P2     A5  K4B1G16_BGA1   I1

M_BMC_DDR3_MA<6>   @BASEBOARD_FAB2_LIB.BASEBOARD_FAB2(SCH_1):M_BMC_DDR3_MA<6>
  U9F4   AA15  MA<6>  AST1250_BGA  I281
  U9F5    R8     A6  K4B1G16_BGA1   I1

M_BMC_DDR3_MA<7>   @BASEBOARD_FAB2_LIB.BASEBOARD_FAB2(SCH_1):M_BMC_DDR3_MA<7>
  U9F4   AB18  MA<7>  AST1250_BGA  I281
  U9F5    R2     A7  K4B1G16_BGA1   I1

M_BMC_DDR3_MA<8>   @BASEBOARD_FAB2_LIB.BASEBOARD_FAB2(SCH_1):M_BMC_DDR3_MA<8>
  U9F4   AB16  MA<8>  AST1250_BGA  I281
  U9F5    T8     A8  K4B1G16_BGA1   I1

M_BMC_DDR3_MA<9>   @BASEBOARD_FAB2_LIB.BASEBOARD_FAB2(SCH_1):M_BMC_DDR3_MA<9>
  U9F4   AA17  MA<9>  AST1250_BGA  I281
  U9F5    R3     A9  K4B1G16_BGA1   I1

M_BMC_DDR3_MA<10>   @BASEBOARD_FAB2_LIB.BASEBOARD_FAB2(SCH_1):M_BMC_DDR3_MA<10>
  U9F4   Y15  MA<10>  AST1250_BGA  I281
  U9F5    L7  A10_AP  K4B1G16_BGA1   I1

M_BMC_DDR3_MA<11>   @BASEBOARD_FAB2_LIB.BASEBOARD_FAB2(SCH_1):M_BMC_DDR3_MA<11>
  U9F4   AA16  MA<11>  AST1250_BGA  I281
  U9F5    R7    A11  K4B1G16_BGA1   I1

M_BMC_DDR3_MA<12>   @BASEBOARD_FAB2_LIB.BASEBOARD_FAB2(SCH_1):M_BMC_DDR3_MA<12>
  U9F4   W17  MA<12>  AST1250_BGA  I281
  U9F5    N7  A12/BC_N  K4B1G16_BGA1   I1

M_BMC_DDR3_MA<13>   @BASEBOARD_FAB2_LIB.BASEBOARD_FAB2(SCH_1):M_BMC_DDR3_MA<13>
  U9F4   Y17  MA<13>  AST1250_BGA  I281
  U9F5    T3  NC<5>  K4B1G16_BGA1   I1

M_BMC_DDR3_MA<14>   @BASEBOARD_FAB2_LIB.BASEBOARD_FAB2(SCH_1):M_BMC_DDR3_MA<14>
  U9F4   AB17  MA<14>  AST1250_BGA  I281
  U9F5    T7  NC<6>  K4B1G16_BGA1   I1

M_BMC_DDR3_MBA_0   @BASEBOARD_FAB2_LIB.BASEBOARD_FAB2(SCH_1):M_BMC_DDR3_MBA_0
  U9F4   W14  MBA<0>  AST1250_BGA  I281
  U9F5    M2    BA0  K4B1G16_BGA1   I1

M_BMC_DDR3_MBA_1   @BASEBOARD_FAB2_LIB.BASEBOARD_FAB2(SCH_1):M_BMC_DDR3_MBA_1
  U9F4   AA14  MBA<1>  AST1250_BGA  I281
  U9F5    N8    BA1  K4B1G16_BGA1   I1

M_BMC_DDR3_MBA_2   @BASEBOARD_FAB2_LIB.BASEBOARD_FAB2(SCH_1):M_BMC_DDR3_MBA_2
  U9F4   Y14  MBA<2>  AST1250_BGA  I281
  U9F5    M3    BA2  K4B1G16_BGA1   I1

M_BMC_DDR3_MCAS_N   @BASEBOARD_FAB2_LIB.BASEBOARD_FAB2(SCH_1):M_BMC_DDR3_MCAS_N
  U9F4   AB13  MCAS_N  AST1250_BGA  I281
  U9F5    K3  CAS_N  K4B1G16_BGA1   I1

M_BMC_DDR3_MCKE   @BASEBOARD_FAB2_LIB.BASEBOARD_FAB2(SCH_1):M_BMC_DDR3_MCKE
  U9F4   Y12   MCKE  AST1250_BGA  I281
  U9F5    K9    CKE  K4B1G16_BGA1   I1

M_BMC_DDR3_MCK_N   @BASEBOARD_FAB2_LIB.BASEBOARD_FAB2(SCH_1):M_BMC_DDR3_MCK_N
  U9F4   AA12   MCKN  AST1250_BGA  I281
  U9F5    K7   CK_N  K4B1G16_BGA1   I1

M_BMC_DDR3_MCK_P   @BASEBOARD_FAB2_LIB.BASEBOARD_FAB2(SCH_1):M_BMC_DDR3_MCK_P
  U9F4   AB12   MCKP  AST1250_BGA  I281
  U9F5    J7     CK  K4B1G16_BGA1   I1

M_BMC_DDR3_MCS_N   @BASEBOARD_FAB2_LIB.BASEBOARD_FAB2(SCH_1):M_BMC_DDR3_MCS_N
  U9F4   AA13  MCS_N  AST1250_BGA  I281
  U9F5    L2   CS_N  K4B1G16_BGA1   I1

M_BMC_DDR3_MDM_0   @BASEBOARD_FAB2_LIB.BASEBOARD_FAB2(SCH_1):M_BMC_DDR3_MDM_0
  U9F4   W10  MDM<0>  AST1250_BGA  I281
  U9F5    E7    DML  K4B1G16_BGA1   I1

M_BMC_DDR3_MDM_1   @BASEBOARD_FAB2_LIB.BASEBOARD_FAB2(SCH_1):M_BMC_DDR3_MDM_1
  U9F4    V8  MDM<1>  AST1250_BGA  I281
  U9F5    D3    DMU  K4B1G16_BGA1   I1

M_BMC_DDR3_MDQS_0_DN   @BASEBOARD_FAB2_LIB.BASEBOARD_FAB2(SCH_1):M_BMC_DDR3_MDQS_0_DN
  U9F4   AA10  MDQS0_N  AST1250_BGA  I281
  U9F5    G3  DQSL_N  K4B1G16_BGA1   I1

M_BMC_DDR3_MDQS_0_DP   @BASEBOARD_FAB2_LIB.BASEBOARD_FAB2(SCH_1):M_BMC_DDR3_MDQS_0_DP
  U9F4   AB10  MDQS0  AST1250_BGA  I281
  U9F5    F3   DQSL  K4B1G16_BGA1   I1

M_BMC_DDR3_MDQS_1_DN   @BASEBOARD_FAB2_LIB.BASEBOARD_FAB2(SCH_1):M_BMC_DDR3_MDQS_1_DN
  U9F4   AB8  MDQS1_N  AST1250_BGA  I281
  U9F5    B7  DQSU_N  K4B1G16_BGA1   I1

M_BMC_DDR3_MDQS_1_DP   @BASEBOARD_FAB2_LIB.BASEBOARD_FAB2(SCH_1):M_BMC_DDR3_MDQS_1_DP
  U9F4   AA8  MDQS1  AST1250_BGA  I281
  U9F5    C7   DQSU  K4B1G16_BGA1   I1

M_BMC_DDR3_MODT   @BASEBOARD_FAB2_LIB.BASEBOARD_FAB2(SCH_1):M_BMC_DDR3_MODT
  U9F4   V14   MODT  AST1250_BGA  I281
  U9F5    K1    ODT  K4B1G16_BGA1   I1

M_BMC_DDR3_MRAS_N   @BASEBOARD_FAB2_LIB.BASEBOARD_FAB2(SCH_1):M_BMC_DDR3_MRAS_N
  U9F4   W13  MRAS_N  AST1250_BGA  I281
  U9F5    J3  RAS_N  K4B1G16_BGA1   I1

M_BMC_DDR3_MVREF   @BASEBOARD_FAB2_LIB.BASEBOARD_FAB2(SCH_1):M_BMC_DDR3_MVREF
  C1T37    1      A  CAP_A       I336
  C1T39    2      B  CAP_A       I64
  C1T41    1      A  CAP_A       I63
  C1T48    1      A  CAP_A       I58
  C1T51    1      A  CAP_A       I62
  R1T29    1      A  RES         I61
  R1T30    2      B  RES         I60
  U9F4   V13  MVREF  AST1250_BGA  I281
  U9F5    H1  VREFDQ  K4B1G16_BGA1   I1
  U9F5    M8  VREFCA  K4B1G16_BGA1   I1

M_BMC_DDR3_MWE_N   @BASEBOARD_FAB2_LIB.BASEBOARD_FAB2(SCH_1):M_BMC_DDR3_MWE_N
  U9F4   Y13  MWE_N  AST1250_BGA  I281
  U9F5    L3   WE_N  K4B1G16_BGA1   I1

M_B_ACT_N       @BASEBOARD_FAB2_LIB.BASEBOARD_FAB2(SCH_1):M_B_ACT_N
  J4G2    62  ACT_N  SCONN288_H44441004_PIP  I111
  J6U1    62  ACT_N  SCONN288_H44441003_PIP  I14
  U5D1   T63  DDR1_ACT_N  SKX_EXT_B_BGA1  I172

M_B_ALERT_N     @BASEBOARD_FAB2_LIB.BASEBOARD_FAB2(SCH_1):M_B_ALERT_N
  J4G2   208  ALERT_N  SCONN288_H44441004_PIP  I111
  J6U1   208  ALERT_N  SCONN288_H44441003_PIP  I14
  U5D1   W62  DDR1_ALERT_N  SKX_EXT_B_BGA1  I172

M_B_BA<0>       @BASEBOARD_FAB2_LIB.BASEBOARD_FAB2(SCH_1):M_B_BA<0>
  J4G2    81  BA<0>  SCONN288_H44441004_PIP  I111
  J6U1    81  BA<0>  SCONN288_H44441003_PIP  I14
  U5D1   T53  DDR1_BA<0>  SKX_EXT_B_BGA1  I172

M_B_BA<1>       @BASEBOARD_FAB2_LIB.BASEBOARD_FAB2(SCH_1):M_B_BA<1>
  J4G2   224  BA<1>  SCONN288_H44441004_PIP  I111
  J6U1   224  BA<1>  SCONN288_H44441003_PIP  I14
  U5D1   K55  DDR1_BA<1>  SKX_EXT_B_BGA1  I172

M_B_BG<0>       @BASEBOARD_FAB2_LIB.BASEBOARD_FAB2(SCH_1):M_B_BG<0>
  J4G2    63  BG<0>  SCONN288_H44441004_PIP  I111
  J6U1    63  BG<0>  SCONN288_H44441003_PIP  I14
  U5D1   M61  DDR1_BG<0>  SKX_EXT_B_BGA1  I172

M_B_BG<1>       @BASEBOARD_FAB2_LIB.BASEBOARD_FAB2(SCH_1):M_B_BG<1>
  J4G2   207  BG<1>  SCONN288_H44441004_PIP  I111
  J6U1   207  BG<1>  SCONN288_H44441003_PIP  I14
  U5D1   N60  DDR1_BG<1>  SKX_EXT_B_BGA1  I172

M_B_C<2>        @BASEBOARD_FAB2_LIB.BASEBOARD_FAB2(SCH_1):M_B_C<2>
  J4G2   235   C<2>  SCONN288_H44441004_PIP  I111
  J6U1   235   C<2>  SCONN288_H44441003_PIP  I14
  U5D1   M47  DDR1_CID<2>  SKX_EXT_B_BGA1  I172

M_B_CKE<0>      @BASEBOARD_FAB2_LIB.BASEBOARD_FAB2(SCH_1):M_B_CKE<0>
  J4G2    60  CKE<0>  SCONN288_H44441004_PIP  I111
  U5D1   N62  DDR1_CKE<0>  SKX_EXT_B_BGA1  I172

M_B_CKE<1>      @BASEBOARD_FAB2_LIB.BASEBOARD_FAB2(SCH_1):M_B_CKE<1>
  J4G2   203  CKE<1>  SCONN288_H44441004_PIP  I111
  U5D1   R64  DDR1_CKE<1>  SKX_EXT_B_BGA1  I172

M_B_CKE<2>      @BASEBOARD_FAB2_LIB.BASEBOARD_FAB2(SCH_1):M_B_CKE<2>
  J6U1    60  CKE<0>  SCONN288_H44441003_PIP  I14
  U5D1   K63  DDR1_CKE<2>  SKX_EXT_B_BGA1  I172

M_B_CKE<3>      @BASEBOARD_FAB2_LIB.BASEBOARD_FAB2(SCH_1):M_B_CKE<3>
  J6U1   203  CKE<1>  SCONN288_H44441003_PIP  I14
  U5D1   L64  DDR1_CKE<3>  SKX_EXT_B_BGA1  I172

M_B_CLK_DN<0>   @BASEBOARD_FAB2_LIB.BASEBOARD_FAB2(SCH_1):M_B_CLK_DN<0>
  J4G2    75   CK0N  SCONN288_H44441004_PIP  I111
  U5D1   M53  DDR1_CLK_DN<0>  SKX_EXT_B_BGA1  I172

M_B_CLK_DN<1>   @BASEBOARD_FAB2_LIB.BASEBOARD_FAB2(SCH_1):M_B_CLK_DN<1>
  J4G2   219   CK1N  SCONN288_H44441004_PIP  I111
  U5D1   R54  DDR1_CLK_DN<1>  SKX_EXT_B_BGA1  I172

M_B_CLK_DN<2>   @BASEBOARD_FAB2_LIB.BASEBOARD_FAB2(SCH_1):M_B_CLK_DN<2>
  J6U1    75   CK0N  SCONN288_H44441003_PIP  I14
  U5D1   N56  DDR1_CLK_DN<2>  SKX_EXT_B_BGA1  I172

M_B_CLK_DN<3>   @BASEBOARD_FAB2_LIB.BASEBOARD_FAB2(SCH_1):M_B_CLK_DN<3>
  J6U1   219   CK1N  SCONN288_H44441003_PIP  I14
  U5D1   R56  DDR1_CLK_DN<3>  SKX_EXT_B_BGA1  I172

M_B_CLK_DP<0>   @BASEBOARD_FAB2_LIB.BASEBOARD_FAB2(SCH_1):M_B_CLK_DP<0>
  J4G2    74   CK0P  SCONN288_H44441004_PIP  I111
  U5D1   N54  DDR1_CLK_DP<0>  SKX_EXT_B_BGA1  I172

M_B_CLK_DP<1>   @BASEBOARD_FAB2_LIB.BASEBOARD_FAB2(SCH_1):M_B_CLK_DP<1>
  J4G2   218   CK1P  SCONN288_H44441004_PIP  I111
  U5D1   T55  DDR1_CLK_DP<1>  SKX_EXT_B_BGA1  I172

M_B_CLK_DP<2>   @BASEBOARD_FAB2_LIB.BASEBOARD_FAB2(SCH_1):M_B_CLK_DP<2>
  J6U1    74   CK0P  SCONN288_H44441003_PIP  I14
  U5D1   M57  DDR1_CLK_DP<2>  SKX_EXT_B_BGA1  I172

M_B_CLK_DP<3>   @BASEBOARD_FAB2_LIB.BASEBOARD_FAB2(SCH_1):M_B_CLK_DP<3>
  J6U1   218   CK1P  SCONN288_H44441003_PIP  I14
  U5D1   T57  DDR1_CLK_DP<3>  SKX_EXT_B_BGA1  I172

M_B_CPU_VREF    @BASEBOARD_FAB2_LIB.BASEBOARD_FAB2(SCH_1):M_B_CPU_VREF
  C4G1     1      A  CAP_A       I43
  R4G1     1      A  RES         I42
  U5D1   AK63  DDR1_CAVREF  SKX_EXT_B_BGA1  I259

M_B_CS_N<0>     @BASEBOARD_FAB2_LIB.BASEBOARD_FAB2(SCH_1):M_B_CS_N<0>
  J4G2    84   S0_N  SCONN288_H44441004_PIP  I111
  U5D1   K51  DDR1_CS_N<0>  SKX_EXT_B_BGA1  I172

M_B_CS_N<1>     @BASEBOARD_FAB2_LIB.BASEBOARD_FAB2(SCH_1):M_B_CS_N<1>
  J4G2    89   S1_N  SCONN288_H44441004_PIP  I111
  U5D1   R50  DDR1_CS_N<1>  SKX_EXT_B_BGA1  I172

M_B_CS_N<2>     @BASEBOARD_FAB2_LIB.BASEBOARD_FAB2(SCH_1):M_B_CS_N<2>
  J4G2    93  S2_N_C<0>  SCONN288_H44441004_PIP  I111
  U5D1   N46  DDR1_CS_N<2>  SKX_EXT_B_BGA1  I172

M_B_CS_N<3>     @BASEBOARD_FAB2_LIB.BASEBOARD_FAB2(SCH_1):M_B_CS_N<3>
  J4G2   237  S3_N_C<1>  SCONN288_H44441004_PIP  I111
  U5D1   V47  DDR1_CS_N<3>  SKX_EXT_B_BGA1  I172

M_B_CS_N<4>     @BASEBOARD_FAB2_LIB.BASEBOARD_FAB2(SCH_1):M_B_CS_N<4>
  J6U1    84   S0_N  SCONN288_H44441003_PIP  I14
  U5D1   J50  DDR1_CS_N<4>  SKX_EXT_B_BGA1  I172

M_B_CS_N<5>     @BASEBOARD_FAB2_LIB.BASEBOARD_FAB2(SCH_1):M_B_CS_N<5>
  J6U1    89   S1_N  SCONN288_H44441003_PIP  I14
  U5D1   T49  DDR1_CS_N<5>  SKX_EXT_B_BGA1  I172

M_B_CS_N<6>     @BASEBOARD_FAB2_LIB.BASEBOARD_FAB2(SCH_1):M_B_CS_N<6>
  J6U1    93  S2_N_C<0>  SCONN288_H44441003_PIP  I14
  U5D1   M45  DDR1_CS_N<6>  SKX_EXT_B_BGA1  I172

M_B_CS_N<7>     @BASEBOARD_FAB2_LIB.BASEBOARD_FAB2(SCH_1):M_B_CS_N<7>
  J6U1   237  S3_N_C<1>  SCONN288_H44441003_PIP  I14
  U5D1   R46  DDR1_CS_N<7>  SKX_EXT_B_BGA1  I172

M_B_DQ<0>       @BASEBOARD_FAB2_LIB.BASEBOARD_FAB2(SCH_1):M_B_DQ<0>
  J4G2   150  DQ<1>  SCONN288_H44441004_PIP  I111
  J6U1     5  DQ<0>  SCONN288_H44441003_PIP  I14
  U5D1   AV81  DDR1_DQ<0>  SKX_EXT_B_BGA1  I172

M_B_DQ<1>       @BASEBOARD_FAB2_LIB.BASEBOARD_FAB2(SCH_1):M_B_DQ<1>
  J4G2     5  DQ<0>  SCONN288_H44441004_PIP  I111
  J6U1   150  DQ<1>  SCONN288_H44441003_PIP  I14
  U5D1   AT79  DDR1_DQ<1>  SKX_EXT_B_BGA1  I172

M_B_DQ<2>       @BASEBOARD_FAB2_LIB.BASEBOARD_FAB2(SCH_1):M_B_DQ<2>
  J4G2   157  DQ<3>  SCONN288_H44441004_PIP  I111
  J6U1    12  DQ<2>  SCONN288_H44441003_PIP  I14
  U5D1   AN82  DDR1_DQ<2>  SKX_EXT_B_BGA1  I172

M_B_DQ<3>       @BASEBOARD_FAB2_LIB.BASEBOARD_FAB2(SCH_1):M_B_DQ<3>
  J4G2    12  DQ<2>  SCONN288_H44441004_PIP  I111
  J6U1   157  DQ<3>  SCONN288_H44441003_PIP  I14
  U5D1   AM81  DDR1_DQ<3>  SKX_EXT_B_BGA1  I172

M_B_DQ<4>       @BASEBOARD_FAB2_LIB.BASEBOARD_FAB2(SCH_1):M_B_DQ<4>
  J4G2   148  DQ<5>  SCONN288_H44441004_PIP  I111
  J6U1     3  DQ<4>  SCONN288_H44441003_PIP  I14
  U5D1   AW80  DDR1_DQ<4>  SKX_EXT_B_BGA1  I172

M_B_DQ<5>       @BASEBOARD_FAB2_LIB.BASEBOARD_FAB2(SCH_1):M_B_DQ<5>
  J4G2     3  DQ<4>  SCONN288_H44441004_PIP  I111
  J6U1   148  DQ<5>  SCONN288_H44441003_PIP  I14
  U5D1   AV79  DDR1_DQ<5>  SKX_EXT_B_BGA1  I172

M_B_DQ<6>       @BASEBOARD_FAB2_LIB.BASEBOARD_FAB2(SCH_1):M_B_DQ<6>
  J4G2   155  DQ<7>  SCONN288_H44441004_PIP  I111
  J6U1    10  DQ<6>  SCONN288_H44441003_PIP  I14
  U5D1   AR82  DDR1_DQ<6>  SKX_EXT_B_BGA1  I172

M_B_DQ<7>       @BASEBOARD_FAB2_LIB.BASEBOARD_FAB2(SCH_1):M_B_DQ<7>
  J4G2    10  DQ<6>  SCONN288_H44441004_PIP  I111
  J6U1   155  DQ<7>  SCONN288_H44441003_PIP  I14
  U5D1   AN80  DDR1_DQ<7>  SKX_EXT_B_BGA1  I172

M_B_DQ<8>       @BASEBOARD_FAB2_LIB.BASEBOARD_FAB2(SCH_1):M_B_DQ<8>
  J4G2   161  DQ<9>  SCONN288_H44441004_PIP  I111
  J6U1    16  DQ<8>  SCONN288_H44441003_PIP  I14
  U5D1   AH81  DDR1_DQ<8>  SKX_EXT_B_BGA1  I172

M_B_DQ<9>       @BASEBOARD_FAB2_LIB.BASEBOARD_FAB2(SCH_1):M_B_DQ<9>
  J4G2    16  DQ<8>  SCONN288_H44441004_PIP  I111
  J6U1   161  DQ<9>  SCONN288_H44441003_PIP  I14
  U5D1   AF79  DDR1_DQ<9>  SKX_EXT_B_BGA1  I172

M_B_DQ<10>      @BASEBOARD_FAB2_LIB.BASEBOARD_FAB2(SCH_1):M_B_DQ<10>
  J4G2   168  DQ<11>  SCONN288_H44441004_PIP  I111
  J6U1    23  DQ<10>  SCONN288_H44441003_PIP  I14
  U5D1   AC82  DDR1_DQ<10>  SKX_EXT_B_BGA1  I172

M_B_DQ<11>      @BASEBOARD_FAB2_LIB.BASEBOARD_FAB2(SCH_1):M_B_DQ<11>
  J4G2    23  DQ<10>  SCONN288_H44441004_PIP  I111
  J6U1   168  DQ<11>  SCONN288_H44441003_PIP  I14
  U5D1   AB81  DDR1_DQ<11>  SKX_EXT_B_BGA1  I172

M_B_DQ<12>      @BASEBOARD_FAB2_LIB.BASEBOARD_FAB2(SCH_1):M_B_DQ<12>
  J4G2   159  DQ<13>  SCONN288_H44441004_PIP  I111
  J6U1    14  DQ<12>  SCONN288_H44441003_PIP  I14
  U5D1   AJ80  DDR1_DQ<12>  SKX_EXT_B_BGA1  I172

M_B_DQ<13>      @BASEBOARD_FAB2_LIB.BASEBOARD_FAB2(SCH_1):M_B_DQ<13>
  J4G2    14  DQ<12>  SCONN288_H44441004_PIP  I111
  J6U1   159  DQ<13>  SCONN288_H44441003_PIP  I14
  U5D1   AH79  DDR1_DQ<13>  SKX_EXT_B_BGA1  I172

M_B_DQ<14>      @BASEBOARD_FAB2_LIB.BASEBOARD_FAB2(SCH_1):M_B_DQ<14>
  J4G2   166  DQ<15>  SCONN288_H44441004_PIP  I111
  J6U1    21  DQ<14>  SCONN288_H44441003_PIP  I14
  U5D1   AE82  DDR1_DQ<14>  SKX_EXT_B_BGA1  I172

M_B_DQ<15>      @BASEBOARD_FAB2_LIB.BASEBOARD_FAB2(SCH_1):M_B_DQ<15>
  J4G2    21  DQ<14>  SCONN288_H44441004_PIP  I111
  J6U1   166  DQ<15>  SCONN288_H44441003_PIP  I14
  U5D1   AC80  DDR1_DQ<15>  SKX_EXT_B_BGA1  I172

M_B_DQ<16>      @BASEBOARD_FAB2_LIB.BASEBOARD_FAB2(SCH_1):M_B_DQ<16>
  J4G2   172  DQ<17>  SCONN288_H44441004_PIP  I111
  J6U1    27  DQ<16>  SCONN288_H44441003_PIP  I14
  U5D1   E80  DDR1_DQ<16>  SKX_EXT_B_BGA1  I172

M_B_DQ<17>      @BASEBOARD_FAB2_LIB.BASEBOARD_FAB2(SCH_1):M_B_DQ<17>
  J4G2    27  DQ<16>  SCONN288_H44441004_PIP  I111
  J6U1   172  DQ<17>  SCONN288_H44441003_PIP  I14
  U5D1   J80  DDR1_DQ<17>  SKX_EXT_B_BGA1  I172

M_B_DQ<18>      @BASEBOARD_FAB2_LIB.BASEBOARD_FAB2(SCH_1):M_B_DQ<18>
  J4G2   179  DQ<19>  SCONN288_H44441004_PIP  I111
  J6U1    34  DQ<18>  SCONN288_H44441003_PIP  I14
  U5D1   F77  DDR1_DQ<18>  SKX_EXT_B_BGA1  I172

M_B_DQ<19>      @BASEBOARD_FAB2_LIB.BASEBOARD_FAB2(SCH_1):M_B_DQ<19>
  J4G2    34  DQ<18>  SCONN288_H44441004_PIP  I111
  J6U1   179  DQ<19>  SCONN288_H44441003_PIP  I14
  U5D1   H77  DDR1_DQ<19>  SKX_EXT_B_BGA1  I172

M_B_DQ<20>      @BASEBOARD_FAB2_LIB.BASEBOARD_FAB2(SCH_1):M_B_DQ<20>
  J4G2   170  DQ<21>  SCONN288_H44441004_PIP  I111
  J6U1    25  DQ<20>  SCONN288_H44441003_PIP  I14
  U5D1   F81  DDR1_DQ<20>  SKX_EXT_B_BGA1  I172

M_B_DQ<21>      @BASEBOARD_FAB2_LIB.BASEBOARD_FAB2(SCH_1):M_B_DQ<21>
  J4G2    25  DQ<20>  SCONN288_H44441004_PIP  I111
  J6U1   170  DQ<21>  SCONN288_H44441003_PIP  I14
  U5D1   H81  DDR1_DQ<21>  SKX_EXT_B_BGA1  I172

M_B_DQ<22>      @BASEBOARD_FAB2_LIB.BASEBOARD_FAB2(SCH_1):M_B_DQ<22>
  J4G2   177  DQ<23>  SCONN288_H44441004_PIP  I111
  J6U1    32  DQ<22>  SCONN288_H44441003_PIP  I14
  U5D1   E78  DDR1_DQ<22>  SKX_EXT_B_BGA1  I172

M_B_DQ<23>      @BASEBOARD_FAB2_LIB.BASEBOARD_FAB2(SCH_1):M_B_DQ<23>
  J4G2    32  DQ<22>  SCONN288_H44441004_PIP  I111
  J6U1   177  DQ<23>  SCONN288_H44441003_PIP  I14
  U5D1   J78  DDR1_DQ<23>  SKX_EXT_B_BGA1  I172

M_B_DQ<24>      @BASEBOARD_FAB2_LIB.BASEBOARD_FAB2(SCH_1):M_B_DQ<24>
  J4G2   183  DQ<25>  SCONN288_H44441004_PIP  I111
  J6U1    38  DQ<24>  SCONN288_H44441003_PIP  I14
  U5D1   D75  DDR1_DQ<24>  SKX_EXT_B_BGA1  I172

M_B_DQ<25>      @BASEBOARD_FAB2_LIB.BASEBOARD_FAB2(SCH_1):M_B_DQ<25>
  J4G2    38  DQ<24>  SCONN288_H44441004_PIP  I111
  J6U1   183  DQ<25>  SCONN288_H44441003_PIP  I14
  U5D1   C74  DDR1_DQ<25>  SKX_EXT_B_BGA1  I172

M_B_DQ<26>      @BASEBOARD_FAB2_LIB.BASEBOARD_FAB2(SCH_1):M_B_DQ<26>
  J4G2   190  DQ<27>  SCONN288_H44441004_PIP  I111
  J6U1    45  DQ<26>  SCONN288_H44441003_PIP  I14
  U5D1   D71  DDR1_DQ<26>  SKX_EXT_B_BGA1  I172

M_B_DQ<27>      @BASEBOARD_FAB2_LIB.BASEBOARD_FAB2(SCH_1):M_B_DQ<27>
  J4G2    45  DQ<26>  SCONN288_H44441004_PIP  I111
  J6U1   190  DQ<27>  SCONN288_H44441003_PIP  I14
  U5D1   F71  DDR1_DQ<27>  SKX_EXT_B_BGA1  I172

M_B_DQ<28>      @BASEBOARD_FAB2_LIB.BASEBOARD_FAB2(SCH_1):M_B_DQ<28>
  J4G2   181  DQ<29>  SCONN288_H44441004_PIP  I111
  J6U1    36  DQ<28>  SCONN288_H44441003_PIP  I14
  U5D1   F75  DDR1_DQ<28>  SKX_EXT_B_BGA1  I172

M_B_DQ<29>      @BASEBOARD_FAB2_LIB.BASEBOARD_FAB2(SCH_1):M_B_DQ<29>
  J4G2    36  DQ<28>  SCONN288_H44441004_PIP  I111
  J6U1   181  DQ<29>  SCONN288_H44441003_PIP  I14
  U5D1   G74  DDR1_DQ<29>  SKX_EXT_B_BGA1  I172

M_B_DQ<30>      @BASEBOARD_FAB2_LIB.BASEBOARD_FAB2(SCH_1):M_B_DQ<30>
  J4G2   188  DQ<31>  SCONN288_H44441004_PIP  I111
  J6U1    43  DQ<30>  SCONN288_H44441003_PIP  I14
  U5D1   C72  DDR1_DQ<30>  SKX_EXT_B_BGA1  I172

M_B_DQ<31>      @BASEBOARD_FAB2_LIB.BASEBOARD_FAB2(SCH_1):M_B_DQ<31>
  J4G2    43  DQ<30>  SCONN288_H44441004_PIP  I111
  J6U1   188  DQ<31>  SCONN288_H44441003_PIP  I14
  U5D1   G72  DDR1_DQ<31>  SKX_EXT_B_BGA1  I172

M_B_DQ<32>      @BASEBOARD_FAB2_LIB.BASEBOARD_FAB2(SCH_1):M_B_DQ<32>
  J4G2   242  DQ<33>  SCONN288_H44441004_PIP  I111
  J6U1    97  DQ<32>  SCONN288_H44441003_PIP  I14
  U5D1   K43  DDR1_DQ<32>  SKX_EXT_B_BGA1  I172

M_B_DQ<33>      @BASEBOARD_FAB2_LIB.BASEBOARD_FAB2(SCH_1):M_B_DQ<33>
  J4G2    97  DQ<32>  SCONN288_H44441004_PIP  I111
  J6U1   242  DQ<33>  SCONN288_H44441003_PIP  I14
  U5D1   H43  DDR1_DQ<33>  SKX_EXT_B_BGA1  I172

M_B_DQ<34>      @BASEBOARD_FAB2_LIB.BASEBOARD_FAB2(SCH_1):M_B_DQ<34>
  J4G2   249  DQ<35>  SCONN288_H44441004_PIP  I111
  J6U1   104  DQ<34>  SCONN288_H44441003_PIP  I14
  U5D1   L40  DDR1_DQ<34>  SKX_EXT_B_BGA1  I172

M_B_DQ<35>      @BASEBOARD_FAB2_LIB.BASEBOARD_FAB2(SCH_1):M_B_DQ<35>
  J4G2   104  DQ<34>  SCONN288_H44441004_PIP  I111
  J6U1   249  DQ<35>  SCONN288_H44441003_PIP  I14
  U5D1   N40  DDR1_DQ<35>  SKX_EXT_B_BGA1  I172

M_B_DQ<36>      @BASEBOARD_FAB2_LIB.BASEBOARD_FAB2(SCH_1):M_B_DQ<36>
  J4G2   240  DQ<37>  SCONN288_H44441004_PIP  I111
  J6U1    95  DQ<36>  SCONN288_H44441003_PIP  I14
  U5D1   P43  DDR1_DQ<36>  SKX_EXT_B_BGA1  I172

M_B_DQ<37>      @BASEBOARD_FAB2_LIB.BASEBOARD_FAB2(SCH_1):M_B_DQ<37>
  J4G2    95  DQ<36>  SCONN288_H44441004_PIP  I111
  J6U1   240  DQ<37>  SCONN288_H44441003_PIP  I14
  U5D1   T43  DDR1_DQ<37>  SKX_EXT_B_BGA1  I172

M_B_DQ<38>      @BASEBOARD_FAB2_LIB.BASEBOARD_FAB2(SCH_1):M_B_DQ<38>
  J4G2   247  DQ<39>  SCONN288_H44441004_PIP  I111
  J6U1   102  DQ<38>  SCONN288_H44441003_PIP  I14
  U5D1   K41  DDR1_DQ<38>  SKX_EXT_B_BGA1  I172

M_B_DQ<39>      @BASEBOARD_FAB2_LIB.BASEBOARD_FAB2(SCH_1):M_B_DQ<39>
  J4G2   102  DQ<38>  SCONN288_H44441004_PIP  I111
  J6U1   247  DQ<39>  SCONN288_H44441003_PIP  I14
  U5D1   P41  DDR1_DQ<39>  SKX_EXT_B_BGA1  I172

M_B_DQ<40>      @BASEBOARD_FAB2_LIB.BASEBOARD_FAB2(SCH_1):M_B_DQ<40>
  J4G2   253  DQ<41>  SCONN288_H44441004_PIP  I111
  J6U1   108  DQ<40>  SCONN288_H44441003_PIP  I14
  U5D1   C36  DDR1_DQ<40>  SKX_EXT_B_BGA1  I172

M_B_DQ<41>      @BASEBOARD_FAB2_LIB.BASEBOARD_FAB2(SCH_1):M_B_DQ<41>
  J4G2   108  DQ<40>  SCONN288_H44441004_PIP  I111
  J6U1   253  DQ<41>  SCONN288_H44441003_PIP  I14
  U5D1   B35  DDR1_DQ<41>  SKX_EXT_B_BGA1  I172

M_B_DQ<42>      @BASEBOARD_FAB2_LIB.BASEBOARD_FAB2(SCH_1):M_B_DQ<42>
  J4G2   260  DQ<43>  SCONN288_H44441004_PIP  I111
  J6U1   115  DQ<42>  SCONN288_H44441003_PIP  I14
  U5D1   C32  DDR1_DQ<42>  SKX_EXT_B_BGA1  I172

M_B_DQ<43>      @BASEBOARD_FAB2_LIB.BASEBOARD_FAB2(SCH_1):M_B_DQ<43>
  J4G2   115  DQ<42>  SCONN288_H44441004_PIP  I111
  J6U1   260  DQ<43>  SCONN288_H44441003_PIP  I14
  U5D1   E32  DDR1_DQ<43>  SKX_EXT_B_BGA1  I172

M_B_DQ<44>      @BASEBOARD_FAB2_LIB.BASEBOARD_FAB2(SCH_1):M_B_DQ<44>
  J4G2   251  DQ<45>  SCONN288_H44441004_PIP  I111
  J6U1   106  DQ<44>  SCONN288_H44441003_PIP  I14
  U5D1   E36  DDR1_DQ<44>  SKX_EXT_B_BGA1  I172

M_B_DQ<45>      @BASEBOARD_FAB2_LIB.BASEBOARD_FAB2(SCH_1):M_B_DQ<45>
  J4G2   106  DQ<44>  SCONN288_H44441004_PIP  I111
  J6U1   251  DQ<45>  SCONN288_H44441003_PIP  I14
  U5D1   F35  DDR1_DQ<45>  SKX_EXT_B_BGA1  I172

M_B_DQ<46>      @BASEBOARD_FAB2_LIB.BASEBOARD_FAB2(SCH_1):M_B_DQ<46>
  J4G2   258  DQ<47>  SCONN288_H44441004_PIP  I111
  J6U1   113  DQ<46>  SCONN288_H44441003_PIP  I14
  U5D1   B33  DDR1_DQ<46>  SKX_EXT_B_BGA1  I172

M_B_DQ<47>      @BASEBOARD_FAB2_LIB.BASEBOARD_FAB2(SCH_1):M_B_DQ<47>
  J4G2   113  DQ<46>  SCONN288_H44441004_PIP  I111
  J6U1   258  DQ<47>  SCONN288_H44441003_PIP  I14
  U5D1   F33  DDR1_DQ<47>  SKX_EXT_B_BGA1  I172

M_B_DQ<48>      @BASEBOARD_FAB2_LIB.BASEBOARD_FAB2(SCH_1):M_B_DQ<48>
  J4G2   264  DQ<49>  SCONN288_H44441004_PIP  I111
  J6U1   119  DQ<48>  SCONN288_H44441003_PIP  I14
  U5D1   C30  DDR1_DQ<48>  SKX_EXT_B_BGA1  I172

M_B_DQ<49>      @BASEBOARD_FAB2_LIB.BASEBOARD_FAB2(SCH_1):M_B_DQ<49>
  J4G2   119  DQ<48>  SCONN288_H44441004_PIP  I111
  J6U1   264  DQ<49>  SCONN288_H44441003_PIP  I14
  U5D1   B29  DDR1_DQ<49>  SKX_EXT_B_BGA1  I172

M_B_DQ<50>      @BASEBOARD_FAB2_LIB.BASEBOARD_FAB2(SCH_1):M_B_DQ<50>
  J4G2   271  DQ<51>  SCONN288_H44441004_PIP  I111
  J6U1   126  DQ<50>  SCONN288_H44441003_PIP  I14
  U5D1   C26  DDR1_DQ<50>  SKX_EXT_B_BGA1  I172

M_B_DQ<51>      @BASEBOARD_FAB2_LIB.BASEBOARD_FAB2(SCH_1):M_B_DQ<51>
  J4G2   126  DQ<50>  SCONN288_H44441004_PIP  I111
  J6U1   271  DQ<51>  SCONN288_H44441003_PIP  I14
  U5D1   E26  DDR1_DQ<51>  SKX_EXT_B_BGA1  I172

M_B_DQ<52>      @BASEBOARD_FAB2_LIB.BASEBOARD_FAB2(SCH_1):M_B_DQ<52>
  J4G2   262  DQ<53>  SCONN288_H44441004_PIP  I111
  J6U1   117  DQ<52>  SCONN288_H44441003_PIP  I14
  U5D1   E30  DDR1_DQ<52>  SKX_EXT_B_BGA1  I172

M_B_DQ<53>      @BASEBOARD_FAB2_LIB.BASEBOARD_FAB2(SCH_1):M_B_DQ<53>
  J4G2   117  DQ<52>  SCONN288_H44441004_PIP  I111
  J6U1   262  DQ<53>  SCONN288_H44441003_PIP  I14
  U5D1   F29  DDR1_DQ<53>  SKX_EXT_B_BGA1  I172

M_B_DQ<54>      @BASEBOARD_FAB2_LIB.BASEBOARD_FAB2(SCH_1):M_B_DQ<54>
  J4G2   269  DQ<55>  SCONN288_H44441004_PIP  I111
  J6U1   124  DQ<54>  SCONN288_H44441003_PIP  I14
  U5D1   B27  DDR1_DQ<54>  SKX_EXT_B_BGA1  I172

M_B_DQ<55>      @BASEBOARD_FAB2_LIB.BASEBOARD_FAB2(SCH_1):M_B_DQ<55>
  J4G2   124  DQ<54>  SCONN288_H44441004_PIP  I111
  J6U1   269  DQ<55>  SCONN288_H44441003_PIP  I14
  U5D1   F27  DDR1_DQ<55>  SKX_EXT_B_BGA1  I172

M_B_DQ<56>      @BASEBOARD_FAB2_LIB.BASEBOARD_FAB2(SCH_1):M_B_DQ<56>
  J4G2   275  DQ<57>  SCONN288_H44441004_PIP  I111
  J6U1   130  DQ<56>  SCONN288_H44441003_PIP  I14
  U5D1   U28  DDR1_DQ<56>  SKX_EXT_B_BGA1  I172

M_B_DQ<57>      @BASEBOARD_FAB2_LIB.BASEBOARD_FAB2(SCH_1):M_B_DQ<57>
  J4G2   130  DQ<56>  SCONN288_H44441004_PIP  I111
  J6U1   275  DQ<57>  SCONN288_H44441003_PIP  I14
  U5D1   AA28  DDR1_DQ<57>  SKX_EXT_B_BGA1  I172

M_B_DQ<58>      @BASEBOARD_FAB2_LIB.BASEBOARD_FAB2(SCH_1):M_B_DQ<58>
  J4G2   282  DQ<59>  SCONN288_H44441004_PIP  I111
  J6U1   137  DQ<58>  SCONN288_H44441003_PIP  I14
  U5D1   V25  DDR1_DQ<58>  SKX_EXT_B_BGA1  I172

M_B_DQ<59>      @BASEBOARD_FAB2_LIB.BASEBOARD_FAB2(SCH_1):M_B_DQ<59>
  J4G2   137  DQ<58>  SCONN288_H44441004_PIP  I111
  J6U1   282  DQ<59>  SCONN288_H44441003_PIP  I14
  U5D1   Y25  DDR1_DQ<59>  SKX_EXT_B_BGA1  I172

M_B_DQ<60>      @BASEBOARD_FAB2_LIB.BASEBOARD_FAB2(SCH_1):M_B_DQ<60>
  J4G2   273  DQ<61>  SCONN288_H44441004_PIP  I111
  J6U1   128  DQ<60>  SCONN288_H44441003_PIP  I14
  U5D1   V29  DDR1_DQ<60>  SKX_EXT_B_BGA1  I172

M_B_DQ<61>      @BASEBOARD_FAB2_LIB.BASEBOARD_FAB2(SCH_1):M_B_DQ<61>
  J4G2   128  DQ<60>  SCONN288_H44441004_PIP  I111
  J6U1   273  DQ<61>  SCONN288_H44441003_PIP  I14
  U5D1   Y29  DDR1_DQ<61>  SKX_EXT_B_BGA1  I172

M_B_DQ<62>      @BASEBOARD_FAB2_LIB.BASEBOARD_FAB2(SCH_1):M_B_DQ<62>
  J4G2   280  DQ<63>  SCONN288_H44441004_PIP  I111
  J6U1   135  DQ<62>  SCONN288_H44441003_PIP  I14
  U5D1   U26  DDR1_DQ<62>  SKX_EXT_B_BGA1  I172

M_B_DQ<63>      @BASEBOARD_FAB2_LIB.BASEBOARD_FAB2(SCH_1):M_B_DQ<63>
  J4G2   135  DQ<62>  SCONN288_H44441004_PIP  I111
  J6U1   280  DQ<63>  SCONN288_H44441003_PIP  I14
  U5D1   AA26  DDR1_DQ<63>  SKX_EXT_B_BGA1  I172

M_B_DQS_DN<0>   @BASEBOARD_FAB2_LIB.BASEBOARD_FAB2(SCH_1):M_B_DQS_DN<0>
  J4G2   152  DQS0N  SCONN288_H44441004_PIP  I61
  J6U1   152  DQS0N  SCONN288_H44441003_PIP  I112
  U5D1   AP79  DDR1_DQS_DN<0>  SKX_EXT_B_BGA1  I172

M_B_DQS_DN<1>   @BASEBOARD_FAB2_LIB.BASEBOARD_FAB2(SCH_1):M_B_DQS_DN<1>
  J4G2   163  DQS1N  SCONN288_H44441004_PIP  I61
  J6U1   163  DQS1N  SCONN288_H44441003_PIP  I112
  U5D1   AD79  DDR1_DQS_DN<1>  SKX_EXT_B_BGA1  I172

M_B_DQS_DN<2>   @BASEBOARD_FAB2_LIB.BASEBOARD_FAB2(SCH_1):M_B_DQS_DN<2>
  J4G2   174  DQS2N  SCONN288_H44441004_PIP  I61
  J6U1   174  DQS2N  SCONN288_H44441003_PIP  I112
  U5D1   K79  DDR1_DQS_DN<2>  SKX_EXT_B_BGA1  I172

M_B_DQS_DN<3>   @BASEBOARD_FAB2_LIB.BASEBOARD_FAB2(SCH_1):M_B_DQS_DN<3>
  J4G2   185  DQS3N  SCONN288_H44441004_PIP  I61
  J6U1   185  DQS3N  SCONN288_H44441003_PIP  I112
  U5D1   H73  DDR1_DQS_DN<3>  SKX_EXT_B_BGA1  I172

M_B_DQS_DN<4>   @BASEBOARD_FAB2_LIB.BASEBOARD_FAB2(SCH_1):M_B_DQS_DN<4>
  J4G2   244  DQS4N  SCONN288_H44441004_PIP  I61
  J6U1   244  DQS4N  SCONN288_H44441003_PIP  I112
  U5D1   N42  DDR1_DQS_DN<4>  SKX_EXT_B_BGA1  I172

M_B_DQS_DN<5>   @BASEBOARD_FAB2_LIB.BASEBOARD_FAB2(SCH_1):M_B_DQS_DN<5>
  J4G2   255  DQS5N  SCONN288_H44441004_PIP  I61
  J6U1   255  DQS5N  SCONN288_H44441003_PIP  I112
  U5D1   G34  DDR1_DQS_DN<5>  SKX_EXT_B_BGA1  I172

M_B_DQS_DN<6>   @BASEBOARD_FAB2_LIB.BASEBOARD_FAB2(SCH_1):M_B_DQS_DN<6>
  J4G2   266  DQS6N  SCONN288_H44441004_PIP  I61
  J6U1   266  DQS6N  SCONN288_H44441003_PIP  I112
  U5D1   G28  DDR1_DQS_DN<6>  SKX_EXT_B_BGA1  I172

M_B_DQS_DN<7>   @BASEBOARD_FAB2_LIB.BASEBOARD_FAB2(SCH_1):M_B_DQS_DN<7>
  J4G2   277  DQS7N  SCONN288_H44441004_PIP  I61
  J6U1   277  DQS7N  SCONN288_H44441003_PIP  I112
  U5D1   AB27  DDR1_DQS_DN<7>  SKX_EXT_B_BGA1  I172

M_B_DQS_DN<8>   @BASEBOARD_FAB2_LIB.BASEBOARD_FAB2(SCH_1):M_B_DQS_DN<8>
  J4G2   196  DQS8N  SCONN288_H44441004_PIP  I61
  J6U1   196  DQS8N  SCONN288_H44441003_PIP  I112
  U5D1   N68  DDR1_DQS_DN<8>  SKX_EXT_B_BGA1  I172

M_B_DQS_DN<9>   @BASEBOARD_FAB2_LIB.BASEBOARD_FAB2(SCH_1):M_B_DQS_DN<9>
  J4G2     8  DQS9N  SCONN288_H44441004_PIP  I61
  J6U1     8  DQS9N  SCONN288_H44441003_PIP  I112
  U5D1   AU82  DDR1_DQS_DN<9>  SKX_EXT_B_BGA1  I172

M_B_DQS_DN<10>   @BASEBOARD_FAB2_LIB.BASEBOARD_FAB2(SCH_1):M_B_DQS_DN<10>
  J4G2    19  DQS10N  SCONN288_H44441004_PIP  I61
  J6U1    19  DQS10N  SCONN288_H44441003_PIP  I112
  U5D1   AG82  DDR1_DQS_DN<10>  SKX_EXT_B_BGA1  I172

M_B_DQS_DN<11>   @BASEBOARD_FAB2_LIB.BASEBOARD_FAB2(SCH_1):M_B_DQS_DN<11>
  J4G2    30  DQS11N  SCONN288_H44441004_PIP  I61
  J6U1    30  DQS11N  SCONN288_H44441003_PIP  I112
  U5D1   D79  DDR1_DQS_DN<11>  SKX_EXT_B_BGA1  I172

M_B_DQS_DN<12>   @BASEBOARD_FAB2_LIB.BASEBOARD_FAB2(SCH_1):M_B_DQS_DN<12>
  J4G2    41  DQS12N  SCONN288_H44441004_PIP  I61
  J6U1    41  DQS12N  SCONN288_H44441003_PIP  I112
  U5D1   B73  DDR1_DQS_DN<12>  SKX_EXT_B_BGA1  I172

M_B_DQS_DN<13>   @BASEBOARD_FAB2_LIB.BASEBOARD_FAB2(SCH_1):M_B_DQS_DN<13>
  J4G2   100  DQS13N  SCONN288_H44441004_PIP  I61
  J6U1   100  DQS13N  SCONN288_H44441003_PIP  I112
  U5D1   J42  DDR1_DQS_DN<13>  SKX_EXT_B_BGA1  I172

M_B_DQS_DN<14>   @BASEBOARD_FAB2_LIB.BASEBOARD_FAB2(SCH_1):M_B_DQS_DN<14>
  J4G2   111  DQS14N  SCONN288_H44441004_PIP  I61
  J6U1   111  DQS14N  SCONN288_H44441003_PIP  I112
  U5D1   A34  DDR1_DQS_DN<14>  SKX_EXT_B_BGA1  I172

M_B_DQS_DN<15>   @BASEBOARD_FAB2_LIB.BASEBOARD_FAB2(SCH_1):M_B_DQS_DN<15>
  J4G2   122  DQS15N  SCONN288_H44441004_PIP  I61
  J6U1   122  DQS15N  SCONN288_H44441003_PIP  I112
  U5D1   A28  DDR1_DQS_DN<15>  SKX_EXT_B_BGA1  I172

M_B_DQS_DN<16>   @BASEBOARD_FAB2_LIB.BASEBOARD_FAB2(SCH_1):M_B_DQS_DN<16>
  J4G2   133  DQS16N  SCONN288_H44441004_PIP  I61
  J6U1   133  DQS16N  SCONN288_H44441003_PIP  I112
  U5D1   T27  DDR1_DQS_DN<16>  SKX_EXT_B_BGA1  I172

M_B_DQS_DN<17>   @BASEBOARD_FAB2_LIB.BASEBOARD_FAB2(SCH_1):M_B_DQS_DN<17>
  J4G2    52  DQS17N  SCONN288_H44441004_PIP  I61
  J6U1    52  DQS17N  SCONN288_H44441003_PIP  I112
  U5D1   G68  DDR1_DQS_DN<17>  SKX_EXT_B_BGA1  I172

M_B_DQS_DP<0>   @BASEBOARD_FAB2_LIB.BASEBOARD_FAB2(SCH_1):M_B_DQS_DP<0>
  J4G2   153  DQS0P  SCONN288_H44441004_PIP  I61
  J6U1   153  DQS0P  SCONN288_H44441003_PIP  I112
  U5D1   AR80  DDR1_DQS_DP<0>  SKX_EXT_B_BGA1  I172

M_B_DQS_DP<1>   @BASEBOARD_FAB2_LIB.BASEBOARD_FAB2(SCH_1):M_B_DQS_DP<1>
  J4G2   164  DQS1P  SCONN288_H44441004_PIP  I61
  J6U1   164  DQS1P  SCONN288_H44441003_PIP  I112
  U5D1   AE80  DDR1_DQS_DP<1>  SKX_EXT_B_BGA1  I172

M_B_DQS_DP<2>   @BASEBOARD_FAB2_LIB.BASEBOARD_FAB2(SCH_1):M_B_DQS_DP<2>
  J4G2   175  DQS2P  SCONN288_H44441004_PIP  I61
  J6U1   175  DQS2P  SCONN288_H44441003_PIP  I112
  U5D1   H79  DDR1_DQS_DP<2>  SKX_EXT_B_BGA1  I172

M_B_DQS_DP<3>   @BASEBOARD_FAB2_LIB.BASEBOARD_FAB2(SCH_1):M_B_DQS_DP<3>
  J4G2   186  DQS3P  SCONN288_H44441004_PIP  I61
  J6U1   186  DQS3P  SCONN288_H44441003_PIP  I112
  U5D1   F73  DDR1_DQS_DP<3>  SKX_EXT_B_BGA1  I172

M_B_DQS_DP<4>   @BASEBOARD_FAB2_LIB.BASEBOARD_FAB2(SCH_1):M_B_DQS_DP<4>
  J4G2   245  DQS4P  SCONN288_H44441004_PIP  I61
  J6U1   245  DQS4P  SCONN288_H44441003_PIP  I112
  U5D1   R42  DDR1_DQS_DP<4>  SKX_EXT_B_BGA1  I172

M_B_DQS_DP<5>   @BASEBOARD_FAB2_LIB.BASEBOARD_FAB2(SCH_1):M_B_DQS_DP<5>
  J4G2   256  DQS5P  SCONN288_H44441004_PIP  I61
  J6U1   256  DQS5P  SCONN288_H44441003_PIP  I112
  U5D1   E34  DDR1_DQS_DP<5>  SKX_EXT_B_BGA1  I172

M_B_DQS_DP<6>   @BASEBOARD_FAB2_LIB.BASEBOARD_FAB2(SCH_1):M_B_DQS_DP<6>
  J4G2   267  DQS6P  SCONN288_H44441004_PIP  I61
  J6U1   267  DQS6P  SCONN288_H44441003_PIP  I112
  U5D1   E28  DDR1_DQS_DP<6>  SKX_EXT_B_BGA1  I172

M_B_DQS_DP<7>   @BASEBOARD_FAB2_LIB.BASEBOARD_FAB2(SCH_1):M_B_DQS_DP<7>
  J4G2   278  DQS7P  SCONN288_H44441004_PIP  I61
  J6U1   278  DQS7P  SCONN288_H44441003_PIP  I112
  U5D1   Y27  DDR1_DQS_DP<7>  SKX_EXT_B_BGA1  I172

M_B_DQS_DP<8>   @BASEBOARD_FAB2_LIB.BASEBOARD_FAB2(SCH_1):M_B_DQS_DP<8>
  J4G2   197  DQS8P  SCONN288_H44441004_PIP  I61
  J6U1   197  DQS8P  SCONN288_H44441003_PIP  I112
  U5D1   L68  DDR1_DQS_DP<8>  SKX_EXT_B_BGA1  I172

M_B_DQS_DP<9>   @BASEBOARD_FAB2_LIB.BASEBOARD_FAB2(SCH_1):M_B_DQS_DP<9>
  J4G2     7  DQS9P  SCONN288_H44441004_PIP  I61
  J6U1     7  DQS9P  SCONN288_H44441003_PIP  I112
  U5D1   AT81  DDR1_DQS_DP<9>  SKX_EXT_B_BGA1  I172

M_B_DQS_DP<10>   @BASEBOARD_FAB2_LIB.BASEBOARD_FAB2(SCH_1):M_B_DQS_DP<10>
  J4G2    18  DQS10P  SCONN288_H44441004_PIP  I61
  J6U1    18  DQS10P  SCONN288_H44441003_PIP  I112
  U5D1   AF81  DDR1_DQS_DP<10>  SKX_EXT_B_BGA1  I172

M_B_DQS_DP<11>   @BASEBOARD_FAB2_LIB.BASEBOARD_FAB2(SCH_1):M_B_DQS_DP<11>
  J4G2    29  DQS11P  SCONN288_H44441004_PIP  I61
  J6U1    29  DQS11P  SCONN288_H44441003_PIP  I112
  U5D1   F79  DDR1_DQS_DP<11>  SKX_EXT_B_BGA1  I172

M_B_DQS_DP<12>   @BASEBOARD_FAB2_LIB.BASEBOARD_FAB2(SCH_1):M_B_DQS_DP<12>
  J4G2    40  DQS12P  SCONN288_H44441004_PIP  I61
  J6U1    40  DQS12P  SCONN288_H44441003_PIP  I112
  U5D1   D73  DDR1_DQS_DP<12>  SKX_EXT_B_BGA1  I172

M_B_DQS_DP<13>   @BASEBOARD_FAB2_LIB.BASEBOARD_FAB2(SCH_1):M_B_DQS_DP<13>
  J4G2    99  DQS13P  SCONN288_H44441004_PIP  I61
  J6U1    99  DQS13P  SCONN288_H44441003_PIP  I112
  U5D1   L42  DDR1_DQS_DP<13>  SKX_EXT_B_BGA1  I172

M_B_DQS_DP<14>   @BASEBOARD_FAB2_LIB.BASEBOARD_FAB2(SCH_1):M_B_DQS_DP<14>
  J4G2   110  DQS14P  SCONN288_H44441004_PIP  I61
  J6U1   110  DQS14P  SCONN288_H44441003_PIP  I112
  U5D1   C34  DDR1_DQS_DP<14>  SKX_EXT_B_BGA1  I172

M_B_DQS_DP<15>   @BASEBOARD_FAB2_LIB.BASEBOARD_FAB2(SCH_1):M_B_DQS_DP<15>
  J4G2   121  DQS15P  SCONN288_H44441004_PIP  I61
  J6U1   121  DQS15P  SCONN288_H44441003_PIP  I112
  U5D1   C28  DDR1_DQS_DP<15>  SKX_EXT_B_BGA1  I172

M_B_DQS_DP<16>   @BASEBOARD_FAB2_LIB.BASEBOARD_FAB2(SCH_1):M_B_DQS_DP<16>
  J4G2   132  DQS16P  SCONN288_H44441004_PIP  I61
  J6U1   132  DQS16P  SCONN288_H44441003_PIP  I112
  U5D1   V27  DDR1_DQS_DP<16>  SKX_EXT_B_BGA1  I172

M_B_DQS_DP<17>   @BASEBOARD_FAB2_LIB.BASEBOARD_FAB2(SCH_1):M_B_DQS_DP<17>
  J4G2    51  DQS17P  SCONN288_H44441004_PIP  I61
  J6U1    51  DQS17P  SCONN288_H44441003_PIP  I112
  U5D1   J68  DDR1_DQS_DP<17>  SKX_EXT_B_BGA1  I172

M_B_ECC<0>      @BASEBOARD_FAB2_LIB.BASEBOARD_FAB2(SCH_1):M_B_ECC<0>
  J4G2   194  CB<1>  SCONN288_H44441004_PIP  I111
  J6U1    49  CB<0>  SCONN288_H44441003_PIP  I14
  U5D1   J70  DDR1_ECC<0>  SKX_EXT_B_BGA1  I172

M_B_ECC<1>      @BASEBOARD_FAB2_LIB.BASEBOARD_FAB2(SCH_1):M_B_ECC<1>
  J4G2    49  CB<0>  SCONN288_H44441004_PIP  I111
  J6U1   194  CB<1>  SCONN288_H44441003_PIP  I14
  U5D1   H69  DDR1_ECC<1>  SKX_EXT_B_BGA1  I172

M_B_ECC<2>      @BASEBOARD_FAB2_LIB.BASEBOARD_FAB2(SCH_1):M_B_ECC<2>
  J4G2   201  CB<3>  SCONN288_H44441004_PIP  I111
  J6U1    56  CB<2>  SCONN288_H44441003_PIP  I14
  U5D1   J66  DDR1_ECC<2>  SKX_EXT_B_BGA1  I172

M_B_ECC<3>      @BASEBOARD_FAB2_LIB.BASEBOARD_FAB2(SCH_1):M_B_ECC<3>
  J4G2    56  CB<2>  SCONN288_H44441004_PIP  I111
  J6U1   201  CB<3>  SCONN288_H44441003_PIP  I14
  U5D1   L66  DDR1_ECC<3>  SKX_EXT_B_BGA1  I172

M_B_ECC<4>      @BASEBOARD_FAB2_LIB.BASEBOARD_FAB2(SCH_1):M_B_ECC<4>
  J4G2   192  CB<5>  SCONN288_H44441004_PIP  I111
  J6U1    47  CB<4>  SCONN288_H44441003_PIP  I14
  U5D1   L70  DDR1_ECC<4>  SKX_EXT_B_BGA1  I172

M_B_ECC<5>      @BASEBOARD_FAB2_LIB.BASEBOARD_FAB2(SCH_1):M_B_ECC<5>
  J4G2    47  CB<4>  SCONN288_H44441004_PIP  I111
  J6U1   192  CB<5>  SCONN288_H44441003_PIP  I14
  U5D1   M69  DDR1_ECC<5>  SKX_EXT_B_BGA1  I172

M_B_ECC<6>      @BASEBOARD_FAB2_LIB.BASEBOARD_FAB2(SCH_1):M_B_ECC<6>
  J4G2   199  CB<7>  SCONN288_H44441004_PIP  I111
  J6U1    54  CB<6>  SCONN288_H44441003_PIP  I14
  U5D1   H67  DDR1_ECC<6>  SKX_EXT_B_BGA1  I172

M_B_ECC<7>      @BASEBOARD_FAB2_LIB.BASEBOARD_FAB2(SCH_1):M_B_ECC<7>
  J4G2    54  CB<6>  SCONN288_H44441004_PIP  I111
  J6U1   199  CB<7>  SCONN288_H44441003_PIP  I14
  U5D1   M67  DDR1_ECC<7>  SKX_EXT_B_BGA1  I172

M_B_MA<0>       @BASEBOARD_FAB2_LIB.BASEBOARD_FAB2(SCH_1):M_B_MA<0>
  J4G2    79     A0  SCONN288_H44441004_PIP  I111
  J6U1    79     A0  SCONN288_H44441003_PIP  I14
  U5D1   J52  DDR1_MA<0>  SKX_EXT_B_BGA1  I172

M_B_MA<1>       @BASEBOARD_FAB2_LIB.BASEBOARD_FAB2(SCH_1):M_B_MA<1>
  J4G2    72     A1  SCONN288_H44441004_PIP  I111
  J6U1    72     A1  SCONN288_H44441003_PIP  I14
  U5D1   J58  DDR1_MA<1>  SKX_EXT_B_BGA1  I172

M_B_MA<2>       @BASEBOARD_FAB2_LIB.BASEBOARD_FAB2(SCH_1):M_B_MA<2>
  J4G2   216     A2  SCONN288_H44441004_PIP  I111
  J6U1   216     A2  SCONN288_H44441003_PIP  I14
  U5D1   K57  DDR1_MA<2>  SKX_EXT_B_BGA1  I172

M_B_MA<3>       @BASEBOARD_FAB2_LIB.BASEBOARD_FAB2(SCH_1):M_B_MA<3>
  J4G2    71     A3  SCONN288_H44441004_PIP  I111
  J6U1    71     A3  SCONN288_H44441003_PIP  I14
  U5D1   N58  DDR1_MA<3>  SKX_EXT_B_BGA1  I172

M_B_MA<4>       @BASEBOARD_FAB2_LIB.BASEBOARD_FAB2(SCH_1):M_B_MA<4>
  J4G2   214     A4  SCONN288_H44441004_PIP  I111
  J6U1   214     A4  SCONN288_H44441003_PIP  I14
  U5D1   M59  DDR1_MA<4>  SKX_EXT_B_BGA1  I172

M_B_MA<5>       @BASEBOARD_FAB2_LIB.BASEBOARD_FAB2(SCH_1):M_B_MA<5>
  J4G2   213     A5  SCONN288_H44441004_PIP  I111
  J6U1   213     A5  SCONN288_H44441003_PIP  I14
  U5D1   R58  DDR1_MA<5>  SKX_EXT_B_BGA1  I172

M_B_MA<6>       @BASEBOARD_FAB2_LIB.BASEBOARD_FAB2(SCH_1):M_B_MA<6>
  J4G2    69     A6  SCONN288_H44441004_PIP  I111
  J6U1    69     A6  SCONN288_H44441003_PIP  I14
  U5D1   T59  DDR1_MA<6>  SKX_EXT_B_BGA1  I172

M_B_MA<7>       @BASEBOARD_FAB2_LIB.BASEBOARD_FAB2(SCH_1):M_B_MA<7>
  J4G2   211     A7  SCONN288_H44441004_PIP  I111
  J6U1   211     A7  SCONN288_H44441003_PIP  I14
  U5D1   V61  DDR1_MA<7>  SKX_EXT_B_BGA1  I172

M_B_MA<8>       @BASEBOARD_FAB2_LIB.BASEBOARD_FAB2(SCH_1):M_B_MA<8>
  J4G2    68     A8  SCONN288_H44441004_PIP  I111
  J6U1    68     A8  SCONN288_H44441003_PIP  I14
  U5D1   W60  DDR1_MA<8>  SKX_EXT_B_BGA1  I172

M_B_MA<9>       @BASEBOARD_FAB2_LIB.BASEBOARD_FAB2(SCH_1):M_B_MA<9>
  J4G2    66     A9  SCONN288_H44441004_PIP  I111
  J6U1    66     A9  SCONN288_H44441003_PIP  I14
  U5D1   K59  DDR1_MA<9>  SKX_EXT_B_BGA1  I172

M_B_MA<10>      @BASEBOARD_FAB2_LIB.BASEBOARD_FAB2(SCH_1):M_B_MA<10>
  J4G2   225    A10  SCONN288_H44441004_PIP  I111
  J6U1   225    A10  SCONN288_H44441003_PIP  I14
  U5D1   M55  DDR1_MA<10>  SKX_EXT_B_BGA1  I172

M_B_MA<11>      @BASEBOARD_FAB2_LIB.BASEBOARD_FAB2(SCH_1):M_B_MA<11>
  J4G2   210    A11  SCONN288_H44441004_PIP  I111
  J6U1   210    A11  SCONN288_H44441003_PIP  I14
  U5D1   R60  DDR1_MA<11>  SKX_EXT_B_BGA1  I172

M_B_MA<12>      @BASEBOARD_FAB2_LIB.BASEBOARD_FAB2(SCH_1):M_B_MA<12>
  J4G2    65    A12  SCONN288_H44441004_PIP  I111
  J6U1    65    A12  SCONN288_H44441003_PIP  I14
  U5D1   T61  DDR1_MA<12>  SKX_EXT_B_BGA1  I172

M_B_MA<13>      @BASEBOARD_FAB2_LIB.BASEBOARD_FAB2(SCH_1):M_B_MA<13>
  J4G2   232    A13  SCONN288_H44441004_PIP  I111
  J6U1   232    A13  SCONN288_H44441003_PIP  I14
  U5D1   M51  DDR1_MA<13>  SKX_EXT_B_BGA1  I172

M_B_MA<14>      @BASEBOARD_FAB2_LIB.BASEBOARD_FAB2(SCH_1):M_B_MA<14>
  J4G2   228  A14_WE_N  SCONN288_H44441004_PIP  I111
  J6U1   228  A14_WE_N  SCONN288_H44441003_PIP  I14
  U5D1   T51  DDR1_MA<14>  SKX_EXT_B_BGA1  I172

M_B_MA<15>      @BASEBOARD_FAB2_LIB.BASEBOARD_FAB2(SCH_1):M_B_MA<15>
  J4G2    86  A15_CAS_N  SCONN288_H44441004_PIP  I111
  J6U1    86  A15_CAS_N  SCONN288_H44441003_PIP  I14
  U5D1   N52  DDR1_MA<15>  SKX_EXT_B_BGA1  I172

M_B_MA<16>      @BASEBOARD_FAB2_LIB.BASEBOARD_FAB2(SCH_1):M_B_MA<16>
  J4G2    82  A16_RAS_N  SCONN288_H44441004_PIP  I111
  J6U1    82  A16_RAS_N  SCONN288_H44441003_PIP  I14
  U5D1   R52  DDR1_MA<16>  SKX_EXT_B_BGA1  I172

M_B_MA<17>      @BASEBOARD_FAB2_LIB.BASEBOARD_FAB2(SCH_1):M_B_MA<17>
  J4G2   234    A17  SCONN288_H44441004_PIP  I111
  J6U1   234    A17  SCONN288_H44441003_PIP  I14
  U5D1   N48  DDR1_MA<17>  SKX_EXT_B_BGA1  I172

M_B_ODT<0>      @BASEBOARD_FAB2_LIB.BASEBOARD_FAB2(SCH_1):M_B_ODT<0>
  J4G2    87  ODT<0>  SCONN288_H44441004_PIP  I111
  U5D1   N50  DDR1_ODT<0>  SKX_EXT_B_BGA1  I172

M_B_ODT<1>      @BASEBOARD_FAB2_LIB.BASEBOARD_FAB2(SCH_1):M_B_ODT<1>
  J4G2    91  ODT<1>  SCONN288_H44441004_PIP  I111
  U5D1   R48  DDR1_ODT<1>  SKX_EXT_B_BGA1  I172

M_B_ODT<2>      @BASEBOARD_FAB2_LIB.BASEBOARD_FAB2(SCH_1):M_B_ODT<2>
  J6U1    87  ODT<0>  SCONN288_H44441003_PIP  I14
  U5D1   M49  DDR1_ODT<2>  SKX_EXT_B_BGA1  I172

M_B_ODT<3>      @BASEBOARD_FAB2_LIB.BASEBOARD_FAB2(SCH_1):M_B_ODT<3>
  J6U1    91  ODT<1>  SCONN288_H44441003_PIP  I14
  U5D1   T47  DDR1_ODT<3>  SKX_EXT_B_BGA1  I172

M_B_PAR         @BASEBOARD_FAB2_LIB.BASEBOARD_FAB2(SCH_1):M_B_PAR
  J4G2   222    PAR  SCONN288_H44441004_PIP  I111
  J6U1   222    PAR  SCONN288_H44441003_PIP  I14
  U5D1   K53  DDR1_PAR  SKX_EXT_B_BGA1  I172

M_B_VREF        @BASEBOARD_FAB2_LIB.BASEBOARD_FAB2(SCH_1):M_B_VREF
  C4G3     1      A  CAP_A       I179
  C6U9     1      A  CAP_A        I5
  J4G2   146  VREFCA  SCONN288_H44441004_PIP  I111
  J6U1   146  VREFCA  SCONN288_H44441003_PIP  I14
  R4G1     2      B  RES         I42
  R4G2     2      B  RES         I38
  R4G3     1      A  RES         I40

M_C_ACT_N       @BASEBOARD_FAB2_LIB.BASEBOARD_FAB2(SCH_1):M_C_ACT_N
  J4G3    62  ACT_N  SCONN288_H44441004_PIP  I111
  J6U2    62  ACT_N  SCONN288_H44441003_PIP  I111
  U5D1   AB61  DDR2_ACT_N  SKX_EXT_B_BGA1  I172

M_C_ALERT_N     @BASEBOARD_FAB2_LIB.BASEBOARD_FAB2(SCH_1):M_C_ALERT_N
  J4G3   208  ALERT_N  SCONN288_H44441004_PIP  I111
  J6U2   208  ALERT_N  SCONN288_H44441003_PIP  I111
  U5D1   AD61  DDR2_ALERT_N  SKX_EXT_B_BGA1  I172

M_C_BA<0>       @BASEBOARD_FAB2_LIB.BASEBOARD_FAB2(SCH_1):M_C_BA<0>
  J4G3    81  BA<0>  SCONN288_H44441004_PIP  I111
  J6U2    81  BA<0>  SCONN288_H44441003_PIP  I111
  U5D1   W52  DDR2_BA<0>  SKX_EXT_B_BGA1  I172

M_C_BA<1>       @BASEBOARD_FAB2_LIB.BASEBOARD_FAB2(SCH_1):M_C_BA<1>
  J4G3   224  BA<1>  SCONN288_H44441004_PIP  I111
  J6U2   224  BA<1>  SCONN288_H44441003_PIP  I111
  U5D1   AE56  DDR2_BA<1>  SKX_EXT_B_BGA1  I172

M_C_BG<0>       @BASEBOARD_FAB2_LIB.BASEBOARD_FAB2(SCH_1):M_C_BG<0>
  J4G3    63  BG<0>  SCONN288_H44441004_PIP  I111
  J6U2    63  BG<0>  SCONN288_H44441003_PIP  I111
  U5D1   AA60  DDR2_BG<0>  SKX_EXT_B_BGA1  I172

M_C_BG<1>       @BASEBOARD_FAB2_LIB.BASEBOARD_FAB2(SCH_1):M_C_BG<1>
  J4G3   207  BG<1>  SCONN288_H44441004_PIP  I111
  J6U2   207  BG<1>  SCONN288_H44441003_PIP  I111
  U5D1   AE62  DDR2_BG<1>  SKX_EXT_B_BGA1  I172

M_C_C<2>        @BASEBOARD_FAB2_LIB.BASEBOARD_FAB2(SCH_1):M_C_C<2>
  J4G3   235   C<2>  SCONN288_H44441004_PIP  I111
  J6U2   235   C<2>  SCONN288_H44441003_PIP  I111
  U5D1   AB45  DDR2_CID<2>  SKX_EXT_B_BGA1  I172

M_C_CKE<0>      @BASEBOARD_FAB2_LIB.BASEBOARD_FAB2(SCH_1):M_C_CKE<0>
  J4G3    60  CKE<0>  SCONN288_H44441004_PIP  I111
  U5D1   AA62  DDR2_CKE<0>  SKX_EXT_B_BGA1  I172

M_C_CKE<1>      @BASEBOARD_FAB2_LIB.BASEBOARD_FAB2(SCH_1):M_C_CKE<1>
  J4G3   203  CKE<1>  SCONN288_H44441004_PIP  I111
  U5D1   AD63  DDR2_CKE<1>  SKX_EXT_B_BGA1  I172

M_C_CKE<2>      @BASEBOARD_FAB2_LIB.BASEBOARD_FAB2(SCH_1):M_C_CKE<2>
  J6U2    60  CKE<0>  SCONN288_H44441003_PIP  I111
  U5D1   V63  DDR2_CKE<2>  SKX_EXT_B_BGA1  I172

M_C_CKE<3>      @BASEBOARD_FAB2_LIB.BASEBOARD_FAB2(SCH_1):M_C_CKE<3>
  J6U2   203  CKE<1>  SCONN288_H44441003_PIP  I111
  U5D1   AB63  DDR2_CKE<3>  SKX_EXT_B_BGA1  I172

M_C_CLK_DN<0>   @BASEBOARD_FAB2_LIB.BASEBOARD_FAB2(SCH_1):M_C_CLK_DN<0>
  J4G3    75   CK0N  SCONN288_H44441004_PIP  I111
  U5D1   AA54  DDR2_CLK_DN<0>  SKX_EXT_B_BGA1  I172

M_C_CLK_DN<1>   @BASEBOARD_FAB2_LIB.BASEBOARD_FAB2(SCH_1):M_C_CLK_DN<1>
  J4G3   219   CK1N  SCONN288_H44441004_PIP  I111
  U5D1   W54  DDR2_CLK_DN<1>  SKX_EXT_B_BGA1  I172

M_C_CLK_DN<2>   @BASEBOARD_FAB2_LIB.BASEBOARD_FAB2(SCH_1):M_C_CLK_DN<2>
  J6U2    75   CK0N  SCONN288_H44441003_PIP  I111
  U5D1   AA56  DDR2_CLK_DN<2>  SKX_EXT_B_BGA1  I172

M_C_CLK_DN<3>   @BASEBOARD_FAB2_LIB.BASEBOARD_FAB2(SCH_1):M_C_CLK_DN<3>
  J6U2   219   CK1N  SCONN288_H44441003_PIP  I111
  U5D1   W56  DDR2_CLK_DN<3>  SKX_EXT_B_BGA1  I172

M_C_CLK_DP<0>   @BASEBOARD_FAB2_LIB.BASEBOARD_FAB2(SCH_1):M_C_CLK_DP<0>
  J4G3    74   CK0P  SCONN288_H44441004_PIP  I111
  U5D1   AB55  DDR2_CLK_DP<0>  SKX_EXT_B_BGA1  I172

M_C_CLK_DP<1>   @BASEBOARD_FAB2_LIB.BASEBOARD_FAB2(SCH_1):M_C_CLK_DP<1>
  J4G3   218   CK1P  SCONN288_H44441004_PIP  I111
  U5D1   V55  DDR2_CLK_DP<1>  SKX_EXT_B_BGA1  I172

M_C_CLK_DP<2>   @BASEBOARD_FAB2_LIB.BASEBOARD_FAB2(SCH_1):M_C_CLK_DP<2>
  J6U2    74   CK0P  SCONN288_H44441003_PIP  I111
  U5D1   AB57  DDR2_CLK_DP<2>  SKX_EXT_B_BGA1  I172

M_C_CLK_DP<3>   @BASEBOARD_FAB2_LIB.BASEBOARD_FAB2(SCH_1):M_C_CLK_DP<3>
  J6U2   218   CK1P  SCONN288_H44441003_PIP  I111
  U5D1   V57  DDR2_CLK_DP<3>  SKX_EXT_B_BGA1  I172

M_C_CPU_VREF    @BASEBOARD_FAB2_LIB.BASEBOARD_FAB2(SCH_1):M_C_CPU_VREF
  C4G17    1      A  CAP_A       I51
  R4G20    1      A  RES         I50
  U5D1   AH63  DDR2_CAVREF  SKX_EXT_B_BGA1  I259

M_C_CS_N<0>     @BASEBOARD_FAB2_LIB.BASEBOARD_FAB2(SCH_1):M_C_CS_N<0>
  J4G3    84   S0_N  SCONN288_H44441004_PIP  I111
  U5D1   V51  DDR2_CS_N<0>  SKX_EXT_B_BGA1  I172

M_C_CS_N<1>     @BASEBOARD_FAB2_LIB.BASEBOARD_FAB2(SCH_1):M_C_CS_N<1>
  J4G3    89   S1_N  SCONN288_H44441004_PIP  I111
  U5D1   AB49  DDR2_CS_N<1>  SKX_EXT_B_BGA1  I172

M_C_CS_N<2>     @BASEBOARD_FAB2_LIB.BASEBOARD_FAB2(SCH_1):M_C_CS_N<2>
  J4G3    93  S2_N_C<0>  SCONN288_H44441004_PIP  I111
  U5D1   W46  DDR2_CS_N<2>  SKX_EXT_B_BGA1  I172

M_C_CS_N<3>     @BASEBOARD_FAB2_LIB.BASEBOARD_FAB2(SCH_1):M_C_CS_N<3>
  J4G3   237  S3_N_C<1>  SCONN288_H44441004_PIP  I111
  U5D1   AA46  DDR2_CS_N<3>  SKX_EXT_B_BGA1  I172

M_C_CS_N<4>     @BASEBOARD_FAB2_LIB.BASEBOARD_FAB2(SCH_1):M_C_CS_N<4>
  J6U2    84   S0_N  SCONN288_H44441003_PIP  I111
  U5D1   AB51  DDR2_CS_N<4>  SKX_EXT_B_BGA1  I172

M_C_CS_N<5>     @BASEBOARD_FAB2_LIB.BASEBOARD_FAB2(SCH_1):M_C_CS_N<5>
  J6U2    89   S1_N  SCONN288_H44441003_PIP  I111
  U5D1   W48  DDR2_CS_N<5>  SKX_EXT_B_BGA1  I172

M_C_CS_N<6>     @BASEBOARD_FAB2_LIB.BASEBOARD_FAB2(SCH_1):M_C_CS_N<6>
  J6U2    93  S2_N_C<0>  SCONN288_H44441003_PIP  I111
  U5D1   T45  DDR2_CS_N<6>  SKX_EXT_B_BGA1  I172

M_C_CS_N<7>     @BASEBOARD_FAB2_LIB.BASEBOARD_FAB2(SCH_1):M_C_CS_N<7>
  J6U2   237  S3_N_C<1>  SCONN288_H44441003_PIP  I111
  U5D1   V45  DDR2_CS_N<7>  SKX_EXT_B_BGA1  I172

M_C_DQ<0>       @BASEBOARD_FAB2_LIB.BASEBOARD_FAB2(SCH_1):M_C_DQ<0>
  J4G3   150  DQ<1>  SCONN288_H44441004_PIP  I111
  J6U2     5  DQ<0>  SCONN288_H44441003_PIP  I111
  U5D1   AR76  DDR2_DQ<0>  SKX_EXT_B_BGA1  I172

M_C_DQ<1>       @BASEBOARD_FAB2_LIB.BASEBOARD_FAB2(SCH_1):M_C_DQ<1>
  J4G3     5  DQ<0>  SCONN288_H44441004_PIP  I111
  J6U2   150  DQ<1>  SCONN288_H44441003_PIP  I111
  U5D1   AN74  DDR2_DQ<1>  SKX_EXT_B_BGA1  I172

M_C_DQ<2>       @BASEBOARD_FAB2_LIB.BASEBOARD_FAB2(SCH_1):M_C_DQ<2>
  J4G3   157  DQ<3>  SCONN288_H44441004_PIP  I111
  J6U2    12  DQ<2>  SCONN288_H44441003_PIP  I111
  U5D1   AK77  DDR2_DQ<2>  SKX_EXT_B_BGA1  I172

M_C_DQ<3>       @BASEBOARD_FAB2_LIB.BASEBOARD_FAB2(SCH_1):M_C_DQ<3>
  J4G3    12  DQ<2>  SCONN288_H44441004_PIP  I111
  J6U2   157  DQ<3>  SCONN288_H44441003_PIP  I111
  U5D1   AJ76  DDR2_DQ<3>  SKX_EXT_B_BGA1  I172

M_C_DQ<4>       @BASEBOARD_FAB2_LIB.BASEBOARD_FAB2(SCH_1):M_C_DQ<4>
  J4G3   148  DQ<5>  SCONN288_H44441004_PIP  I111
  J6U2     3  DQ<4>  SCONN288_H44441003_PIP  I111
  U5D1   AT75  DDR2_DQ<4>  SKX_EXT_B_BGA1  I172

M_C_DQ<5>       @BASEBOARD_FAB2_LIB.BASEBOARD_FAB2(SCH_1):M_C_DQ<5>
  J4G3     3  DQ<4>  SCONN288_H44441004_PIP  I111
  J6U2   148  DQ<5>  SCONN288_H44441003_PIP  I111
  U5D1   AR74  DDR2_DQ<5>  SKX_EXT_B_BGA1  I172

M_C_DQ<6>       @BASEBOARD_FAB2_LIB.BASEBOARD_FAB2(SCH_1):M_C_DQ<6>
  J4G3   155  DQ<7>  SCONN288_H44441004_PIP  I111
  J6U2    10  DQ<6>  SCONN288_H44441003_PIP  I111
  U5D1   AM77  DDR2_DQ<6>  SKX_EXT_B_BGA1  I172

M_C_DQ<7>       @BASEBOARD_FAB2_LIB.BASEBOARD_FAB2(SCH_1):M_C_DQ<7>
  J4G3    10  DQ<6>  SCONN288_H44441004_PIP  I111
  J6U2   155  DQ<7>  SCONN288_H44441003_PIP  I111
  U5D1   AK75  DDR2_DQ<7>  SKX_EXT_B_BGA1  I172

M_C_DQ<8>       @BASEBOARD_FAB2_LIB.BASEBOARD_FAB2(SCH_1):M_C_DQ<8>
  J4G3   161  DQ<9>  SCONN288_H44441004_PIP  I111
  J6U2    16  DQ<8>  SCONN288_H44441003_PIP  I111
  U5D1   AE76  DDR2_DQ<8>  SKX_EXT_B_BGA1  I172

M_C_DQ<9>       @BASEBOARD_FAB2_LIB.BASEBOARD_FAB2(SCH_1):M_C_DQ<9>
  J4G3    16  DQ<8>  SCONN288_H44441004_PIP  I111
  J6U2   161  DQ<9>  SCONN288_H44441003_PIP  I111
  U5D1   AC74  DDR2_DQ<9>  SKX_EXT_B_BGA1  I172

M_C_DQ<10>      @BASEBOARD_FAB2_LIB.BASEBOARD_FAB2(SCH_1):M_C_DQ<10>
  J4G3   168  DQ<11>  SCONN288_H44441004_PIP  I111
  J6U2    23  DQ<10>  SCONN288_H44441003_PIP  I111
  U5D1   Y77  DDR2_DQ<10>  SKX_EXT_B_BGA1  I172

M_C_DQ<11>      @BASEBOARD_FAB2_LIB.BASEBOARD_FAB2(SCH_1):M_C_DQ<11>
  J4G3    23  DQ<10>  SCONN288_H44441004_PIP  I111
  J6U2   168  DQ<11>  SCONN288_H44441003_PIP  I111
  U5D1   W76  DDR2_DQ<11>  SKX_EXT_B_BGA1  I172

M_C_DQ<12>      @BASEBOARD_FAB2_LIB.BASEBOARD_FAB2(SCH_1):M_C_DQ<12>
  J4G3   159  DQ<13>  SCONN288_H44441004_PIP  I111
  J6U2    14  DQ<12>  SCONN288_H44441003_PIP  I111
  U5D1   AF75  DDR2_DQ<12>  SKX_EXT_B_BGA1  I172

M_C_DQ<13>      @BASEBOARD_FAB2_LIB.BASEBOARD_FAB2(SCH_1):M_C_DQ<13>
  J4G3    14  DQ<12>  SCONN288_H44441004_PIP  I111
  J6U2   159  DQ<13>  SCONN288_H44441003_PIP  I111
  U5D1   AE74  DDR2_DQ<13>  SKX_EXT_B_BGA1  I172

M_C_DQ<14>      @BASEBOARD_FAB2_LIB.BASEBOARD_FAB2(SCH_1):M_C_DQ<14>
  J4G3   166  DQ<15>  SCONN288_H44441004_PIP  I111
  J6U2    21  DQ<14>  SCONN288_H44441003_PIP  I111
  U5D1   AB77  DDR2_DQ<14>  SKX_EXT_B_BGA1  I172

M_C_DQ<15>      @BASEBOARD_FAB2_LIB.BASEBOARD_FAB2(SCH_1):M_C_DQ<15>
  J4G3    21  DQ<14>  SCONN288_H44441004_PIP  I111
  J6U2   166  DQ<15>  SCONN288_H44441003_PIP  I111
  U5D1   Y75  DDR2_DQ<15>  SKX_EXT_B_BGA1  I172

M_C_DQ<16>      @BASEBOARD_FAB2_LIB.BASEBOARD_FAB2(SCH_1):M_C_DQ<16>
  J4G3   172  DQ<17>  SCONN288_H44441004_PIP  I111
  J6U2    27  DQ<16>  SCONN288_H44441003_PIP  I111
  U5D1   W72  DDR2_DQ<16>  SKX_EXT_B_BGA1  I172

M_C_DQ<17>      @BASEBOARD_FAB2_LIB.BASEBOARD_FAB2(SCH_1):M_C_DQ<17>
  J4G3    27  DQ<16>  SCONN288_H44441004_PIP  I111
  J6U2   172  DQ<17>  SCONN288_H44441003_PIP  I111
  U5D1   AA70  DDR2_DQ<17>  SKX_EXT_B_BGA1  I172

M_C_DQ<18>      @BASEBOARD_FAB2_LIB.BASEBOARD_FAB2(SCH_1):M_C_DQ<18>
  J4G3   179  DQ<19>  SCONN288_H44441004_PIP  I111
  J6U2    34  DQ<18>  SCONN288_H44441003_PIP  I111
  U5D1   R70  DDR2_DQ<18>  SKX_EXT_B_BGA1  I172

M_C_DQ<19>      @BASEBOARD_FAB2_LIB.BASEBOARD_FAB2(SCH_1):M_C_DQ<19>
  J4G3    34  DQ<18>  SCONN288_H44441004_PIP  I111
  J6U2   179  DQ<19>  SCONN288_H44441003_PIP  I111
  U5D1   T69  DDR2_DQ<19>  SKX_EXT_B_BGA1  I172

M_C_DQ<20>      @BASEBOARD_FAB2_LIB.BASEBOARD_FAB2(SCH_1):M_C_DQ<20>
  J4G3   170  DQ<21>  SCONN288_H44441004_PIP  I111
  J6U2    25  DQ<20>  SCONN288_H44441003_PIP  I111
  U5D1   AA72  DDR2_DQ<20>  SKX_EXT_B_BGA1  I172

M_C_DQ<21>      @BASEBOARD_FAB2_LIB.BASEBOARD_FAB2(SCH_1):M_C_DQ<21>
  J4G3    25  DQ<20>  SCONN288_H44441004_PIP  I111
  J6U2   170  DQ<21>  SCONN288_H44441003_PIP  I111
  U5D1   AB71  DDR2_DQ<21>  SKX_EXT_B_BGA1  I172

M_C_DQ<22>      @BASEBOARD_FAB2_LIB.BASEBOARD_FAB2(SCH_1):M_C_DQ<22>
  J4G3   177  DQ<23>  SCONN288_H44441004_PIP  I111
  J6U2    32  DQ<22>  SCONN288_H44441003_PIP  I111
  U5D1   T71  DDR2_DQ<22>  SKX_EXT_B_BGA1  I172

M_C_DQ<23>      @BASEBOARD_FAB2_LIB.BASEBOARD_FAB2(SCH_1):M_C_DQ<23>
  J4G3    32  DQ<22>  SCONN288_H44441004_PIP  I111
  J6U2   177  DQ<23>  SCONN288_H44441003_PIP  I111
  U5D1   V69  DDR2_DQ<23>  SKX_EXT_B_BGA1  I172

M_C_DQ<24>      @BASEBOARD_FAB2_LIB.BASEBOARD_FAB2(SCH_1):M_C_DQ<24>
  J4G3   183  DQ<25>  SCONN288_H44441004_PIP  I111
  J6U2    38  DQ<24>  SCONN288_H44441003_PIP  I111
  U5D1   AM67  DDR2_DQ<24>  SKX_EXT_B_BGA1  I172

M_C_DQ<25>      @BASEBOARD_FAB2_LIB.BASEBOARD_FAB2(SCH_1):M_C_DQ<25>
  J4G3    38  DQ<24>  SCONN288_H44441004_PIP  I111
  J6U2   183  DQ<25>  SCONN288_H44441003_PIP  I111
  U5D1   AT67  DDR2_DQ<25>  SKX_EXT_B_BGA1  I172

M_C_DQ<26>      @BASEBOARD_FAB2_LIB.BASEBOARD_FAB2(SCH_1):M_C_DQ<26>
  J4G3   190  DQ<27>  SCONN288_H44441004_PIP  I111
  J6U2    45  DQ<26>  SCONN288_H44441003_PIP  I111
  U5D1   AN64  DDR2_DQ<26>  SKX_EXT_B_BGA1  I172

M_C_DQ<27>      @BASEBOARD_FAB2_LIB.BASEBOARD_FAB2(SCH_1):M_C_DQ<27>
  J4G3    45  DQ<26>  SCONN288_H44441004_PIP  I111
  J6U2   190  DQ<27>  SCONN288_H44441003_PIP  I111
  U5D1   AR64  DDR2_DQ<27>  SKX_EXT_B_BGA1  I172

M_C_DQ<28>      @BASEBOARD_FAB2_LIB.BASEBOARD_FAB2(SCH_1):M_C_DQ<28>
  J4G3   181  DQ<29>  SCONN288_H44441004_PIP  I111
  J6U2    36  DQ<28>  SCONN288_H44441003_PIP  I111
  U5D1   AN68  DDR2_DQ<28>  SKX_EXT_B_BGA1  I172

M_C_DQ<29>      @BASEBOARD_FAB2_LIB.BASEBOARD_FAB2(SCH_1):M_C_DQ<29>
  J4G3    36  DQ<28>  SCONN288_H44441004_PIP  I111
  J6U2   181  DQ<29>  SCONN288_H44441003_PIP  I111
  U5D1   AR68  DDR2_DQ<29>  SKX_EXT_B_BGA1  I172

M_C_DQ<30>      @BASEBOARD_FAB2_LIB.BASEBOARD_FAB2(SCH_1):M_C_DQ<30>
  J4G3   188  DQ<31>  SCONN288_H44441004_PIP  I111
  J6U2    43  DQ<30>  SCONN288_H44441003_PIP  I111
  U5D1   AM65  DDR2_DQ<30>  SKX_EXT_B_BGA1  I172

M_C_DQ<31>      @BASEBOARD_FAB2_LIB.BASEBOARD_FAB2(SCH_1):M_C_DQ<31>
  J4G3    43  DQ<30>  SCONN288_H44441004_PIP  I111
  J6U2   188  DQ<31>  SCONN288_H44441003_PIP  I111
  U5D1   AT65  DDR2_DQ<31>  SKX_EXT_B_BGA1  I172

M_C_DQ<32>      @BASEBOARD_FAB2_LIB.BASEBOARD_FAB2(SCH_1):M_C_DQ<32>
  J4G3   242  DQ<33>  SCONN288_H44441004_PIP  I111
  J6U2    97  DQ<32>  SCONN288_H44441003_PIP  I111
  U5D1   U40  DDR2_DQ<32>  SKX_EXT_B_BGA1  I172

M_C_DQ<33>      @BASEBOARD_FAB2_LIB.BASEBOARD_FAB2(SCH_1):M_C_DQ<33>
  J4G3    97  DQ<32>  SCONN288_H44441004_PIP  I111
  J6U2   242  DQ<33>  SCONN288_H44441003_PIP  I111
  U5D1   AA40  DDR2_DQ<33>  SKX_EXT_B_BGA1  I172

M_C_DQ<34>      @BASEBOARD_FAB2_LIB.BASEBOARD_FAB2(SCH_1):M_C_DQ<34>
  J4G3   249  DQ<35>  SCONN288_H44441004_PIP  I111
  J6U2   104  DQ<34>  SCONN288_H44441003_PIP  I111
  U5D1   V37  DDR2_DQ<34>  SKX_EXT_B_BGA1  I172

M_C_DQ<35>      @BASEBOARD_FAB2_LIB.BASEBOARD_FAB2(SCH_1):M_C_DQ<35>
  J4G3   104  DQ<34>  SCONN288_H44441004_PIP  I111
  J6U2   249  DQ<35>  SCONN288_H44441003_PIP  I111
  U5D1   Y37  DDR2_DQ<35>  SKX_EXT_B_BGA1  I172

M_C_DQ<36>      @BASEBOARD_FAB2_LIB.BASEBOARD_FAB2(SCH_1):M_C_DQ<36>
  J4G3   240  DQ<37>  SCONN288_H44441004_PIP  I111
  J6U2    95  DQ<36>  SCONN288_H44441003_PIP  I111
  U5D1   V41  DDR2_DQ<36>  SKX_EXT_B_BGA1  I172

M_C_DQ<37>      @BASEBOARD_FAB2_LIB.BASEBOARD_FAB2(SCH_1):M_C_DQ<37>
  J4G3    95  DQ<36>  SCONN288_H44441004_PIP  I111
  J6U2   240  DQ<37>  SCONN288_H44441003_PIP  I111
  U5D1   Y41  DDR2_DQ<37>  SKX_EXT_B_BGA1  I172

M_C_DQ<38>      @BASEBOARD_FAB2_LIB.BASEBOARD_FAB2(SCH_1):M_C_DQ<38>
  J4G3   247  DQ<39>  SCONN288_H44441004_PIP  I111
  J6U2   102  DQ<38>  SCONN288_H44441003_PIP  I111
  U5D1   U38  DDR2_DQ<38>  SKX_EXT_B_BGA1  I172

M_C_DQ<39>      @BASEBOARD_FAB2_LIB.BASEBOARD_FAB2(SCH_1):M_C_DQ<39>
  J4G3   102  DQ<38>  SCONN288_H44441004_PIP  I111
  J6U2   247  DQ<39>  SCONN288_H44441003_PIP  I111
  U5D1   AA38  DDR2_DQ<39>  SKX_EXT_B_BGA1  I172

M_C_DQ<40>      @BASEBOARD_FAB2_LIB.BASEBOARD_FAB2(SCH_1):M_C_DQ<40>
  J4G3   253  DQ<41>  SCONN288_H44441004_PIP  I111
  J6U2   108  DQ<40>  SCONN288_H44441003_PIP  I111
  U5D1   U34  DDR2_DQ<40>  SKX_EXT_B_BGA1  I172

M_C_DQ<41>      @BASEBOARD_FAB2_LIB.BASEBOARD_FAB2(SCH_1):M_C_DQ<41>
  J4G3   108  DQ<40>  SCONN288_H44441004_PIP  I111
  J6U2   253  DQ<41>  SCONN288_H44441003_PIP  I111
  U5D1   AA34  DDR2_DQ<41>  SKX_EXT_B_BGA1  I172

M_C_DQ<42>      @BASEBOARD_FAB2_LIB.BASEBOARD_FAB2(SCH_1):M_C_DQ<42>
  J4G3   260  DQ<43>  SCONN288_H44441004_PIP  I111
  J6U2   115  DQ<42>  SCONN288_H44441003_PIP  I111
  U5D1   V31  DDR2_DQ<42>  SKX_EXT_B_BGA1  I172

M_C_DQ<43>      @BASEBOARD_FAB2_LIB.BASEBOARD_FAB2(SCH_1):M_C_DQ<43>
  J4G3   115  DQ<42>  SCONN288_H44441004_PIP  I111
  J6U2   260  DQ<43>  SCONN288_H44441003_PIP  I111
  U5D1   Y31  DDR2_DQ<43>  SKX_EXT_B_BGA1  I172

M_C_DQ<44>      @BASEBOARD_FAB2_LIB.BASEBOARD_FAB2(SCH_1):M_C_DQ<44>
  J4G3   251  DQ<45>  SCONN288_H44441004_PIP  I111
  J6U2   106  DQ<44>  SCONN288_H44441003_PIP  I111
  U5D1   V35  DDR2_DQ<44>  SKX_EXT_B_BGA1  I172

M_C_DQ<45>      @BASEBOARD_FAB2_LIB.BASEBOARD_FAB2(SCH_1):M_C_DQ<45>
  J4G3   106  DQ<44>  SCONN288_H44441004_PIP  I111
  J6U2   251  DQ<45>  SCONN288_H44441003_PIP  I111
  U5D1   Y35  DDR2_DQ<45>  SKX_EXT_B_BGA1  I172

M_C_DQ<46>      @BASEBOARD_FAB2_LIB.BASEBOARD_FAB2(SCH_1):M_C_DQ<46>
  J4G3   258  DQ<47>  SCONN288_H44441004_PIP  I111
  J6U2   113  DQ<46>  SCONN288_H44441003_PIP  I111
  U5D1   U32  DDR2_DQ<46>  SKX_EXT_B_BGA1  I172

M_C_DQ<47>      @BASEBOARD_FAB2_LIB.BASEBOARD_FAB2(SCH_1):M_C_DQ<47>
  J4G3   113  DQ<46>  SCONN288_H44441004_PIP  I111
  J6U2   258  DQ<47>  SCONN288_H44441003_PIP  I111
  U5D1   AA32  DDR2_DQ<47>  SKX_EXT_B_BGA1  I172

M_C_DQ<48>      @BASEBOARD_FAB2_LIB.BASEBOARD_FAB2(SCH_1):M_C_DQ<48>
  J4G3   264  DQ<49>  SCONN288_H44441004_PIP  I111
  J6U2   119  DQ<48>  SCONN288_H44441003_PIP  I111
  U5D1   AD31  DDR2_DQ<48>  SKX_EXT_B_BGA1  I172

M_C_DQ<49>      @BASEBOARD_FAB2_LIB.BASEBOARD_FAB2(SCH_1):M_C_DQ<49>
  J4G3   119  DQ<48>  SCONN288_H44441004_PIP  I111
  J6U2   264  DQ<49>  SCONN288_H44441003_PIP  I111
  U5D1   AH31  DDR2_DQ<49>  SKX_EXT_B_BGA1  I172

M_C_DQ<50>      @BASEBOARD_FAB2_LIB.BASEBOARD_FAB2(SCH_1):M_C_DQ<50>
  J4G3   271  DQ<51>  SCONN288_H44441004_PIP  I111
  J6U2   126  DQ<50>  SCONN288_H44441003_PIP  I111
  U5D1   AE28  DDR2_DQ<50>  SKX_EXT_B_BGA1  I172

M_C_DQ<51>      @BASEBOARD_FAB2_LIB.BASEBOARD_FAB2(SCH_1):M_C_DQ<51>
  J4G3   126  DQ<50>  SCONN288_H44441004_PIP  I111
  J6U2   271  DQ<51>  SCONN288_H44441003_PIP  I111
  U5D1   AG28  DDR2_DQ<51>  SKX_EXT_B_BGA1  I172

M_C_DQ<52>      @BASEBOARD_FAB2_LIB.BASEBOARD_FAB2(SCH_1):M_C_DQ<52>
  J4G3   262  DQ<53>  SCONN288_H44441004_PIP  I111
  J6U2   117  DQ<52>  SCONN288_H44441003_PIP  I111
  U5D1   AE32  DDR2_DQ<52>  SKX_EXT_B_BGA1  I172

M_C_DQ<53>      @BASEBOARD_FAB2_LIB.BASEBOARD_FAB2(SCH_1):M_C_DQ<53>
  J4G3   117  DQ<52>  SCONN288_H44441004_PIP  I111
  J6U2   262  DQ<53>  SCONN288_H44441003_PIP  I111
  U5D1   AG32  DDR2_DQ<53>  SKX_EXT_B_BGA1  I172

M_C_DQ<54>      @BASEBOARD_FAB2_LIB.BASEBOARD_FAB2(SCH_1):M_C_DQ<54>
  J4G3   269  DQ<55>  SCONN288_H44441004_PIP  I111
  J6U2   124  DQ<54>  SCONN288_H44441003_PIP  I111
  U5D1   AD29  DDR2_DQ<54>  SKX_EXT_B_BGA1  I172

M_C_DQ<55>      @BASEBOARD_FAB2_LIB.BASEBOARD_FAB2(SCH_1):M_C_DQ<55>
  J4G3   124  DQ<54>  SCONN288_H44441004_PIP  I111
  J6U2   269  DQ<55>  SCONN288_H44441003_PIP  I111
  U5D1   AH29  DDR2_DQ<55>  SKX_EXT_B_BGA1  I172

M_C_DQ<56>      @BASEBOARD_FAB2_LIB.BASEBOARD_FAB2(SCH_1):M_C_DQ<56>
  J4G3   275  DQ<57>  SCONN288_H44441004_PIP  I111
  J6U2   130  DQ<56>  SCONN288_H44441003_PIP  I111
  U5D1   AD25  DDR2_DQ<56>  SKX_EXT_B_BGA1  I172

M_C_DQ<57>      @BASEBOARD_FAB2_LIB.BASEBOARD_FAB2(SCH_1):M_C_DQ<57>
  J4G3   130  DQ<56>  SCONN288_H44441004_PIP  I111
  J6U2   275  DQ<57>  SCONN288_H44441003_PIP  I111
  U5D1   AH25  DDR2_DQ<57>  SKX_EXT_B_BGA1  I172

M_C_DQ<58>      @BASEBOARD_FAB2_LIB.BASEBOARD_FAB2(SCH_1):M_C_DQ<58>
  J4G3   282  DQ<59>  SCONN288_H44441004_PIP  I111
  J6U2   137  DQ<58>  SCONN288_H44441003_PIP  I111
  U5D1   AE22  DDR2_DQ<58>  SKX_EXT_B_BGA1  I172

M_C_DQ<59>      @BASEBOARD_FAB2_LIB.BASEBOARD_FAB2(SCH_1):M_C_DQ<59>
  J4G3   137  DQ<58>  SCONN288_H44441004_PIP  I111
  J6U2   282  DQ<59>  SCONN288_H44441003_PIP  I111
  U5D1   AG22  DDR2_DQ<59>  SKX_EXT_B_BGA1  I172

M_C_DQ<60>      @BASEBOARD_FAB2_LIB.BASEBOARD_FAB2(SCH_1):M_C_DQ<60>
  J4G3   273  DQ<61>  SCONN288_H44441004_PIP  I111
  J6U2   128  DQ<60>  SCONN288_H44441003_PIP  I111
  U5D1   AE26  DDR2_DQ<60>  SKX_EXT_B_BGA1  I172

M_C_DQ<61>      @BASEBOARD_FAB2_LIB.BASEBOARD_FAB2(SCH_1):M_C_DQ<61>
  J4G3   128  DQ<60>  SCONN288_H44441004_PIP  I111
  J6U2   273  DQ<61>  SCONN288_H44441003_PIP  I111
  U5D1   AG26  DDR2_DQ<61>  SKX_EXT_B_BGA1  I172

M_C_DQ<62>      @BASEBOARD_FAB2_LIB.BASEBOARD_FAB2(SCH_1):M_C_DQ<62>
  J4G3   280  DQ<63>  SCONN288_H44441004_PIP  I111
  J6U2   135  DQ<62>  SCONN288_H44441003_PIP  I111
  U5D1   AD23  DDR2_DQ<62>  SKX_EXT_B_BGA1  I172

M_C_DQ<63>      @BASEBOARD_FAB2_LIB.BASEBOARD_FAB2(SCH_1):M_C_DQ<63>
  J4G3   135  DQ<62>  SCONN288_H44441004_PIP  I111
  J6U2   280  DQ<63>  SCONN288_H44441003_PIP  I111
  U5D1   AH23  DDR2_DQ<63>  SKX_EXT_B_BGA1  I172

M_C_DQS_DN<0>   @BASEBOARD_FAB2_LIB.BASEBOARD_FAB2(SCH_1):M_C_DQS_DN<0>
  J4G3   152  DQS0N  SCONN288_H44441004_PIP  I61
  J6U2   152  DQS0N  SCONN288_H44441003_PIP  I61
  U5D1   AL74  DDR2_DQS_DN<0>  SKX_EXT_B_BGA1  I172

M_C_DQS_DN<1>   @BASEBOARD_FAB2_LIB.BASEBOARD_FAB2(SCH_1):M_C_DQS_DN<1>
  J4G3   163  DQS1N  SCONN288_H44441004_PIP  I61
  J6U2   163  DQS1N  SCONN288_H44441003_PIP  I61
  U5D1   AA74  DDR2_DQS_DN<1>  SKX_EXT_B_BGA1  I172

M_C_DQS_DN<2>   @BASEBOARD_FAB2_LIB.BASEBOARD_FAB2(SCH_1):M_C_DQS_DN<2>
  J4G3   174  DQS2N  SCONN288_H44441004_PIP  I61
  J6U2   174  DQS2N  SCONN288_H44441003_PIP  I61
  U5D1   Y69  DDR2_DQS_DN<2>  SKX_EXT_B_BGA1  I172

M_C_DQS_DN<3>   @BASEBOARD_FAB2_LIB.BASEBOARD_FAB2(SCH_1):M_C_DQS_DN<3>
  J4G3   185  DQS3N  SCONN288_H44441004_PIP  I61
  J6U2   185  DQS3N  SCONN288_H44441003_PIP  I61
  U5D1   AU66  DDR2_DQS_DN<3>  SKX_EXT_B_BGA1  I172

M_C_DQS_DN<4>   @BASEBOARD_FAB2_LIB.BASEBOARD_FAB2(SCH_1):M_C_DQS_DN<4>
  J4G3   244  DQS4N  SCONN288_H44441004_PIP  I61
  J6U2   244  DQS4N  SCONN288_H44441003_PIP  I61
  U5D1   AB39  DDR2_DQS_DN<4>  SKX_EXT_B_BGA1  I172

M_C_DQS_DN<5>   @BASEBOARD_FAB2_LIB.BASEBOARD_FAB2(SCH_1):M_C_DQS_DN<5>
  J4G3   255  DQS5N  SCONN288_H44441004_PIP  I61
  J6U2   255  DQS5N  SCONN288_H44441003_PIP  I61
  U5D1   AB33  DDR2_DQS_DN<5>  SKX_EXT_B_BGA1  I172

M_C_DQS_DN<6>   @BASEBOARD_FAB2_LIB.BASEBOARD_FAB2(SCH_1):M_C_DQS_DN<6>
  J4G3   266  DQS6N  SCONN288_H44441004_PIP  I61
  J6U2   266  DQS6N  SCONN288_H44441003_PIP  I61
  U5D1   AJ30  DDR2_DQS_DN<6>  SKX_EXT_B_BGA1  I172

M_C_DQS_DN<7>   @BASEBOARD_FAB2_LIB.BASEBOARD_FAB2(SCH_1):M_C_DQS_DN<7>
  J4G3   277  DQS7N  SCONN288_H44441004_PIP  I61
  J6U2   277  DQS7N  SCONN288_H44441003_PIP  I61
  U5D1   AJ24  DDR2_DQS_DN<7>  SKX_EXT_B_BGA1  I172

M_C_DQS_DN<8>   @BASEBOARD_FAB2_LIB.BASEBOARD_FAB2(SCH_1):M_C_DQS_DN<8>
  J4G3   196  DQS8N  SCONN288_H44441004_PIP  I61
  J6U2   196  DQS8N  SCONN288_H44441003_PIP  I61
  U5D1   BB71  DDR2_DQS_DN<8>  SKX_EXT_B_BGA1  I172

M_C_DQS_DN<9>   @BASEBOARD_FAB2_LIB.BASEBOARD_FAB2(SCH_1):M_C_DQS_DN<9>
  J4G3     8  DQS9N  SCONN288_H44441004_PIP  I61
  J6U2     8  DQS9N  SCONN288_H44441003_PIP  I61
  U5D1   AP77  DDR2_DQS_DN<9>  SKX_EXT_B_BGA1  I172

M_C_DQS_DN<10>   @BASEBOARD_FAB2_LIB.BASEBOARD_FAB2(SCH_1):M_C_DQS_DN<10>
  J4G3    19  DQS10N  SCONN288_H44441004_PIP  I61
  J6U2    19  DQS10N  SCONN288_H44441003_PIP  I61
  U5D1   AD77  DDR2_DQS_DN<10>  SKX_EXT_B_BGA1  I172

M_C_DQS_DN<11>   @BASEBOARD_FAB2_LIB.BASEBOARD_FAB2(SCH_1):M_C_DQS_DN<11>
  J4G3    30  DQS11N  SCONN288_H44441004_PIP  I61
  J6U2    30  DQS11N  SCONN288_H44441003_PIP  I61
  U5D1   U72  DDR2_DQS_DN<11>  SKX_EXT_B_BGA1  I172

M_C_DQS_DN<12>   @BASEBOARD_FAB2_LIB.BASEBOARD_FAB2(SCH_1):M_C_DQS_DN<12>
  J4G3    41  DQS12N  SCONN288_H44441004_PIP  I61
  J6U2    41  DQS12N  SCONN288_H44441003_PIP  I61
  U5D1   AL66  DDR2_DQS_DN<12>  SKX_EXT_B_BGA1  I172

M_C_DQS_DN<13>   @BASEBOARD_FAB2_LIB.BASEBOARD_FAB2(SCH_1):M_C_DQS_DN<13>
  J4G3   100  DQS13N  SCONN288_H44441004_PIP  I61
  J6U2   100  DQS13N  SCONN288_H44441003_PIP  I61
  U5D1   T39  DDR2_DQS_DN<13>  SKX_EXT_B_BGA1  I172

M_C_DQS_DN<14>   @BASEBOARD_FAB2_LIB.BASEBOARD_FAB2(SCH_1):M_C_DQS_DN<14>
  J4G3   111  DQS14N  SCONN288_H44441004_PIP  I61
  J6U2   111  DQS14N  SCONN288_H44441003_PIP  I61
  U5D1   T33  DDR2_DQS_DN<14>  SKX_EXT_B_BGA1  I172

M_C_DQS_DN<15>   @BASEBOARD_FAB2_LIB.BASEBOARD_FAB2(SCH_1):M_C_DQS_DN<15>
  J4G3   122  DQS15N  SCONN288_H44441004_PIP  I61
  J6U2   122  DQS15N  SCONN288_H44441003_PIP  I61
  U5D1   AC30  DDR2_DQS_DN<15>  SKX_EXT_B_BGA1  I172

M_C_DQS_DN<16>   @BASEBOARD_FAB2_LIB.BASEBOARD_FAB2(SCH_1):M_C_DQS_DN<16>
  J4G3   133  DQS16N  SCONN288_H44441004_PIP  I61
  J6U2   133  DQS16N  SCONN288_H44441003_PIP  I61
  U5D1   AC24  DDR2_DQS_DN<16>  SKX_EXT_B_BGA1  I172

M_C_DQS_DN<17>   @BASEBOARD_FAB2_LIB.BASEBOARD_FAB2(SCH_1):M_C_DQS_DN<17>
  J4G3    52  DQS17N  SCONN288_H44441004_PIP  I61
  J6U2    52  DQS17N  SCONN288_H44441003_PIP  I61
  U5D1   AT71  DDR2_DQS_DN<17>  SKX_EXT_B_BGA1  I172

M_C_DQS_DP<0>   @BASEBOARD_FAB2_LIB.BASEBOARD_FAB2(SCH_1):M_C_DQS_DP<0>
  J4G3   153  DQS0P  SCONN288_H44441004_PIP  I61
  J6U2   153  DQS0P  SCONN288_H44441003_PIP  I61
  U5D1   AM75  DDR2_DQS_DP<0>  SKX_EXT_B_BGA1  I172

M_C_DQS_DP<1>   @BASEBOARD_FAB2_LIB.BASEBOARD_FAB2(SCH_1):M_C_DQS_DP<1>
  J4G3   164  DQS1P  SCONN288_H44441004_PIP  I61
  J6U2   164  DQS1P  SCONN288_H44441003_PIP  I61
  U5D1   AB75  DDR2_DQS_DP<1>  SKX_EXT_B_BGA1  I172

M_C_DQS_DP<2>   @BASEBOARD_FAB2_LIB.BASEBOARD_FAB2(SCH_1):M_C_DQS_DP<2>
  J4G3   175  DQS2P  SCONN288_H44441004_PIP  I61
  J6U2   175  DQS2P  SCONN288_H44441003_PIP  I61
  U5D1   W70  DDR2_DQS_DP<2>  SKX_EXT_B_BGA1  I172

M_C_DQS_DP<3>   @BASEBOARD_FAB2_LIB.BASEBOARD_FAB2(SCH_1):M_C_DQS_DP<3>
  J4G3   186  DQS3P  SCONN288_H44441004_PIP  I61
  J6U2   186  DQS3P  SCONN288_H44441003_PIP  I61
  U5D1   AR66  DDR2_DQS_DP<3>  SKX_EXT_B_BGA1  I172

M_C_DQS_DP<4>   @BASEBOARD_FAB2_LIB.BASEBOARD_FAB2(SCH_1):M_C_DQS_DP<4>
  J4G3   245  DQS4P  SCONN288_H44441004_PIP  I61
  J6U2   245  DQS4P  SCONN288_H44441003_PIP  I61
  U5D1   Y39  DDR2_DQS_DP<4>  SKX_EXT_B_BGA1  I172

M_C_DQS_DP<5>   @BASEBOARD_FAB2_LIB.BASEBOARD_FAB2(SCH_1):M_C_DQS_DP<5>
  J4G3   256  DQS5P  SCONN288_H44441004_PIP  I61
  J6U2   256  DQS5P  SCONN288_H44441003_PIP  I61
  U5D1   Y33  DDR2_DQS_DP<5>  SKX_EXT_B_BGA1  I172

M_C_DQS_DP<6>   @BASEBOARD_FAB2_LIB.BASEBOARD_FAB2(SCH_1):M_C_DQS_DP<6>
  J4G3   267  DQS6P  SCONN288_H44441004_PIP  I61
  J6U2   267  DQS6P  SCONN288_H44441003_PIP  I61
  U5D1   AG30  DDR2_DQS_DP<6>  SKX_EXT_B_BGA1  I172

M_C_DQS_DP<7>   @BASEBOARD_FAB2_LIB.BASEBOARD_FAB2(SCH_1):M_C_DQS_DP<7>
  J4G3   278  DQS7P  SCONN288_H44441004_PIP  I61
  J6U2   278  DQS7P  SCONN288_H44441003_PIP  I61
  U5D1   AG24  DDR2_DQS_DP<7>  SKX_EXT_B_BGA1  I172

M_C_DQS_DP<8>   @BASEBOARD_FAB2_LIB.BASEBOARD_FAB2(SCH_1):M_C_DQS_DP<8>
  J4G3   197  DQS8P  SCONN288_H44441004_PIP  I61
  J6U2   197  DQS8P  SCONN288_H44441003_PIP  I61
  U5D1   AY71  DDR2_DQS_DP<8>  SKX_EXT_B_BGA1  I172

M_C_DQS_DP<9>   @BASEBOARD_FAB2_LIB.BASEBOARD_FAB2(SCH_1):M_C_DQS_DP<9>
  J4G3     7  DQS9P  SCONN288_H44441004_PIP  I61
  J6U2     7  DQS9P  SCONN288_H44441003_PIP  I61
  U5D1   AN76  DDR2_DQS_DP<9>  SKX_EXT_B_BGA1  I172

M_C_DQS_DP<10>   @BASEBOARD_FAB2_LIB.BASEBOARD_FAB2(SCH_1):M_C_DQS_DP<10>
  J4G3    18  DQS10P  SCONN288_H44441004_PIP  I61
  J6U2    18  DQS10P  SCONN288_H44441003_PIP  I61
  U5D1   AC76  DDR2_DQS_DP<10>  SKX_EXT_B_BGA1  I172

M_C_DQS_DP<11>   @BASEBOARD_FAB2_LIB.BASEBOARD_FAB2(SCH_1):M_C_DQS_DP<11>
  J4G3    29  DQS11P  SCONN288_H44441004_PIP  I61
  J6U2    29  DQS11P  SCONN288_H44441003_PIP  I61
  U5D1   V71  DDR2_DQS_DP<11>  SKX_EXT_B_BGA1  I172

M_C_DQS_DP<12>   @BASEBOARD_FAB2_LIB.BASEBOARD_FAB2(SCH_1):M_C_DQS_DP<12>
  J4G3    40  DQS12P  SCONN288_H44441004_PIP  I61
  J6U2    40  DQS12P  SCONN288_H44441003_PIP  I61
  U5D1   AN66  DDR2_DQS_DP<12>  SKX_EXT_B_BGA1  I172

M_C_DQS_DP<13>   @BASEBOARD_FAB2_LIB.BASEBOARD_FAB2(SCH_1):M_C_DQS_DP<13>
  J4G3    99  DQS13P  SCONN288_H44441004_PIP  I61
  J6U2    99  DQS13P  SCONN288_H44441003_PIP  I61
  U5D1   V39  DDR2_DQS_DP<13>  SKX_EXT_B_BGA1  I172

M_C_DQS_DP<14>   @BASEBOARD_FAB2_LIB.BASEBOARD_FAB2(SCH_1):M_C_DQS_DP<14>
  J4G3   110  DQS14P  SCONN288_H44441004_PIP  I61
  J6U2   110  DQS14P  SCONN288_H44441003_PIP  I61
  U5D1   V33  DDR2_DQS_DP<14>  SKX_EXT_B_BGA1  I172

M_C_DQS_DP<15>   @BASEBOARD_FAB2_LIB.BASEBOARD_FAB2(SCH_1):M_C_DQS_DP<15>
  J4G3   121  DQS15P  SCONN288_H44441004_PIP  I61
  J6U2   121  DQS15P  SCONN288_H44441003_PIP  I61
  U5D1   AE30  DDR2_DQS_DP<15>  SKX_EXT_B_BGA1  I172

M_C_DQS_DP<16>   @BASEBOARD_FAB2_LIB.BASEBOARD_FAB2(SCH_1):M_C_DQS_DP<16>
  J4G3   132  DQS16P  SCONN288_H44441004_PIP  I61
  J6U2   132  DQS16P  SCONN288_H44441003_PIP  I61
  U5D1   AE24  DDR2_DQS_DP<16>  SKX_EXT_B_BGA1  I172

M_C_DQS_DP<17>   @BASEBOARD_FAB2_LIB.BASEBOARD_FAB2(SCH_1):M_C_DQS_DP<17>
  J4G3    51  DQS17P  SCONN288_H44441004_PIP  I61
  J6U2    51  DQS17P  SCONN288_H44441003_PIP  I61
  U5D1   AV71  DDR2_DQS_DP<17>  SKX_EXT_B_BGA1  I172

M_C_ECC<0>      @BASEBOARD_FAB2_LIB.BASEBOARD_FAB2(SCH_1):M_C_ECC<0>
  J4G3   194  CB<1>  SCONN288_H44441004_PIP  I111
  J6U2    49  CB<0>  SCONN288_H44441003_PIP  I111
  U5D1   AU72  DDR2_ECC<0>  SKX_EXT_B_BGA1  I172

M_C_ECC<1>      @BASEBOARD_FAB2_LIB.BASEBOARD_FAB2(SCH_1):M_C_ECC<1>
  J4G3    49  CB<0>  SCONN288_H44441004_PIP  I111
  J6U2   194  CB<1>  SCONN288_H44441003_PIP  I111
  U5D1   BA72  DDR2_ECC<1>  SKX_EXT_B_BGA1  I172

M_C_ECC<2>      @BASEBOARD_FAB2_LIB.BASEBOARD_FAB2(SCH_1):M_C_ECC<2>
  J4G3   201  CB<3>  SCONN288_H44441004_PIP  I111
  J6U2    56  CB<2>  SCONN288_H44441003_PIP  I111
  U5D1   AV69  DDR2_ECC<2>  SKX_EXT_B_BGA1  I172

M_C_ECC<3>      @BASEBOARD_FAB2_LIB.BASEBOARD_FAB2(SCH_1):M_C_ECC<3>
  J4G3    56  CB<2>  SCONN288_H44441004_PIP  I111
  J6U2   201  CB<3>  SCONN288_H44441003_PIP  I111
  U5D1   AY69  DDR2_ECC<3>  SKX_EXT_B_BGA1  I172

M_C_ECC<4>      @BASEBOARD_FAB2_LIB.BASEBOARD_FAB2(SCH_1):M_C_ECC<4>
  J4G3   192  CB<5>  SCONN288_H44441004_PIP  I111
  J6U2    47  CB<4>  SCONN288_H44441003_PIP  I111
  U5D1   AV73  DDR2_ECC<4>  SKX_EXT_B_BGA1  I172

M_C_ECC<5>      @BASEBOARD_FAB2_LIB.BASEBOARD_FAB2(SCH_1):M_C_ECC<5>
  J4G3    47  CB<4>  SCONN288_H44441004_PIP  I111
  J6U2   192  CB<5>  SCONN288_H44441003_PIP  I111
  U5D1   AY73  DDR2_ECC<5>  SKX_EXT_B_BGA1  I172

M_C_ECC<6>      @BASEBOARD_FAB2_LIB.BASEBOARD_FAB2(SCH_1):M_C_ECC<6>
  J4G3   199  CB<7>  SCONN288_H44441004_PIP  I111
  J6U2    54  CB<6>  SCONN288_H44441003_PIP  I111
  U5D1   AU70  DDR2_ECC<6>  SKX_EXT_B_BGA1  I172

M_C_ECC<7>      @BASEBOARD_FAB2_LIB.BASEBOARD_FAB2(SCH_1):M_C_ECC<7>
  J4G3    54  CB<6>  SCONN288_H44441004_PIP  I111
  J6U2   199  CB<7>  SCONN288_H44441003_PIP  I111
  U5D1   BA70  DDR2_ECC<7>  SKX_EXT_B_BGA1  I172

M_C_MA<0>       @BASEBOARD_FAB2_LIB.BASEBOARD_FAB2(SCH_1):M_C_MA<0>
  J4G3    79     A0  SCONN288_H44441004_PIP  I111
  J6U2    79     A0  SCONN288_H44441003_PIP  I111
  U5D1   AB53  DDR2_MA<0>  SKX_EXT_B_BGA1  I172

M_C_MA<1>       @BASEBOARD_FAB2_LIB.BASEBOARD_FAB2(SCH_1):M_C_MA<1>
  J4G3    72     A1  SCONN288_H44441004_PIP  I111
  J6U2    72     A1  SCONN288_H44441003_PIP  I111
  U5D1   AE58  DDR2_MA<1>  SKX_EXT_B_BGA1  I172

M_C_MA<2>       @BASEBOARD_FAB2_LIB.BASEBOARD_FAB2(SCH_1):M_C_MA<2>
  J4G3   216     A2  SCONN288_H44441004_PIP  I111
  J6U2   216     A2  SCONN288_H44441003_PIP  I111
  U5D1   AD57  DDR2_MA<2>  SKX_EXT_B_BGA1  I172

M_C_MA<3>       @BASEBOARD_FAB2_LIB.BASEBOARD_FAB2(SCH_1):M_C_MA<3>
  J4G3    71     A3  SCONN288_H44441004_PIP  I111
  J6U2    71     A3  SCONN288_H44441003_PIP  I111
  U5D1   W58  DDR2_MA<3>  SKX_EXT_B_BGA1  I172

M_C_MA<4>       @BASEBOARD_FAB2_LIB.BASEBOARD_FAB2(SCH_1):M_C_MA<4>
  J4G3   214     A4  SCONN288_H44441004_PIP  I111
  J6U2   214     A4  SCONN288_H44441003_PIP  I111
  U5D1   AA58  DDR2_MA<4>  SKX_EXT_B_BGA1  I172

M_C_MA<5>       @BASEBOARD_FAB2_LIB.BASEBOARD_FAB2(SCH_1):M_C_MA<5>
  J4G3   213     A5  SCONN288_H44441004_PIP  I111
  J6U2   213     A5  SCONN288_H44441003_PIP  I111
  U5D1   V59  DDR2_MA<5>  SKX_EXT_B_BGA1  I172

M_C_MA<6>       @BASEBOARD_FAB2_LIB.BASEBOARD_FAB2(SCH_1):M_C_MA<6>
  J4G3    69     A6  SCONN288_H44441004_PIP  I111
  J6U2    69     A6  SCONN288_H44441003_PIP  I111
  U5D1   AB59  DDR2_MA<6>  SKX_EXT_B_BGA1  I172

M_C_MA<7>       @BASEBOARD_FAB2_LIB.BASEBOARD_FAB2(SCH_1):M_C_MA<7>
  J4G3   211     A7  SCONN288_H44441004_PIP  I111
  J6U2   211     A7  SCONN288_H44441003_PIP  I111
  U5D1   AE60  DDR2_MA<7>  SKX_EXT_B_BGA1  I172

M_C_MA<8>       @BASEBOARD_FAB2_LIB.BASEBOARD_FAB2(SCH_1):M_C_MA<8>
  J4G3    68     A8  SCONN288_H44441004_PIP  I111
  J6U2    68     A8  SCONN288_H44441003_PIP  I111
  U5D1   AD59  DDR2_MA<8>  SKX_EXT_B_BGA1  I172

M_C_MA<9>       @BASEBOARD_FAB2_LIB.BASEBOARD_FAB2(SCH_1):M_C_MA<9>
  J4G3    66     A9  SCONN288_H44441004_PIP  I111
  J6U2    66     A9  SCONN288_H44441003_PIP  I111
  U5D1   AG58  DDR2_MA<9>  SKX_EXT_B_BGA1  I172

M_C_MA<10>      @BASEBOARD_FAB2_LIB.BASEBOARD_FAB2(SCH_1):M_C_MA<10>
  J4G3   225    A10  SCONN288_H44441004_PIP  I111
  J6U2   225    A10  SCONN288_H44441003_PIP  I111
  U5D1   AD55  DDR2_MA<10>  SKX_EXT_B_BGA1  I172

M_C_MA<11>      @BASEBOARD_FAB2_LIB.BASEBOARD_FAB2(SCH_1):M_C_MA<11>
  J4G3   210    A11  SCONN288_H44441004_PIP  I111
  J6U2   210    A11  SCONN288_H44441003_PIP  I111
  U5D1   AG60  DDR2_MA<11>  SKX_EXT_B_BGA1  I172

M_C_MA<12>      @BASEBOARD_FAB2_LIB.BASEBOARD_FAB2(SCH_1):M_C_MA<12>
  J4G3    65    A12  SCONN288_H44441004_PIP  I111
  J6U2    65    A12  SCONN288_H44441003_PIP  I111
  U5D1   AG62  DDR2_MA<12>  SKX_EXT_B_BGA1  I172

M_C_MA<13>      @BASEBOARD_FAB2_LIB.BASEBOARD_FAB2(SCH_1):M_C_MA<13>
  J4G3   232    A13  SCONN288_H44441004_PIP  I111
  J6U2   232    A13  SCONN288_H44441003_PIP  I111
  U5D1   AD53  DDR2_MA<13>  SKX_EXT_B_BGA1  I172

M_C_MA<14>      @BASEBOARD_FAB2_LIB.BASEBOARD_FAB2(SCH_1):M_C_MA<14>
  J4G3   228  A14_WE_N  SCONN288_H44441004_PIP  I111
  J6U2   228  A14_WE_N  SCONN288_H44441003_PIP  I111
  U5D1   W50  DDR2_MA<14>  SKX_EXT_B_BGA1  I172

M_C_MA<15>      @BASEBOARD_FAB2_LIB.BASEBOARD_FAB2(SCH_1):M_C_MA<15>
  J4G3    86  A15_CAS_N  SCONN288_H44441004_PIP  I111
  J6U2    86  A15_CAS_N  SCONN288_H44441003_PIP  I111
  U5D1   AE54  DDR2_MA<15>  SKX_EXT_B_BGA1  I172

M_C_MA<16>      @BASEBOARD_FAB2_LIB.BASEBOARD_FAB2(SCH_1):M_C_MA<16>
  J4G3    82  A16_RAS_N  SCONN288_H44441004_PIP  I111
  J6U2    82  A16_RAS_N  SCONN288_H44441003_PIP  I111
  U5D1   AA52  DDR2_MA<16>  SKX_EXT_B_BGA1  I172

M_C_MA<17>      @BASEBOARD_FAB2_LIB.BASEBOARD_FAB2(SCH_1):M_C_MA<17>
  J4G3   234    A17  SCONN288_H44441004_PIP  I111
  J6U2   234    A17  SCONN288_H44441003_PIP  I111
  U5D1   AC46  DDR2_MA<17>  SKX_EXT_B_BGA1  I172

M_C_ODT<0>      @BASEBOARD_FAB2_LIB.BASEBOARD_FAB2(SCH_1):M_C_ODT<0>
  J4G3    87  ODT<0>  SCONN288_H44441004_PIP  I111
  U5D1   AA50  DDR2_ODT<0>  SKX_EXT_B_BGA1  I172

M_C_ODT<1>      @BASEBOARD_FAB2_LIB.BASEBOARD_FAB2(SCH_1):M_C_ODT<1>
  J4G3    91  ODT<1>  SCONN288_H44441004_PIP  I111
  U5D1   AA48  DDR2_ODT<1>  SKX_EXT_B_BGA1  I172

M_C_ODT<2>      @BASEBOARD_FAB2_LIB.BASEBOARD_FAB2(SCH_1):M_C_ODT<2>
  J6U2    87  ODT<0>  SCONN288_H44441003_PIP  I111
  U5D1   V49  DDR2_ODT<2>  SKX_EXT_B_BGA1  I172

M_C_ODT<3>      @BASEBOARD_FAB2_LIB.BASEBOARD_FAB2(SCH_1):M_C_ODT<3>
  J6U2    91  ODT<1>  SCONN288_H44441003_PIP  I111
  U5D1   AB47  DDR2_ODT<3>  SKX_EXT_B_BGA1  I172

M_C_PAR         @BASEBOARD_FAB2_LIB.BASEBOARD_FAB2(SCH_1):M_C_PAR
  J4G3   222    PAR  SCONN288_H44441004_PIP  I111
  J6U2   222    PAR  SCONN288_H44441003_PIP  I111
  U5D1   V53  DDR2_PAR  SKX_EXT_B_BGA1  I172

M_C_VREF        @BASEBOARD_FAB2_LIB.BASEBOARD_FAB2(SCH_1):M_C_VREF
  C4G19    1      A  CAP_A       I188
  C6U17    1      A  CAP_A       I176
  J4G3   146  VREFCA  SCONN288_H44441004_PIP  I111
  J6U2   146  VREFCA  SCONN288_H44441003_PIP  I111
  R4G20    2      B  RES         I50
  R4G21    2      B  RES         I46
  R4G22    1      A  RES         I48

M_DEF_RST_N     @BASEBOARD_FAB2_LIB.BASEBOARD_FAB2(SCH_1):M_DEF_RST_N
  J4A1    58  RESET_N  SCONN288_H44441004_PIP  I111
  J4A2    58  RESET_N  SCONN288_H44441004_PIP  I111
  J4B1    58  RESET_N  SCONN288_H44441004_PIP  I111
  J6L1    58  RESET_N  SCONN288_H44441003_PIP  I111
  J6L2    58  RESET_N  SCONN288_H44441003_PIP  I12
  J6M1    58  RESET_N  SCONN288_H44441003_PIP  I158
  U5D1   DV63  DDR345_RESET_N  SKX_EXT_B_BGA1  I259

M_D_ACT_N       @BASEBOARD_FAB2_LIB.BASEBOARD_FAB2(SCH_1):M_D_ACT_N
  J4B1    62  ACT_N  SCONN288_H44441004_PIP  I111
  J6M1    62  ACT_N  SCONN288_H44441003_PIP  I158
  U5D1   DW60  DDR3_ACT_N  SKX_EXT_B_BGA1  I172

M_D_ALERT_N     @BASEBOARD_FAB2_LIB.BASEBOARD_FAB2(SCH_1):M_D_ALERT_N
  J4B1   208  ALERT_N  SCONN288_H44441004_PIP  I111
  J6M1   208  ALERT_N  SCONN288_H44441003_PIP  I158
  U5D1   ED63  DDR3_ALERT_N  SKX_EXT_B_BGA1  I172

M_D_BA<0>       @BASEBOARD_FAB2_LIB.BASEBOARD_FAB2(SCH_1):M_D_BA<0>
  J4B1    81  BA<0>  SCONN288_H44441004_PIP  I111
  J6M1    81  BA<0>  SCONN288_H44441003_PIP  I158
  U5D1   EE52  DDR3_BA<0>  SKX_EXT_B_BGA1  I172

M_D_BA<1>       @BASEBOARD_FAB2_LIB.BASEBOARD_FAB2(SCH_1):M_D_BA<1>
  J4B1   224  BA<1>  SCONN288_H44441004_PIP  I111
  J6M1   224  BA<1>  SCONN288_H44441003_PIP  I158
  U5D1   EA54  DDR3_BA<1>  SKX_EXT_B_BGA1  I172

M_D_BG<0>       @BASEBOARD_FAB2_LIB.BASEBOARD_FAB2(SCH_1):M_D_BG<0>
  J4B1    63  BG<0>  SCONN288_H44441004_PIP  I111
  J6M1    63  BG<0>  SCONN288_H44441003_PIP  I158
  U5D1   ED61  DDR3_BG<0>  SKX_EXT_B_BGA1  I172

M_D_BG<1>       @BASEBOARD_FAB2_LIB.BASEBOARD_FAB2(SCH_1):M_D_BG<1>
  J4B1   207  BG<1>  SCONN288_H44441004_PIP  I111
  J6M1   207  BG<1>  SCONN288_H44441003_PIP  I158
  U5D1   DW62  DDR3_BG<1>  SKX_EXT_B_BGA1  I172

M_D_C<2>        @BASEBOARD_FAB2_LIB.BASEBOARD_FAB2(SCH_1):M_D_C<2>
  J4B1   235   C<2>  SCONN288_H44441004_PIP  I111
  J6M1   235   C<2>  SCONN288_H44441003_PIP  I158
  U5D1   DV47  DDR3_CID<2>  SKX_EXT_B_BGA1  I172

M_D_CKE<0>      @BASEBOARD_FAB2_LIB.BASEBOARD_FAB2(SCH_1):M_D_CKE<0>
  J4B1    60  CKE<0>  SCONN288_H44441004_PIP  I111
  U5D1   EE62  DDR3_CKE<0>  SKX_EXT_B_BGA1  I172

M_D_CKE<1>      @BASEBOARD_FAB2_LIB.BASEBOARD_FAB2(SCH_1):M_D_CKE<1>
  J4B1   203  CKE<1>  SCONN288_H44441004_PIP  I111
  U5D1   EF63  DDR3_CKE<1>  SKX_EXT_B_BGA1  I172

M_D_CKE<2>      @BASEBOARD_FAB2_LIB.BASEBOARD_FAB2(SCH_1):M_D_CKE<2>
  J6M1    60  CKE<0>  SCONN288_H44441003_PIP  I158
  U5D1   EA62  DDR3_CKE<2>  SKX_EXT_B_BGA1  I172

M_D_CKE<3>      @BASEBOARD_FAB2_LIB.BASEBOARD_FAB2(SCH_1):M_D_CKE<3>
  J6M1   203  CKE<1>  SCONN288_H44441003_PIP  I158
  U5D1   EB63  DDR3_CKE<3>  SKX_EXT_B_BGA1  I172

M_D_CLK_DN<0>   @BASEBOARD_FAB2_LIB.BASEBOARD_FAB2(SCH_1):M_D_CLK_DN<0>
  J4B1    75   CK0N  SCONN288_H44441004_PIP  I111
  U5D1   ED55  DDR3_CLK_DN<0>  SKX_EXT_B_BGA1  I172

M_D_CLK_DN<1>   @BASEBOARD_FAB2_LIB.BASEBOARD_FAB2(SCH_1):M_D_CLK_DN<1>
  J4B1   219   CK1N  SCONN288_H44441004_PIP  I111
  U5D1   EF55  DDR3_CLK_DN<1>  SKX_EXT_B_BGA1  I172

M_D_CLK_DN<2>   @BASEBOARD_FAB2_LIB.BASEBOARD_FAB2(SCH_1):M_D_CLK_DN<2>
  J6M1    75   CK0N  SCONN288_H44441003_PIP  I158
  U5D1   DW56  DDR3_CLK_DN<2>  SKX_EXT_B_BGA1  I172

M_D_CLK_DN<3>   @BASEBOARD_FAB2_LIB.BASEBOARD_FAB2(SCH_1):M_D_CLK_DN<3>
  J6M1   219   CK1N  SCONN288_H44441003_PIP  I158
  U5D1   EF57  DDR3_CLK_DN<3>  SKX_EXT_B_BGA1  I172

M_D_CLK_DP<0>   @BASEBOARD_FAB2_LIB.BASEBOARD_FAB2(SCH_1):M_D_CLK_DP<0>
  J4B1    74   CK0P  SCONN288_H44441004_PIP  I111
  U5D1   EB55  DDR3_CLK_DP<0>  SKX_EXT_B_BGA1  I172

M_D_CLK_DP<1>   @BASEBOARD_FAB2_LIB.BASEBOARD_FAB2(SCH_1):M_D_CLK_DP<1>
  J4B1   218   CK1P  SCONN288_H44441004_PIP  I111
  U5D1   EE54  DDR3_CLK_DP<1>  SKX_EXT_B_BGA1  I172

M_D_CLK_DP<2>   @BASEBOARD_FAB2_LIB.BASEBOARD_FAB2(SCH_1):M_D_CLK_DP<2>
  J6M1    74   CK0P  SCONN288_H44441003_PIP  I158
  U5D1   EA56  DDR3_CLK_DP<2>  SKX_EXT_B_BGA1  I172

M_D_CLK_DP<3>   @BASEBOARD_FAB2_LIB.BASEBOARD_FAB2(SCH_1):M_D_CLK_DP<3>
  J6M1   218   CK1P  SCONN288_H44441003_PIP  I158
  U5D1   EE56  DDR3_CLK_DP<3>  SKX_EXT_B_BGA1  I172

M_D_CPU_VREF    @BASEBOARD_FAB2_LIB.BASEBOARD_FAB2(SCH_1):M_D_CPU_VREF
  C6M2     1      A  CAP_A       I33
  R6M2     1      A  RES         I14
  U5D1   CP61  DDR3_CAVREF  SKX_EXT_B_BGA1  I259

M_D_CS_N<0>     @BASEBOARD_FAB2_LIB.BASEBOARD_FAB2(SCH_1):M_D_CS_N<0>
  J4B1    84   S0_N  SCONN288_H44441004_PIP  I111
  U5D1   EF51  DDR3_CS_N<0>  SKX_EXT_B_BGA1  I172

M_D_CS_N<1>     @BASEBOARD_FAB2_LIB.BASEBOARD_FAB2(SCH_1):M_D_CS_N<1>
  J4B1    89   S1_N  SCONN288_H44441004_PIP  I111
  U5D1   ED49  DDR3_CS_N<1>  SKX_EXT_B_BGA1  I172

M_D_CS_N<2>     @BASEBOARD_FAB2_LIB.BASEBOARD_FAB2(SCH_1):M_D_CS_N<2>
  J4B1    93  S2_N_C<0>  SCONN288_H44441004_PIP  I111
  U5D1   ED47  DDR3_CS_N<2>  SKX_EXT_B_BGA1  I172

M_D_CS_N<3>     @BASEBOARD_FAB2_LIB.BASEBOARD_FAB2(SCH_1):M_D_CS_N<3>
  J4B1   237  S3_N_C<1>  SCONN288_H44441004_PIP  I111
  U5D1   EB47  DDR3_CS_N<3>  SKX_EXT_B_BGA1  I172

M_D_CS_N<4>     @BASEBOARD_FAB2_LIB.BASEBOARD_FAB2(SCH_1):M_D_CS_N<4>
  J6M1    84   S0_N  SCONN288_H44441003_PIP  I158
  U5D1   EB51  DDR3_CS_N<4>  SKX_EXT_B_BGA1  I172

M_D_CS_N<5>     @BASEBOARD_FAB2_LIB.BASEBOARD_FAB2(SCH_1):M_D_CS_N<5>
  J6M1    89   S1_N  SCONN288_H44441003_PIP  I158
  U5D1   EB49  DDR3_CS_N<5>  SKX_EXT_B_BGA1  I172

M_D_CS_N<6>     @BASEBOARD_FAB2_LIB.BASEBOARD_FAB2(SCH_1):M_D_CS_N<6>
  J6M1    93  S2_N_C<0>  SCONN288_H44441003_PIP  I158
  U5D1   DV45  DDR3_CS_N<6>  SKX_EXT_B_BGA1  I172

M_D_CS_N<7>     @BASEBOARD_FAB2_LIB.BASEBOARD_FAB2(SCH_1):M_D_CS_N<7>
  J6M1   237  S3_N_C<1>  SCONN288_H44441003_PIP  I158
  U5D1   EB45  DDR3_CS_N<7>  SKX_EXT_B_BGA1  I172

M_D_DQ<0>       @BASEBOARD_FAB2_LIB.BASEBOARD_FAB2(SCH_1):M_D_DQ<0>
  J4B1   150  DQ<1>  SCONN288_H44441004_PIP  I111
  J6M1     5  DQ<0>  SCONN288_H44441003_PIP  I158
  U5D1   CN84  DDR3_DQ<0>  SKX_EXT_B_BGA1  I172

M_D_DQ<1>       @BASEBOARD_FAB2_LIB.BASEBOARD_FAB2(SCH_1):M_D_DQ<1>
  J4B1     5  DQ<0>  SCONN288_H44441004_PIP  I111
  J6M1   150  DQ<1>  SCONN288_H44441003_PIP  I158
  U5D1   CN86  DDR3_DQ<1>  SKX_EXT_B_BGA1  I172

M_D_DQ<2>       @BASEBOARD_FAB2_LIB.BASEBOARD_FAB2(SCH_1):M_D_DQ<2>
  J4B1   157  DQ<3>  SCONN288_H44441004_PIP  I111
  J6M1    12  DQ<2>  SCONN288_H44441003_PIP  I158
  U5D1   DA86  DDR3_DQ<2>  SKX_EXT_B_BGA1  I172

M_D_DQ<3>       @BASEBOARD_FAB2_LIB.BASEBOARD_FAB2(SCH_1):M_D_DQ<3>
  J4B1    12  DQ<2>  SCONN288_H44441004_PIP  I111
  J6M1   157  DQ<3>  SCONN288_H44441003_PIP  I158
  U5D1   DA84  DDR3_DQ<3>  SKX_EXT_B_BGA1  I172

M_D_DQ<4>       @BASEBOARD_FAB2_LIB.BASEBOARD_FAB2(SCH_1):M_D_DQ<4>
  J4B1   148  DQ<5>  SCONN288_H44441004_PIP  I111
  J6M1     3  DQ<4>  SCONN288_H44441003_PIP  I158
  U5D1   CL84  DDR3_DQ<4>  SKX_EXT_B_BGA1  I172

M_D_DQ<5>       @BASEBOARD_FAB2_LIB.BASEBOARD_FAB2(SCH_1):M_D_DQ<5>
  J4B1     3  DQ<4>  SCONN288_H44441004_PIP  I111
  J6M1   148  DQ<5>  SCONN288_H44441003_PIP  I158
  U5D1   CL86  DDR3_DQ<5>  SKX_EXT_B_BGA1  I172

M_D_DQ<6>       @BASEBOARD_FAB2_LIB.BASEBOARD_FAB2(SCH_1):M_D_DQ<6>
  J4B1   155  DQ<7>  SCONN288_H44441004_PIP  I111
  J6M1    10  DQ<6>  SCONN288_H44441003_PIP  I158
  U5D1   CW86  DDR3_DQ<6>  SKX_EXT_B_BGA1  I172

M_D_DQ<7>       @BASEBOARD_FAB2_LIB.BASEBOARD_FAB2(SCH_1):M_D_DQ<7>
  J4B1    10  DQ<6>  SCONN288_H44441004_PIP  I111
  J6M1   155  DQ<7>  SCONN288_H44441003_PIP  I158
  U5D1   CW84  DDR3_DQ<7>  SKX_EXT_B_BGA1  I172

M_D_DQ<8>       @BASEBOARD_FAB2_LIB.BASEBOARD_FAB2(SCH_1):M_D_DQ<8>
  J4B1   161  DQ<9>  SCONN288_H44441004_PIP  I111
  J6M1    16  DQ<8>  SCONN288_H44441003_PIP  I158
  U5D1   DG84  DDR3_DQ<8>  SKX_EXT_B_BGA1  I172

M_D_DQ<9>       @BASEBOARD_FAB2_LIB.BASEBOARD_FAB2(SCH_1):M_D_DQ<9>
  J4B1    16  DQ<8>  SCONN288_H44441004_PIP  I111
  J6M1   161  DQ<9>  SCONN288_H44441003_PIP  I158
  U5D1   DH85  DDR3_DQ<9>  SKX_EXT_B_BGA1  I172

M_D_DQ<10>      @BASEBOARD_FAB2_LIB.BASEBOARD_FAB2(SCH_1):M_D_DQ<10>
  J4B1   168  DQ<11>  SCONN288_H44441004_PIP  I111
  J6M1    23  DQ<10>  SCONN288_H44441003_PIP  I158
  U5D1   DV83  DDR3_DQ<10>  SKX_EXT_B_BGA1  I172

M_D_DQ<11>      @BASEBOARD_FAB2_LIB.BASEBOARD_FAB2(SCH_1):M_D_DQ<11>
  J4B1    23  DQ<10>  SCONN288_H44441004_PIP  I111
  J6M1   168  DQ<11>  SCONN288_H44441003_PIP  I158
  U5D1   DY83  DDR3_DQ<11>  SKX_EXT_B_BGA1  I172

M_D_DQ<12>      @BASEBOARD_FAB2_LIB.BASEBOARD_FAB2(SCH_1):M_D_DQ<12>
  J4B1   159  DQ<13>  SCONN288_H44441004_PIP  I111
  J6M1    14  DQ<12>  SCONN288_H44441003_PIP  I158
  U5D1   DD85  DDR3_DQ<12>  SKX_EXT_B_BGA1  I172

M_D_DQ<13>      @BASEBOARD_FAB2_LIB.BASEBOARD_FAB2(SCH_1):M_D_DQ<13>
  J4B1    14  DQ<12>  SCONN288_H44441004_PIP  I111
  J6M1   159  DQ<13>  SCONN288_H44441003_PIP  I158
  U5D1   DE84  DDR3_DQ<13>  SKX_EXT_B_BGA1  I172

M_D_DQ<14>      @BASEBOARD_FAB2_LIB.BASEBOARD_FAB2(SCH_1):M_D_DQ<14>
  J4B1   166  DQ<15>  SCONN288_H44441004_PIP  I111
  J6M1    21  DQ<14>  SCONN288_H44441003_PIP  I158
  U5D1   DR84  DDR3_DQ<14>  SKX_EXT_B_BGA1  I172

M_D_DQ<15>      @BASEBOARD_FAB2_LIB.BASEBOARD_FAB2(SCH_1):M_D_DQ<15>
  J4B1    21  DQ<14>  SCONN288_H44441004_PIP  I111
  J6M1   166  DQ<15>  SCONN288_H44441003_PIP  I158
  U5D1   DV85  DDR3_DQ<15>  SKX_EXT_B_BGA1  I172

M_D_DQ<16>      @BASEBOARD_FAB2_LIB.BASEBOARD_FAB2(SCH_1):M_D_DQ<16>
  J4B1   172  DQ<17>  SCONN288_H44441004_PIP  I111
  J6M1    27  DQ<16>  SCONN288_H44441003_PIP  I158
  U5D1   DM79  DDR3_DQ<16>  SKX_EXT_B_BGA1  I172

M_D_DQ<17>      @BASEBOARD_FAB2_LIB.BASEBOARD_FAB2(SCH_1):M_D_DQ<17>
  J4B1    27  DQ<16>  SCONN288_H44441004_PIP  I111
  J6M1   172  DQ<17>  SCONN288_H44441003_PIP  I158
  U5D1   DK81  DDR3_DQ<17>  SKX_EXT_B_BGA1  I172

M_D_DQ<18>      @BASEBOARD_FAB2_LIB.BASEBOARD_FAB2(SCH_1):M_D_DQ<18>
  J4B1   179  DQ<19>  SCONN288_H44441004_PIP  I111
  J6M1    34  DQ<18>  SCONN288_H44441003_PIP  I158
  U5D1   DT81  DDR3_DQ<18>  SKX_EXT_B_BGA1  I172

M_D_DQ<19>      @BASEBOARD_FAB2_LIB.BASEBOARD_FAB2(SCH_1):M_D_DQ<19>
  J4B1    34  DQ<18>  SCONN288_H44441004_PIP  I111
  J6M1   179  DQ<19>  SCONN288_H44441003_PIP  I158
  U5D1   DR82  DDR3_DQ<19>  SKX_EXT_B_BGA1  I172

M_D_DQ<20>      @BASEBOARD_FAB2_LIB.BASEBOARD_FAB2(SCH_1):M_D_DQ<20>
  J4B1   170  DQ<21>  SCONN288_H44441004_PIP  I111
  J6M1    25  DQ<20>  SCONN288_H44441003_PIP  I158
  U5D1   DK79  DDR3_DQ<20>  SKX_EXT_B_BGA1  I172

M_D_DQ<21>      @BASEBOARD_FAB2_LIB.BASEBOARD_FAB2(SCH_1):M_D_DQ<21>
  J4B1    25  DQ<20>  SCONN288_H44441004_PIP  I111
  J6M1   170  DQ<21>  SCONN288_H44441003_PIP  I158
  U5D1   DJ80  DDR3_DQ<21>  SKX_EXT_B_BGA1  I172

M_D_DQ<22>      @BASEBOARD_FAB2_LIB.BASEBOARD_FAB2(SCH_1):M_D_DQ<22>
  J4B1   177  DQ<23>  SCONN288_H44441004_PIP  I111
  J6M1    32  DQ<22>  SCONN288_H44441003_PIP  I158
  U5D1   DR80  DDR3_DQ<22>  SKX_EXT_B_BGA1  I172

M_D_DQ<23>      @BASEBOARD_FAB2_LIB.BASEBOARD_FAB2(SCH_1):M_D_DQ<23>
  J4B1    32  DQ<22>  SCONN288_H44441004_PIP  I111
  J6M1   177  DQ<23>  SCONN288_H44441003_PIP  I158
  U5D1   DN82  DDR3_DQ<23>  SKX_EXT_B_BGA1  I172

M_D_DQ<24>      @BASEBOARD_FAB2_LIB.BASEBOARD_FAB2(SCH_1):M_D_DQ<24>
  J4B1   183  DQ<25>  SCONN288_H44441004_PIP  I111
  J6M1    38  DQ<24>  SCONN288_H44441003_PIP  I158
  U5D1   DN76  DDR3_DQ<24>  SKX_EXT_B_BGA1  I172

M_D_DQ<25>      @BASEBOARD_FAB2_LIB.BASEBOARD_FAB2(SCH_1):M_D_DQ<25>
  J4B1    38  DQ<24>  SCONN288_H44441004_PIP  I111
  J6M1   183  DQ<25>  SCONN288_H44441003_PIP  I158
  U5D1   DU76  DDR3_DQ<25>  SKX_EXT_B_BGA1  I172

M_D_DQ<26>      @BASEBOARD_FAB2_LIB.BASEBOARD_FAB2(SCH_1):M_D_DQ<26>
  J4B1   190  DQ<27>  SCONN288_H44441004_PIP  I111
  J6M1    45  DQ<26>  SCONN288_H44441003_PIP  I158
  U5D1   DP73  DDR3_DQ<26>  SKX_EXT_B_BGA1  I172

M_D_DQ<27>      @BASEBOARD_FAB2_LIB.BASEBOARD_FAB2(SCH_1):M_D_DQ<27>
  J4B1    45  DQ<26>  SCONN288_H44441004_PIP  I111
  J6M1   190  DQ<27>  SCONN288_H44441003_PIP  I158
  U5D1   DT73  DDR3_DQ<27>  SKX_EXT_B_BGA1  I172

M_D_DQ<28>      @BASEBOARD_FAB2_LIB.BASEBOARD_FAB2(SCH_1):M_D_DQ<28>
  J4B1   181  DQ<29>  SCONN288_H44441004_PIP  I111
  J6M1    36  DQ<28>  SCONN288_H44441003_PIP  I158
  U5D1   DP77  DDR3_DQ<28>  SKX_EXT_B_BGA1  I172

M_D_DQ<29>      @BASEBOARD_FAB2_LIB.BASEBOARD_FAB2(SCH_1):M_D_DQ<29>
  J4B1    36  DQ<28>  SCONN288_H44441004_PIP  I111
  J6M1   181  DQ<29>  SCONN288_H44441003_PIP  I158
  U5D1   DT77  DDR3_DQ<29>  SKX_EXT_B_BGA1  I172

M_D_DQ<30>      @BASEBOARD_FAB2_LIB.BASEBOARD_FAB2(SCH_1):M_D_DQ<30>
  J4B1   188  DQ<31>  SCONN288_H44441004_PIP  I111
  J6M1    43  DQ<30>  SCONN288_H44441003_PIP  I158
  U5D1   DN74  DDR3_DQ<30>  SKX_EXT_B_BGA1  I172

M_D_DQ<31>      @BASEBOARD_FAB2_LIB.BASEBOARD_FAB2(SCH_1):M_D_DQ<31>
  J4B1    43  DQ<30>  SCONN288_H44441004_PIP  I111
  J6M1   188  DQ<31>  SCONN288_H44441003_PIP  I158
  U5D1   DU74  DDR3_DQ<31>  SKX_EXT_B_BGA1  I172

M_D_DQ<32>      @BASEBOARD_FAB2_LIB.BASEBOARD_FAB2(SCH_1):M_D_DQ<32>
  J4B1   242  DQ<33>  SCONN288_H44441004_PIP  I111
  J6M1    97  DQ<32>  SCONN288_H44441003_PIP  I158
  U5D1   EC40  DDR3_DQ<32>  SKX_EXT_B_BGA1  I172

M_D_DQ<33>      @BASEBOARD_FAB2_LIB.BASEBOARD_FAB2(SCH_1):M_D_DQ<33>
  J4B1    97  DQ<32>  SCONN288_H44441004_PIP  I111
  J6M1   242  DQ<33>  SCONN288_H44441003_PIP  I158
  U5D1   ED39  DDR3_DQ<33>  SKX_EXT_B_BGA1  I172

M_D_DQ<34>      @BASEBOARD_FAB2_LIB.BASEBOARD_FAB2(SCH_1):M_D_DQ<34>
  J4B1   249  DQ<35>  SCONN288_H44441004_PIP  I111
  J6M1   104  DQ<34>  SCONN288_H44441003_PIP  I158
  U5D1   EA36  DDR3_DQ<34>  SKX_EXT_B_BGA1  I172

M_D_DQ<35>      @BASEBOARD_FAB2_LIB.BASEBOARD_FAB2(SCH_1):M_D_DQ<35>
  J4B1   104  DQ<34>  SCONN288_H44441004_PIP  I111
  J6M1   249  DQ<35>  SCONN288_H44441003_PIP  I158
  U5D1   EC36  DDR3_DQ<35>  SKX_EXT_B_BGA1  I172

M_D_DQ<36>      @BASEBOARD_FAB2_LIB.BASEBOARD_FAB2(SCH_1):M_D_DQ<36>
  J4B1   240  DQ<37>  SCONN288_H44441004_PIP  I111
  J6M1    95  DQ<36>  SCONN288_H44441003_PIP  I158
  U5D1   DY39  DDR3_DQ<36>  SKX_EXT_B_BGA1  I172

M_D_DQ<37>      @BASEBOARD_FAB2_LIB.BASEBOARD_FAB2(SCH_1):M_D_DQ<37>
  J4B1    95  DQ<36>  SCONN288_H44441004_PIP  I111
  J6M1   240  DQ<37>  SCONN288_H44441003_PIP  I158
  U5D1   EA40  DDR3_DQ<37>  SKX_EXT_B_BGA1  I172

M_D_DQ<38>      @BASEBOARD_FAB2_LIB.BASEBOARD_FAB2(SCH_1):M_D_DQ<38>
  J4B1   247  DQ<39>  SCONN288_H44441004_PIP  I111
  J6M1   102  DQ<38>  SCONN288_H44441003_PIP  I158
  U5D1   DY37  DDR3_DQ<38>  SKX_EXT_B_BGA1  I172

M_D_DQ<39>      @BASEBOARD_FAB2_LIB.BASEBOARD_FAB2(SCH_1):M_D_DQ<39>
  J4B1   102  DQ<38>  SCONN288_H44441004_PIP  I111
  J6M1   247  DQ<39>  SCONN288_H44441003_PIP  I158
  U5D1   ED37  DDR3_DQ<39>  SKX_EXT_B_BGA1  I172

M_D_DQ<40>      @BASEBOARD_FAB2_LIB.BASEBOARD_FAB2(SCH_1):M_D_DQ<40>
  J4B1   253  DQ<41>  SCONN288_H44441004_PIP  I111
  J6M1   108  DQ<40>  SCONN288_H44441003_PIP  I158
  U5D1   DN36  DDR3_DQ<40>  SKX_EXT_B_BGA1  I172

M_D_DQ<41>      @BASEBOARD_FAB2_LIB.BASEBOARD_FAB2(SCH_1):M_D_DQ<41>
  J4B1   108  DQ<40>  SCONN288_H44441004_PIP  I111
  J6M1   253  DQ<41>  SCONN288_H44441003_PIP  I158
  U5D1   DU36  DDR3_DQ<41>  SKX_EXT_B_BGA1  I172

M_D_DQ<42>      @BASEBOARD_FAB2_LIB.BASEBOARD_FAB2(SCH_1):M_D_DQ<42>
  J4B1   260  DQ<43>  SCONN288_H44441004_PIP  I111
  J6M1   115  DQ<42>  SCONN288_H44441003_PIP  I158
  U5D1   DP33  DDR3_DQ<42>  SKX_EXT_B_BGA1  I172

M_D_DQ<43>      @BASEBOARD_FAB2_LIB.BASEBOARD_FAB2(SCH_1):M_D_DQ<43>
  J4B1   115  DQ<42>  SCONN288_H44441004_PIP  I111
  J6M1   260  DQ<43>  SCONN288_H44441003_PIP  I158
  U5D1   DT33  DDR3_DQ<43>  SKX_EXT_B_BGA1  I172

M_D_DQ<44>      @BASEBOARD_FAB2_LIB.BASEBOARD_FAB2(SCH_1):M_D_DQ<44>
  J4B1   251  DQ<45>  SCONN288_H44441004_PIP  I111
  J6M1   106  DQ<44>  SCONN288_H44441003_PIP  I158
  U5D1   DP37  DDR3_DQ<44>  SKX_EXT_B_BGA1  I172

M_D_DQ<45>      @BASEBOARD_FAB2_LIB.BASEBOARD_FAB2(SCH_1):M_D_DQ<45>
  J4B1   106  DQ<44>  SCONN288_H44441004_PIP  I111
  J6M1   251  DQ<45>  SCONN288_H44441003_PIP  I158
  U5D1   DT37  DDR3_DQ<45>  SKX_EXT_B_BGA1  I172

M_D_DQ<46>      @BASEBOARD_FAB2_LIB.BASEBOARD_FAB2(SCH_1):M_D_DQ<46>
  J4B1   258  DQ<47>  SCONN288_H44441004_PIP  I111
  J6M1   113  DQ<46>  SCONN288_H44441003_PIP  I158
  U5D1   DN34  DDR3_DQ<46>  SKX_EXT_B_BGA1  I172

M_D_DQ<47>      @BASEBOARD_FAB2_LIB.BASEBOARD_FAB2(SCH_1):M_D_DQ<47>
  J4B1   113  DQ<46>  SCONN288_H44441004_PIP  I111
  J6M1   258  DQ<47>  SCONN288_H44441003_PIP  I158
  U5D1   DU34  DDR3_DQ<47>  SKX_EXT_B_BGA1  I172

M_D_DQ<48>      @BASEBOARD_FAB2_LIB.BASEBOARD_FAB2(SCH_1):M_D_DQ<48>
  J4B1   264  DQ<49>  SCONN288_H44441004_PIP  I111
  J6M1   119  DQ<48>  SCONN288_H44441003_PIP  I158
  U5D1   DN30  DDR3_DQ<48>  SKX_EXT_B_BGA1  I172

M_D_DQ<49>      @BASEBOARD_FAB2_LIB.BASEBOARD_FAB2(SCH_1):M_D_DQ<49>
  J4B1   119  DQ<48>  SCONN288_H44441004_PIP  I111
  J6M1   264  DQ<49>  SCONN288_H44441003_PIP  I158
  U5D1   DU30  DDR3_DQ<49>  SKX_EXT_B_BGA1  I172

M_D_DQ<50>      @BASEBOARD_FAB2_LIB.BASEBOARD_FAB2(SCH_1):M_D_DQ<50>
  J4B1   271  DQ<51>  SCONN288_H44441004_PIP  I111
  J6M1   126  DQ<50>  SCONN288_H44441003_PIP  I158
  U5D1   DP27  DDR3_DQ<50>  SKX_EXT_B_BGA1  I172

M_D_DQ<51>      @BASEBOARD_FAB2_LIB.BASEBOARD_FAB2(SCH_1):M_D_DQ<51>
  J4B1   126  DQ<50>  SCONN288_H44441004_PIP  I111
  J6M1   271  DQ<51>  SCONN288_H44441003_PIP  I158
  U5D1   DT27  DDR3_DQ<51>  SKX_EXT_B_BGA1  I172

M_D_DQ<52>      @BASEBOARD_FAB2_LIB.BASEBOARD_FAB2(SCH_1):M_D_DQ<52>
  J4B1   262  DQ<53>  SCONN288_H44441004_PIP  I111
  J6M1   117  DQ<52>  SCONN288_H44441003_PIP  I158
  U5D1   DP31  DDR3_DQ<52>  SKX_EXT_B_BGA1  I172

M_D_DQ<53>      @BASEBOARD_FAB2_LIB.BASEBOARD_FAB2(SCH_1):M_D_DQ<53>
  J4B1   117  DQ<52>  SCONN288_H44441004_PIP  I111
  J6M1   262  DQ<53>  SCONN288_H44441003_PIP  I158
  U5D1   DT31  DDR3_DQ<53>  SKX_EXT_B_BGA1  I172

M_D_DQ<54>      @BASEBOARD_FAB2_LIB.BASEBOARD_FAB2(SCH_1):M_D_DQ<54>
  J4B1   269  DQ<55>  SCONN288_H44441004_PIP  I111
  J6M1   124  DQ<54>  SCONN288_H44441003_PIP  I158
  U5D1   DN28  DDR3_DQ<54>  SKX_EXT_B_BGA1  I172

M_D_DQ<55>      @BASEBOARD_FAB2_LIB.BASEBOARD_FAB2(SCH_1):M_D_DQ<55>
  J4B1   124  DQ<54>  SCONN288_H44441004_PIP  I111
  J6M1   269  DQ<55>  SCONN288_H44441003_PIP  I158
  U5D1   DU28  DDR3_DQ<55>  SKX_EXT_B_BGA1  I172

M_D_DQ<56>      @BASEBOARD_FAB2_LIB.BASEBOARD_FAB2(SCH_1):M_D_DQ<56>
  J4B1   275  DQ<57>  SCONN288_H44441004_PIP  I111
  J6M1   130  DQ<56>  SCONN288_H44441003_PIP  I158
  U5D1   DN24  DDR3_DQ<56>  SKX_EXT_B_BGA1  I172

M_D_DQ<57>      @BASEBOARD_FAB2_LIB.BASEBOARD_FAB2(SCH_1):M_D_DQ<57>
  J4B1   130  DQ<56>  SCONN288_H44441004_PIP  I111
  J6M1   275  DQ<57>  SCONN288_H44441003_PIP  I158
  U5D1   DU24  DDR3_DQ<57>  SKX_EXT_B_BGA1  I172

M_D_DQ<58>      @BASEBOARD_FAB2_LIB.BASEBOARD_FAB2(SCH_1):M_D_DQ<58>
  J4B1   282  DQ<59>  SCONN288_H44441004_PIP  I111
  J6M1   137  DQ<58>  SCONN288_H44441003_PIP  I158
  U5D1   DY21  DDR3_DQ<58>  SKX_EXT_B_BGA1  I172

M_D_DQ<59>      @BASEBOARD_FAB2_LIB.BASEBOARD_FAB2(SCH_1):M_D_DQ<59>
  J4B1   137  DQ<58>  SCONN288_H44441004_PIP  I111
  J6M1   282  DQ<59>  SCONN288_H44441003_PIP  I158
  U5D1   EB21  DDR3_DQ<59>  SKX_EXT_B_BGA1  I172

M_D_DQ<60>      @BASEBOARD_FAB2_LIB.BASEBOARD_FAB2(SCH_1):M_D_DQ<60>
  J4B1   273  DQ<61>  SCONN288_H44441004_PIP  I111
  J6M1   128  DQ<60>  SCONN288_H44441003_PIP  I158
  U5D1   DP25  DDR3_DQ<60>  SKX_EXT_B_BGA1  I172

M_D_DQ<61>      @BASEBOARD_FAB2_LIB.BASEBOARD_FAB2(SCH_1):M_D_DQ<61>
  J4B1   128  DQ<60>  SCONN288_H44441004_PIP  I111
  J6M1   273  DQ<61>  SCONN288_H44441003_PIP  I158
  U5D1   DT25  DDR3_DQ<61>  SKX_EXT_B_BGA1  I172

M_D_DQ<62>      @BASEBOARD_FAB2_LIB.BASEBOARD_FAB2(SCH_1):M_D_DQ<62>
  J4B1   280  DQ<63>  SCONN288_H44441004_PIP  I111
  J6M1   135  DQ<62>  SCONN288_H44441003_PIP  I158
  U5D1   EC22  DDR3_DQ<62>  SKX_EXT_B_BGA1  I172

M_D_DQ<63>      @BASEBOARD_FAB2_LIB.BASEBOARD_FAB2(SCH_1):M_D_DQ<63>
  J4B1   135  DQ<62>  SCONN288_H44441004_PIP  I111
  J6M1   280  DQ<63>  SCONN288_H44441003_PIP  I158
  U5D1   DW22  DDR3_DQ<63>  SKX_EXT_B_BGA1  I172

M_D_DQS_DN<0>   @BASEBOARD_FAB2_LIB.BASEBOARD_FAB2(SCH_1):M_D_DQS_DN<0>
  J4B1   152  DQS0N  SCONN288_H44441004_PIP  I66
  J6M1   152  DQS0N  SCONN288_H44441003_PIP  I46
  U5D1   CU84  DDR3_DQS_DN<0>  SKX_EXT_B_BGA1  I172

M_D_DQS_DN<1>   @BASEBOARD_FAB2_LIB.BASEBOARD_FAB2(SCH_1):M_D_DQS_DN<1>
  J4B1   163  DQS1N  SCONN288_H44441004_PIP  I66
  J6M1   163  DQS1N  SCONN288_H44441003_PIP  I46
  U5D1   DN84  DDR3_DQS_DN<1>  SKX_EXT_B_BGA1  I172

M_D_DQS_DN<2>   @BASEBOARD_FAB2_LIB.BASEBOARD_FAB2(SCH_1):M_D_DQS_DN<2>
  J4B1   174  DQS2N  SCONN288_H44441004_PIP  I66
  J6M1   174  DQS2N  SCONN288_H44441003_PIP  I46
  U5D1   DL82  DDR3_DQS_DN<2>  SKX_EXT_B_BGA1  I172

M_D_DQS_DN<3>   @BASEBOARD_FAB2_LIB.BASEBOARD_FAB2(SCH_1):M_D_DQS_DN<3>
  J4B1   185  DQS3N  SCONN288_H44441004_PIP  I66
  J6M1   185  DQS3N  SCONN288_H44441003_PIP  I46
  U5D1   DV75  DDR3_DQS_DN<3>  SKX_EXT_B_BGA1  I172

M_D_DQS_DN<4>   @BASEBOARD_FAB2_LIB.BASEBOARD_FAB2(SCH_1):M_D_DQS_DN<4>
  J4B1   244  DQS4N  SCONN288_H44441004_PIP  I66
  J6M1   244  DQS4N  SCONN288_H44441003_PIP  I46
  U5D1   EE38  DDR3_DQS_DN<4>  SKX_EXT_B_BGA1  I172

M_D_DQS_DN<5>   @BASEBOARD_FAB2_LIB.BASEBOARD_FAB2(SCH_1):M_D_DQS_DN<5>
  J4B1   255  DQS5N  SCONN288_H44441004_PIP  I66
  J6M1   255  DQS5N  SCONN288_H44441003_PIP  I46
  U5D1   DV35  DDR3_DQS_DN<5>  SKX_EXT_B_BGA1  I172

M_D_DQS_DN<6>   @BASEBOARD_FAB2_LIB.BASEBOARD_FAB2(SCH_1):M_D_DQS_DN<6>
  J4B1   266  DQS6N  SCONN288_H44441004_PIP  I66
  J6M1   266  DQS6N  SCONN288_H44441003_PIP  I46
  U5D1   DV29  DDR3_DQS_DN<6>  SKX_EXT_B_BGA1  I172

M_D_DQS_DN<7>   @BASEBOARD_FAB2_LIB.BASEBOARD_FAB2(SCH_1):M_D_DQS_DN<7>
  J4B1   277  DQS7N  SCONN288_H44441004_PIP  I66
  J6M1   277  DQS7N  SCONN288_H44441003_PIP  I46
  U5D1   DV23  DDR3_DQS_DN<7>  SKX_EXT_B_BGA1  I172

M_D_DQS_DN<8>   @BASEBOARD_FAB2_LIB.BASEBOARD_FAB2(SCH_1):M_D_DQS_DN<8>
  J4B1   196  DQS8N  SCONN288_H44441004_PIP  I66
  J6M1   196  DQS8N  SCONN288_H44441003_PIP  I46
  U5D1   DF67  DDR3_DQS_DN<8>  SKX_EXT_B_BGA1  I172

M_D_DQS_DN<9>   @BASEBOARD_FAB2_LIB.BASEBOARD_FAB2(SCH_1):M_D_DQS_DN<9>
  J4B1     8  DQS9N  SCONN288_H44441004_PIP  I66
  J6M1     8  DQS9N  SCONN288_H44441003_PIP  I46
  U5D1   CR84  DDR3_DQS_DN<9>  SKX_EXT_B_BGA1  I172

M_D_DQS_DN<10>   @BASEBOARD_FAB2_LIB.BASEBOARD_FAB2(SCH_1):M_D_DQS_DN<10>
  J4B1    19  DQS10N  SCONN288_H44441004_PIP  I66
  J6M1    19  DQS10N  SCONN288_H44441003_PIP  I46
  U5D1   DM85  DDR3_DQS_DN<10>  SKX_EXT_B_BGA1  I172

M_D_DQS_DN<11>   @BASEBOARD_FAB2_LIB.BASEBOARD_FAB2(SCH_1):M_D_DQS_DN<11>
  J4B1    30  DQS11N  SCONN288_H44441004_PIP  I66
  J6M1    30  DQS11N  SCONN288_H44441003_PIP  I46
  U5D1   DN80  DDR3_DQS_DN<11>  SKX_EXT_B_BGA1  I172

M_D_DQS_DN<12>   @BASEBOARD_FAB2_LIB.BASEBOARD_FAB2(SCH_1):M_D_DQS_DN<12>
  J4B1    41  DQS12N  SCONN288_H44441004_PIP  I66
  J6M1    41  DQS12N  SCONN288_H44441003_PIP  I46
  U5D1   DP75  DDR3_DQS_DN<12>  SKX_EXT_B_BGA1  I172

M_D_DQS_DN<13>   @BASEBOARD_FAB2_LIB.BASEBOARD_FAB2(SCH_1):M_D_DQS_DN<13>
  J4B1   100  DQS13N  SCONN288_H44441004_PIP  I66
  J6M1   100  DQS13N  SCONN288_H44441003_PIP  I46
  U5D1   EA38  DDR3_DQS_DN<13>  SKX_EXT_B_BGA1  I172

M_D_DQS_DN<14>   @BASEBOARD_FAB2_LIB.BASEBOARD_FAB2(SCH_1):M_D_DQS_DN<14>
  J4B1   111  DQS14N  SCONN288_H44441004_PIP  I66
  J6M1   111  DQS14N  SCONN288_H44441003_PIP  I46
  U5D1   DP35  DDR3_DQS_DN<14>  SKX_EXT_B_BGA1  I172

M_D_DQS_DN<15>   @BASEBOARD_FAB2_LIB.BASEBOARD_FAB2(SCH_1):M_D_DQS_DN<15>
  J4B1   122  DQS15N  SCONN288_H44441004_PIP  I66
  J6M1   122  DQS15N  SCONN288_H44441003_PIP  I46
  U5D1   DM29  DDR3_DQS_DN<15>  SKX_EXT_B_BGA1  I172

M_D_DQS_DN<16>   @BASEBOARD_FAB2_LIB.BASEBOARD_FAB2(SCH_1):M_D_DQS_DN<16>
  J4B1   133  DQS16N  SCONN288_H44441004_PIP  I66
  J6M1   133  DQS16N  SCONN288_H44441003_PIP  I46
  U5D1   DM23  DDR3_DQS_DN<16>  SKX_EXT_B_BGA1  I172

M_D_DQS_DN<17>   @BASEBOARD_FAB2_LIB.BASEBOARD_FAB2(SCH_1):M_D_DQS_DN<17>
  J4B1    52  DQS17N  SCONN288_H44441004_PIP  I66
  J6M1    52  DQS17N  SCONN288_H44441003_PIP  I46
  U5D1   DB67  DDR3_DQS_DN<17>  SKX_EXT_B_BGA1  I172

M_D_DQS_DP<0>   @BASEBOARD_FAB2_LIB.BASEBOARD_FAB2(SCH_1):M_D_DQS_DP<0>
  J4B1   153  DQS0P  SCONN288_H44441004_PIP  I66
  J6M1   153  DQS0P  SCONN288_H44441003_PIP  I46
  U5D1   CV85  DDR3_DQS_DP<0>  SKX_EXT_B_BGA1  I172

M_D_DQS_DP<1>   @BASEBOARD_FAB2_LIB.BASEBOARD_FAB2(SCH_1):M_D_DQS_DP<1>
  J4B1   164  DQS1P  SCONN288_H44441004_PIP  I66
  J6M1   164  DQS1P  SCONN288_H44441003_PIP  I46
  U5D1   DP85  DDR3_DQS_DP<1>  SKX_EXT_B_BGA1  I172

M_D_DQS_DP<2>   @BASEBOARD_FAB2_LIB.BASEBOARD_FAB2(SCH_1):M_D_DQS_DP<2>
  J4B1   175  DQS2P  SCONN288_H44441004_PIP  I66
  J6M1   175  DQS2P  SCONN288_H44441003_PIP  I46
  U5D1   DM81  DDR3_DQS_DP<2>  SKX_EXT_B_BGA1  I172

M_D_DQS_DP<3>   @BASEBOARD_FAB2_LIB.BASEBOARD_FAB2(SCH_1):M_D_DQS_DP<3>
  J4B1   186  DQS3P  SCONN288_H44441004_PIP  I66
  J6M1   186  DQS3P  SCONN288_H44441003_PIP  I46
  U5D1   DT75  DDR3_DQS_DP<3>  SKX_EXT_B_BGA1  I172

M_D_DQS_DP<4>   @BASEBOARD_FAB2_LIB.BASEBOARD_FAB2(SCH_1):M_D_DQS_DP<4>
  J4B1   245  DQS4P  SCONN288_H44441004_PIP  I66
  J6M1   245  DQS4P  SCONN288_H44441003_PIP  I46
  U5D1   EC38  DDR3_DQS_DP<4>  SKX_EXT_B_BGA1  I172

M_D_DQS_DP<5>   @BASEBOARD_FAB2_LIB.BASEBOARD_FAB2(SCH_1):M_D_DQS_DP<5>
  J4B1   256  DQS5P  SCONN288_H44441004_PIP  I66
  J6M1   256  DQS5P  SCONN288_H44441003_PIP  I46
  U5D1   DT35  DDR3_DQS_DP<5>  SKX_EXT_B_BGA1  I172

M_D_DQS_DP<6>   @BASEBOARD_FAB2_LIB.BASEBOARD_FAB2(SCH_1):M_D_DQS_DP<6>
  J4B1   267  DQS6P  SCONN288_H44441004_PIP  I66
  J6M1   267  DQS6P  SCONN288_H44441003_PIP  I46
  U5D1   DT29  DDR3_DQS_DP<6>  SKX_EXT_B_BGA1  I172

M_D_DQS_DP<7>   @BASEBOARD_FAB2_LIB.BASEBOARD_FAB2(SCH_1):M_D_DQS_DP<7>
  J4B1   278  DQS7P  SCONN288_H44441004_PIP  I66
  J6M1   278  DQS7P  SCONN288_H44441003_PIP  I46
  U5D1   DT23  DDR3_DQS_DP<7>  SKX_EXT_B_BGA1  I172

M_D_DQS_DP<8>   @BASEBOARD_FAB2_LIB.BASEBOARD_FAB2(SCH_1):M_D_DQS_DP<8>
  J4B1   197  DQS8P  SCONN288_H44441004_PIP  I66
  J6M1   197  DQS8P  SCONN288_H44441003_PIP  I46
  U5D1   DD67  DDR3_DQS_DP<8>  SKX_EXT_B_BGA1  I172

M_D_DQS_DP<9>   @BASEBOARD_FAB2_LIB.BASEBOARD_FAB2(SCH_1):M_D_DQS_DP<9>
  J4B1     7  DQS9P  SCONN288_H44441004_PIP  I66
  J6M1     7  DQS9P  SCONN288_H44441003_PIP  I46
  U5D1   CP85  DDR3_DQS_DP<9>  SKX_EXT_B_BGA1  I172

M_D_DQS_DP<10>   @BASEBOARD_FAB2_LIB.BASEBOARD_FAB2(SCH_1):M_D_DQS_DP<10>
  J4B1    18  DQS10P  SCONN288_H44441004_PIP  I66
  J6M1    18  DQS10P  SCONN288_H44441003_PIP  I46
  U5D1   DL84  DDR3_DQS_DP<10>  SKX_EXT_B_BGA1  I172

M_D_DQS_DP<11>   @BASEBOARD_FAB2_LIB.BASEBOARD_FAB2(SCH_1):M_D_DQS_DP<11>
  J4B1    29  DQS11P  SCONN288_H44441004_PIP  I66
  J6M1    29  DQS11P  SCONN288_H44441003_PIP  I46
  U5D1   DP79  DDR3_DQS_DP<11>  SKX_EXT_B_BGA1  I172

M_D_DQS_DP<12>   @BASEBOARD_FAB2_LIB.BASEBOARD_FAB2(SCH_1):M_D_DQS_DP<12>
  J4B1    40  DQS12P  SCONN288_H44441004_PIP  I66
  J6M1    40  DQS12P  SCONN288_H44441003_PIP  I46
  U5D1   DM75  DDR3_DQS_DP<12>  SKX_EXT_B_BGA1  I172

M_D_DQS_DP<13>   @BASEBOARD_FAB2_LIB.BASEBOARD_FAB2(SCH_1):M_D_DQS_DP<13>
  J4B1    99  DQS13P  SCONN288_H44441004_PIP  I66
  J6M1    99  DQS13P  SCONN288_H44441003_PIP  I46
  U5D1   DW38  DDR3_DQS_DP<13>  SKX_EXT_B_BGA1  I172

M_D_DQS_DP<14>   @BASEBOARD_FAB2_LIB.BASEBOARD_FAB2(SCH_1):M_D_DQS_DP<14>
  J4B1   110  DQS14P  SCONN288_H44441004_PIP  I66
  J6M1   110  DQS14P  SCONN288_H44441003_PIP  I46
  U5D1   DM35  DDR3_DQS_DP<14>  SKX_EXT_B_BGA1  I172

M_D_DQS_DP<15>   @BASEBOARD_FAB2_LIB.BASEBOARD_FAB2(SCH_1):M_D_DQS_DP<15>
  J4B1   121  DQS15P  SCONN288_H44441004_PIP  I66
  J6M1   121  DQS15P  SCONN288_H44441003_PIP  I46
  U5D1   DP29  DDR3_DQS_DP<15>  SKX_EXT_B_BGA1  I172

M_D_DQS_DP<16>   @BASEBOARD_FAB2_LIB.BASEBOARD_FAB2(SCH_1):M_D_DQS_DP<16>
  J4B1   132  DQS16P  SCONN288_H44441004_PIP  I66
  J6M1   132  DQS16P  SCONN288_H44441003_PIP  I46
  U5D1   DP23  DDR3_DQS_DP<16>  SKX_EXT_B_BGA1  I172

M_D_DQS_DP<17>   @BASEBOARD_FAB2_LIB.BASEBOARD_FAB2(SCH_1):M_D_DQS_DP<17>
  J4B1    51  DQS17P  SCONN288_H44441004_PIP  I66
  J6M1    51  DQS17P  SCONN288_H44441003_PIP  I46
  U5D1   CY67  DDR3_DQS_DP<17>  SKX_EXT_B_BGA1  I172

M_D_ECC<0>      @BASEBOARD_FAB2_LIB.BASEBOARD_FAB2(SCH_1):M_D_ECC<0>
  J4B1   194  CB<1>  SCONN288_H44441004_PIP  I111
  J6M1    49  CB<0>  SCONN288_H44441003_PIP  I158
  U5D1   DA68  DDR3_ECC<0>  SKX_EXT_B_BGA1  I172

M_D_ECC<1>      @BASEBOARD_FAB2_LIB.BASEBOARD_FAB2(SCH_1):M_D_ECC<1>
  J4B1    49  CB<0>  SCONN288_H44441004_PIP  I111
  J6M1   194  CB<1>  SCONN288_H44441003_PIP  I158
  U5D1   DE68  DDR3_ECC<1>  SKX_EXT_B_BGA1  I172

M_D_ECC<2>      @BASEBOARD_FAB2_LIB.BASEBOARD_FAB2(SCH_1):M_D_ECC<2>
  J4B1   201  CB<3>  SCONN288_H44441004_PIP  I111
  J6M1    56  CB<2>  SCONN288_H44441003_PIP  I158
  U5D1   DB65  DDR3_ECC<2>  SKX_EXT_B_BGA1  I172

M_D_ECC<3>      @BASEBOARD_FAB2_LIB.BASEBOARD_FAB2(SCH_1):M_D_ECC<3>
  J4B1    56  CB<2>  SCONN288_H44441004_PIP  I111
  J6M1   201  CB<3>  SCONN288_H44441003_PIP  I158
  U5D1   DD65  DDR3_ECC<3>  SKX_EXT_B_BGA1  I172

M_D_ECC<4>      @BASEBOARD_FAB2_LIB.BASEBOARD_FAB2(SCH_1):M_D_ECC<4>
  J4B1   192  CB<5>  SCONN288_H44441004_PIP  I111
  J6M1    47  CB<4>  SCONN288_H44441003_PIP  I158
  U5D1   DB69  DDR3_ECC<4>  SKX_EXT_B_BGA1  I172

M_D_ECC<5>      @BASEBOARD_FAB2_LIB.BASEBOARD_FAB2(SCH_1):M_D_ECC<5>
  J4B1    47  CB<4>  SCONN288_H44441004_PIP  I111
  J6M1   192  CB<5>  SCONN288_H44441003_PIP  I158
  U5D1   DD69  DDR3_ECC<5>  SKX_EXT_B_BGA1  I172

M_D_ECC<6>      @BASEBOARD_FAB2_LIB.BASEBOARD_FAB2(SCH_1):M_D_ECC<6>
  J4B1   199  CB<7>  SCONN288_H44441004_PIP  I111
  J6M1    54  CB<6>  SCONN288_H44441003_PIP  I158
  U5D1   DA66  DDR3_ECC<6>  SKX_EXT_B_BGA1  I172

M_D_ECC<7>      @BASEBOARD_FAB2_LIB.BASEBOARD_FAB2(SCH_1):M_D_ECC<7>
  J4B1    54  CB<6>  SCONN288_H44441004_PIP  I111
  J6M1   199  CB<7>  SCONN288_H44441003_PIP  I158
  U5D1   DE66  DDR3_ECC<7>  SKX_EXT_B_BGA1  I172

M_D_MA<0>       @BASEBOARD_FAB2_LIB.BASEBOARD_FAB2(SCH_1):M_D_MA<0>
  J4B1    79     A0  SCONN288_H44441004_PIP  I111
  J6M1    79     A0  SCONN288_H44441003_PIP  I158
  U5D1   EB53  DDR3_MA<0>  SKX_EXT_B_BGA1  I172

M_D_MA<1>       @BASEBOARD_FAB2_LIB.BASEBOARD_FAB2(SCH_1):M_D_MA<1>
  J4B1    72     A1  SCONN288_H44441004_PIP  I111
  J6M1    72     A1  SCONN288_H44441003_PIP  I158
  U5D1   ED57  DDR3_MA<1>  SKX_EXT_B_BGA1  I172

M_D_MA<2>       @BASEBOARD_FAB2_LIB.BASEBOARD_FAB2(SCH_1):M_D_MA<2>
  J4B1   216     A2  SCONN288_H44441004_PIP  I111
  J6M1   216     A2  SCONN288_H44441003_PIP  I158
  U5D1   EE58  DDR3_MA<2>  SKX_EXT_B_BGA1  I172

M_D_MA<3>       @BASEBOARD_FAB2_LIB.BASEBOARD_FAB2(SCH_1):M_D_MA<3>
  J4B1    71     A3  SCONN288_H44441004_PIP  I111
  J6M1    71     A3  SCONN288_H44441003_PIP  I158
  U5D1   EB57  DDR3_MA<3>  SKX_EXT_B_BGA1  I172

M_D_MA<4>       @BASEBOARD_FAB2_LIB.BASEBOARD_FAB2(SCH_1):M_D_MA<4>
  J4B1   214     A4  SCONN288_H44441004_PIP  I111
  J6M1   214     A4  SCONN288_H44441003_PIP  I158
  U5D1   ED59  DDR3_MA<4>  SKX_EXT_B_BGA1  I172

M_D_MA<5>       @BASEBOARD_FAB2_LIB.BASEBOARD_FAB2(SCH_1):M_D_MA<5>
  J4B1   213     A5  SCONN288_H44441004_PIP  I111
  J6M1   213     A5  SCONN288_H44441003_PIP  I158
  U5D1   EA58  DDR3_MA<5>  SKX_EXT_B_BGA1  I172

M_D_MA<6>       @BASEBOARD_FAB2_LIB.BASEBOARD_FAB2(SCH_1):M_D_MA<6>
  J4B1    69     A6  SCONN288_H44441004_PIP  I111
  J6M1    69     A6  SCONN288_H44441003_PIP  I158
  U5D1   EE60  DDR3_MA<6>  SKX_EXT_B_BGA1  I172

M_D_MA<7>       @BASEBOARD_FAB2_LIB.BASEBOARD_FAB2(SCH_1):M_D_MA<7>
  J4B1   211     A7  SCONN288_H44441004_PIP  I111
  J6M1   211     A7  SCONN288_H44441003_PIP  I158
  U5D1   EA60  DDR3_MA<7>  SKX_EXT_B_BGA1  I172

M_D_MA<8>       @BASEBOARD_FAB2_LIB.BASEBOARD_FAB2(SCH_1):M_D_MA<8>
  J4B1    68     A8  SCONN288_H44441004_PIP  I111
  J6M1    68     A8  SCONN288_H44441003_PIP  I158
  U5D1   EB59  DDR3_MA<8>  SKX_EXT_B_BGA1  I172

M_D_MA<9>       @BASEBOARD_FAB2_LIB.BASEBOARD_FAB2(SCH_1):M_D_MA<9>
  J4B1    66     A9  SCONN288_H44441004_PIP  I111
  J6M1    66     A9  SCONN288_H44441003_PIP  I158
  U5D1   EF61  DDR3_MA<9>  SKX_EXT_B_BGA1  I172

M_D_MA<10>      @BASEBOARD_FAB2_LIB.BASEBOARD_FAB2(SCH_1):M_D_MA<10>
  J4B1   225    A10  SCONN288_H44441004_PIP  I111
  J6M1   225    A10  SCONN288_H44441003_PIP  I158
  U5D1   DW54  DDR3_MA<10>  SKX_EXT_B_BGA1  I172

M_D_MA<11>      @BASEBOARD_FAB2_LIB.BASEBOARD_FAB2(SCH_1):M_D_MA<11>
  J4B1   210    A11  SCONN288_H44441004_PIP  I111
  J6M1   210    A11  SCONN288_H44441003_PIP  I158
  U5D1   EB61  DDR3_MA<11>  SKX_EXT_B_BGA1  I172

M_D_MA<12>      @BASEBOARD_FAB2_LIB.BASEBOARD_FAB2(SCH_1):M_D_MA<12>
  J4B1    65    A12  SCONN288_H44441004_PIP  I111
  J6M1    65    A12  SCONN288_H44441003_PIP  I158
  U5D1   DT63  DDR3_MA<12>  SKX_EXT_B_BGA1  I172

M_D_MA<13>      @BASEBOARD_FAB2_LIB.BASEBOARD_FAB2(SCH_1):M_D_MA<13>
  J4B1   232    A13  SCONN288_H44441004_PIP  I111
  J6M1   232    A13  SCONN288_H44441003_PIP  I158
  U5D1   DW48  DDR3_MA<13>  SKX_EXT_B_BGA1  I172

M_D_MA<14>      @BASEBOARD_FAB2_LIB.BASEBOARD_FAB2(SCH_1):M_D_MA<14>
  J4B1   228  A14_WE_N  SCONN288_H44441004_PIP  I111
  J6M1   228  A14_WE_N  SCONN288_H44441003_PIP  I158
  U5D1   ED51  DDR3_MA<14>  SKX_EXT_B_BGA1  I172

M_D_MA<15>      @BASEBOARD_FAB2_LIB.BASEBOARD_FAB2(SCH_1):M_D_MA<15>
  J4B1    86  A15_CAS_N  SCONN288_H44441004_PIP  I111
  J6M1    86  A15_CAS_N  SCONN288_H44441003_PIP  I158
  U5D1   DV49  DDR3_MA<15>  SKX_EXT_B_BGA1  I172

M_D_MA<16>      @BASEBOARD_FAB2_LIB.BASEBOARD_FAB2(SCH_1):M_D_MA<16>
  J4B1    82  A16_RAS_N  SCONN288_H44441004_PIP  I111
  J6M1    82  A16_RAS_N  SCONN288_H44441003_PIP  I158
  U5D1   EA52  DDR3_MA<16>  SKX_EXT_B_BGA1  I172

M_D_MA<17>      @BASEBOARD_FAB2_LIB.BASEBOARD_FAB2(SCH_1):M_D_MA<17>
  J4B1   234    A17  SCONN288_H44441004_PIP  I111
  J6M1   234    A17  SCONN288_H44441003_PIP  I158
  U5D1   EA46  DDR3_MA<17>  SKX_EXT_B_BGA1  I172

M_D_ODT<0>      @BASEBOARD_FAB2_LIB.BASEBOARD_FAB2(SCH_1):M_D_ODT<0>
  J4B1    87  ODT<0>  SCONN288_H44441004_PIP  I111
  U5D1   EE50  DDR3_ODT<0>  SKX_EXT_B_BGA1  I172

M_D_ODT<1>      @BASEBOARD_FAB2_LIB.BASEBOARD_FAB2(SCH_1):M_D_ODT<1>
  J4B1    91  ODT<1>  SCONN288_H44441004_PIP  I111
  U5D1   EE48  DDR3_ODT<1>  SKX_EXT_B_BGA1  I172

M_D_ODT<2>      @BASEBOARD_FAB2_LIB.BASEBOARD_FAB2(SCH_1):M_D_ODT<2>
  J6M1    87  ODT<0>  SCONN288_H44441003_PIP  I158
  U5D1   EA50  DDR3_ODT<2>  SKX_EXT_B_BGA1  I172

M_D_ODT<3>      @BASEBOARD_FAB2_LIB.BASEBOARD_FAB2(SCH_1):M_D_ODT<3>
  J6M1    91  ODT<1>  SCONN288_H44441003_PIP  I158
  U5D1   EA48  DDR3_ODT<3>  SKX_EXT_B_BGA1  I172

M_D_PAR         @BASEBOARD_FAB2_LIB.BASEBOARD_FAB2(SCH_1):M_D_PAR
  J4B1   222    PAR  SCONN288_H44441004_PIP  I111
  J6M1   222    PAR  SCONN288_H44441003_PIP  I158
  U5D1   ED53  DDR3_PAR  SKX_EXT_B_BGA1  I172

M_D_VREF        @BASEBOARD_FAB2_LIB.BASEBOARD_FAB2(SCH_1):M_D_VREF
  C4B12    1      A  CAP_A       I179
  C6M1     1      A  CAP_A       I177
  J4B1   146  VREFCA  SCONN288_H44441004_PIP  I111
  J6M1   146  VREFCA  SCONN288_H44441003_PIP  I158
  R6L16    1      A  RES         I12
  R6M1     2      B  RES          I9
  R6M2     2      B  RES         I14

M_E_ACT_N       @BASEBOARD_FAB2_LIB.BASEBOARD_FAB2(SCH_1):M_E_ACT_N
  J4A2    62  ACT_N  SCONN288_H44441004_PIP  I111
  J6L2    62  ACT_N  SCONN288_H44441003_PIP  I12
  U5D1   DR62  DDR4_ACT_N  SKX_EXT_B_BGA1  I172

M_E_ALERT_N     @BASEBOARD_FAB2_LIB.BASEBOARD_FAB2(SCH_1):M_E_ALERT_N
  J4A2   208  ALERT_N  SCONN288_H44441004_PIP  I111
  J6L2   208  ALERT_N  SCONN288_H44441003_PIP  I12
  U5D1   DT61  DDR4_ALERT_N  SKX_EXT_B_BGA1  I172

M_E_BA<0>       @BASEBOARD_FAB2_LIB.BASEBOARD_FAB2(SCH_1):M_E_BA<0>
  J4A2    81  BA<0>  SCONN288_H44441004_PIP  I111
  J6L2    81  BA<0>  SCONN288_H44441003_PIP  I12
  U5D1   DM53  DDR4_BA<0>  SKX_EXT_B_BGA1  I172

M_E_BA<1>       @BASEBOARD_FAB2_LIB.BASEBOARD_FAB2(SCH_1):M_E_BA<1>
  J4A2   224  BA<1>  SCONN288_H44441004_PIP  I111
  J6L2   224  BA<1>  SCONN288_H44441003_PIP  I12
  U5D1   DV55  DDR4_BA<1>  SKX_EXT_B_BGA1  I172

M_E_BG<0>       @BASEBOARD_FAB2_LIB.BASEBOARD_FAB2(SCH_1):M_E_BG<0>
  J4A2    63  BG<0>  SCONN288_H44441004_PIP  I111
  J6L2    63  BG<0>  SCONN288_H44441003_PIP  I12
  U5D1   DJ62  DDR4_BG<0>  SKX_EXT_B_BGA1  I172

M_E_BG<1>       @BASEBOARD_FAB2_LIB.BASEBOARD_FAB2(SCH_1):M_E_BG<1>
  J4A2   207  BG<1>  SCONN288_H44441004_PIP  I111
  J6L2   207  BG<1>  SCONN288_H44441003_PIP  I12
  U5D1   DM61  DDR4_BG<1>  SKX_EXT_B_BGA1  I172

M_E_C<2>        @BASEBOARD_FAB2_LIB.BASEBOARD_FAB2(SCH_1):M_E_C<2>
  J4A2   235   C<2>  SCONN288_H44441004_PIP  I111
  J6L2   235   C<2>  SCONN288_H44441003_PIP  I12
  U5D1   DT47  DDR4_CID<2>  SKX_EXT_B_BGA1  I172

M_E_CKE<0>      @BASEBOARD_FAB2_LIB.BASEBOARD_FAB2(SCH_1):M_E_CKE<0>
  J4A2    60  CKE<0>  SCONN288_H44441004_PIP  I111
  U5D1   DM63  DDR4_CKE<0>  SKX_EXT_B_BGA1  I172

M_E_CKE<1>      @BASEBOARD_FAB2_LIB.BASEBOARD_FAB2(SCH_1):M_E_CKE<1>
  J4A2   203  CKE<1>  SCONN288_H44441004_PIP  I111
  U5D1   DN64  DDR4_CKE<1>  SKX_EXT_B_BGA1  I172

M_E_CKE<2>      @BASEBOARD_FAB2_LIB.BASEBOARD_FAB2(SCH_1):M_E_CKE<2>
  J6L2    60  CKE<0>  SCONN288_H44441003_PIP  I12
  U5D1   DL64  DDR4_CKE<2>  SKX_EXT_B_BGA1  I172

M_E_CKE<3>      @BASEBOARD_FAB2_LIB.BASEBOARD_FAB2(SCH_1):M_E_CKE<3>
  J6L2   203  CKE<1>  SCONN288_H44441003_PIP  I12
  U5D1   DR64  DDR4_CKE<3>  SKX_EXT_B_BGA1  I172

M_E_CLK_DN<0>   @BASEBOARD_FAB2_LIB.BASEBOARD_FAB2(SCH_1):M_E_CLK_DN<0>
  J4A2    75   CK0N  SCONN288_H44441004_PIP  I111
  U5D1   DM55  DDR4_CLK_DN<0>  SKX_EXT_B_BGA1  I172

M_E_CLK_DN<1>   @BASEBOARD_FAB2_LIB.BASEBOARD_FAB2(SCH_1):M_E_CLK_DN<1>
  J4A2   219   CK1N  SCONN288_H44441004_PIP  I111
  U5D1   DR54  DDR4_CLK_DN<1>  SKX_EXT_B_BGA1  I172

M_E_CLK_DN<2>   @BASEBOARD_FAB2_LIB.BASEBOARD_FAB2(SCH_1):M_E_CLK_DN<2>
  J6L2    75   CK0N  SCONN288_H44441003_PIP  I12
  U5D1   DM57  DDR4_CLK_DN<2>  SKX_EXT_B_BGA1  I172

M_E_CLK_DN<3>   @BASEBOARD_FAB2_LIB.BASEBOARD_FAB2(SCH_1):M_E_CLK_DN<3>
  J6L2   219   CK1N  SCONN288_H44441003_PIP  I12
  U5D1   DT57  DDR4_CLK_DN<3>  SKX_EXT_B_BGA1  I172

M_E_CLK_DP<0>   @BASEBOARD_FAB2_LIB.BASEBOARD_FAB2(SCH_1):M_E_CLK_DP<0>
  J4A2    74   CK0P  SCONN288_H44441004_PIP  I111
  U5D1   DN54  DDR4_CLK_DP<0>  SKX_EXT_B_BGA1  I172

M_E_CLK_DP<1>   @BASEBOARD_FAB2_LIB.BASEBOARD_FAB2(SCH_1):M_E_CLK_DP<1>
  J4A2   218   CK1P  SCONN288_H44441004_PIP  I111
  U5D1   DT53  DDR4_CLK_DP<1>  SKX_EXT_B_BGA1  I172

M_E_CLK_DP<2>   @BASEBOARD_FAB2_LIB.BASEBOARD_FAB2(SCH_1):M_E_CLK_DP<2>
  J6L2    74   CK0P  SCONN288_H44441003_PIP  I12
  U5D1   DN56  DDR4_CLK_DP<2>  SKX_EXT_B_BGA1  I172

M_E_CLK_DP<3>   @BASEBOARD_FAB2_LIB.BASEBOARD_FAB2(SCH_1):M_E_CLK_DP<3>
  J6L2   218   CK1P  SCONN288_H44441003_PIP  I12
  U5D1   DR56  DDR4_CLK_DP<3>  SKX_EXT_B_BGA1  I172

M_E_CPU_VREF    @BASEBOARD_FAB2_LIB.BASEBOARD_FAB2(SCH_1):M_E_CPU_VREF
  C6L7     1      A  CAP_A       I59
  R6L14    1      A  RES         I58
  U5D1   CT61  DDR4_CAVREF  SKX_EXT_B_BGA1  I259

M_E_CS_N<0>     @BASEBOARD_FAB2_LIB.BASEBOARD_FAB2(SCH_1):M_E_CS_N<0>
  J4A2    84   S0_N  SCONN288_H44441004_PIP  I111
  U5D1   DV51  DDR4_CS_N<0>  SKX_EXT_B_BGA1  I172

M_E_CS_N<1>     @BASEBOARD_FAB2_LIB.BASEBOARD_FAB2(SCH_1):M_E_CS_N<1>
  J4A2    89   S1_N  SCONN288_H44441004_PIP  I111
  U5D1   DN50  DDR4_CS_N<1>  SKX_EXT_B_BGA1  I172

M_E_CS_N<2>     @BASEBOARD_FAB2_LIB.BASEBOARD_FAB2(SCH_1):M_E_CS_N<2>
  J4A2    93  S2_N_C<0>  SCONN288_H44441004_PIP  I111
  U5D1   DR46  DDR4_CS_N<2>  SKX_EXT_B_BGA1  I172

M_E_CS_N<3>     @BASEBOARD_FAB2_LIB.BASEBOARD_FAB2(SCH_1):M_E_CS_N<3>
  J4A2   237  S3_N_C<1>  SCONN288_H44441004_PIP  I111
  U5D1   DK47  DDR4_CS_N<3>  SKX_EXT_B_BGA1  I172

M_E_CS_N<4>     @BASEBOARD_FAB2_LIB.BASEBOARD_FAB2(SCH_1):M_E_CS_N<4>
  J6L2    84   S0_N  SCONN288_H44441003_PIP  I12
  U5D1   DW50  DDR4_CS_N<4>  SKX_EXT_B_BGA1  I172

M_E_CS_N<5>     @BASEBOARD_FAB2_LIB.BASEBOARD_FAB2(SCH_1):M_E_CS_N<5>
  J6L2    89   S1_N  SCONN288_H44441003_PIP  I12
  U5D1   DM49  DDR4_CS_N<5>  SKX_EXT_B_BGA1  I172

M_E_CS_N<6>     @BASEBOARD_FAB2_LIB.BASEBOARD_FAB2(SCH_1):M_E_CS_N<6>
  J6L2    93  S2_N_C<0>  SCONN288_H44441003_PIP  I12
  U5D1   DT45  DDR4_CS_N<6>  SKX_EXT_B_BGA1  I172

M_E_CS_N<7>     @BASEBOARD_FAB2_LIB.BASEBOARD_FAB2(SCH_1):M_E_CS_N<7>
  J6L2   237  S3_N_C<1>  SCONN288_H44441003_PIP  I12
  U5D1   DN46  DDR4_CS_N<7>  SKX_EXT_B_BGA1  I172

M_E_DQ<0>       @BASEBOARD_FAB2_LIB.BASEBOARD_FAB2(SCH_1):M_E_DQ<0>
  J4A2   150  DQ<1>  SCONN288_H44441004_PIP  I111
  J6L2     5  DQ<0>  SCONN288_H44441003_PIP  I12
  U5D1   CM79  DDR4_DQ<0>  SKX_EXT_B_BGA1  I172

M_E_DQ<1>       @BASEBOARD_FAB2_LIB.BASEBOARD_FAB2(SCH_1):M_E_DQ<1>
  J4A2     5  DQ<0>  SCONN288_H44441004_PIP  I111
  J6L2   150  DQ<1>  SCONN288_H44441003_PIP  I12
  U5D1   CK81  DDR4_DQ<1>  SKX_EXT_B_BGA1  I172

M_E_DQ<2>       @BASEBOARD_FAB2_LIB.BASEBOARD_FAB2(SCH_1):M_E_DQ<2>
  J4A2   157  DQ<3>  SCONN288_H44441004_PIP  I111
  J6L2    12  DQ<2>  SCONN288_H44441003_PIP  I12
  U5D1   CT81  DDR4_DQ<2>  SKX_EXT_B_BGA1  I172

M_E_DQ<3>       @BASEBOARD_FAB2_LIB.BASEBOARD_FAB2(SCH_1):M_E_DQ<3>
  J4A2    12  DQ<2>  SCONN288_H44441004_PIP  I111
  J6L2   157  DQ<3>  SCONN288_H44441003_PIP  I12
  U5D1   CR82  DDR4_DQ<3>  SKX_EXT_B_BGA1  I172

M_E_DQ<4>       @BASEBOARD_FAB2_LIB.BASEBOARD_FAB2(SCH_1):M_E_DQ<4>
  J4A2   148  DQ<5>  SCONN288_H44441004_PIP  I111
  J6L2     3  DQ<4>  SCONN288_H44441003_PIP  I12
  U5D1   CK79  DDR4_DQ<4>  SKX_EXT_B_BGA1  I172

M_E_DQ<5>       @BASEBOARD_FAB2_LIB.BASEBOARD_FAB2(SCH_1):M_E_DQ<5>
  J4A2     3  DQ<4>  SCONN288_H44441004_PIP  I111
  J6L2   148  DQ<5>  SCONN288_H44441003_PIP  I12
  U5D1   CJ80  DDR4_DQ<5>  SKX_EXT_B_BGA1  I172

M_E_DQ<6>       @BASEBOARD_FAB2_LIB.BASEBOARD_FAB2(SCH_1):M_E_DQ<6>
  J4A2   155  DQ<7>  SCONN288_H44441004_PIP  I111
  J6L2    10  DQ<6>  SCONN288_H44441003_PIP  I12
  U5D1   CR80  DDR4_DQ<6>  SKX_EXT_B_BGA1  I172

M_E_DQ<7>       @BASEBOARD_FAB2_LIB.BASEBOARD_FAB2(SCH_1):M_E_DQ<7>
  J4A2    10  DQ<6>  SCONN288_H44441004_PIP  I111
  J6L2   155  DQ<7>  SCONN288_H44441003_PIP  I12
  U5D1   CN82  DDR4_DQ<7>  SKX_EXT_B_BGA1  I172

M_E_DQ<8>       @BASEBOARD_FAB2_LIB.BASEBOARD_FAB2(SCH_1):M_E_DQ<8>
  J4A2   161  DQ<9>  SCONN288_H44441004_PIP  I111
  J6L2    16  DQ<8>  SCONN288_H44441003_PIP  I12
  U5D1   DB79  DDR4_DQ<8>  SKX_EXT_B_BGA1  I172

M_E_DQ<9>       @BASEBOARD_FAB2_LIB.BASEBOARD_FAB2(SCH_1):M_E_DQ<9>
  J4A2    16  DQ<8>  SCONN288_H44441004_PIP  I111
  J6L2   161  DQ<9>  SCONN288_H44441003_PIP  I12
  U5D1   CY81  DDR4_DQ<9>  SKX_EXT_B_BGA1  I172

M_E_DQ<10>      @BASEBOARD_FAB2_LIB.BASEBOARD_FAB2(SCH_1):M_E_DQ<10>
  J4A2   168  DQ<11>  SCONN288_H44441004_PIP  I111
  J6L2    23  DQ<10>  SCONN288_H44441003_PIP  I12
  U5D1   DE80  DDR4_DQ<10>  SKX_EXT_B_BGA1  I172

M_E_DQ<11>      @BASEBOARD_FAB2_LIB.BASEBOARD_FAB2(SCH_1):M_E_DQ<11>
  J4A2    23  DQ<10>  SCONN288_H44441004_PIP  I111
  J6L2   168  DQ<11>  SCONN288_H44441003_PIP  I12
  U5D1   DF81  DDR4_DQ<11>  SKX_EXT_B_BGA1  I172

M_E_DQ<12>      @BASEBOARD_FAB2_LIB.BASEBOARD_FAB2(SCH_1):M_E_DQ<12>
  J4A2   159  DQ<13>  SCONN288_H44441004_PIP  I111
  J6L2    14  DQ<12>  SCONN288_H44441003_PIP  I12
  U5D1   CY79  DDR4_DQ<12>  SKX_EXT_B_BGA1  I172

M_E_DQ<13>      @BASEBOARD_FAB2_LIB.BASEBOARD_FAB2(SCH_1):M_E_DQ<13>
  J4A2    14  DQ<12>  SCONN288_H44441004_PIP  I111
  J6L2   159  DQ<13>  SCONN288_H44441003_PIP  I12
  U5D1   CW80  DDR4_DQ<13>  SKX_EXT_B_BGA1  I172

M_E_DQ<14>      @BASEBOARD_FAB2_LIB.BASEBOARD_FAB2(SCH_1):M_E_DQ<14>
  J4A2   166  DQ<15>  SCONN288_H44441004_PIP  I111
  J6L2    21  DQ<14>  SCONN288_H44441003_PIP  I12
  U5D1   DC82  DDR4_DQ<14>  SKX_EXT_B_BGA1  I172

M_E_DQ<15>      @BASEBOARD_FAB2_LIB.BASEBOARD_FAB2(SCH_1):M_E_DQ<15>
  J4A2    21  DQ<14>  SCONN288_H44441004_PIP  I111
  J6L2   166  DQ<15>  SCONN288_H44441003_PIP  I12
  U5D1   DE82  DDR4_DQ<15>  SKX_EXT_B_BGA1  I172

M_E_DQ<16>      @BASEBOARD_FAB2_LIB.BASEBOARD_FAB2(SCH_1):M_E_DQ<16>
  J4A2   172  DQ<17>  SCONN288_H44441004_PIP  I111
  J6L2    27  DQ<16>  SCONN288_H44441003_PIP  I12
  U5D1   DW80  DDR4_DQ<16>  SKX_EXT_B_BGA1  I172

M_E_DQ<17>      @BASEBOARD_FAB2_LIB.BASEBOARD_FAB2(SCH_1):M_E_DQ<17>
  J4A2    27  DQ<16>  SCONN288_H44441004_PIP  I111
  J6L2   172  DQ<17>  SCONN288_H44441003_PIP  I12
  U5D1   EC80  DDR4_DQ<17>  SKX_EXT_B_BGA1  I172

M_E_DQ<18>      @BASEBOARD_FAB2_LIB.BASEBOARD_FAB2(SCH_1):M_E_DQ<18>
  J4A2   179  DQ<19>  SCONN288_H44441004_PIP  I111
  J6L2    34  DQ<18>  SCONN288_H44441003_PIP  I12
  U5D1   DY77  DDR4_DQ<18>  SKX_EXT_B_BGA1  I172

M_E_DQ<19>      @BASEBOARD_FAB2_LIB.BASEBOARD_FAB2(SCH_1):M_E_DQ<19>
  J4A2    34  DQ<18>  SCONN288_H44441004_PIP  I111
  J6L2   179  DQ<19>  SCONN288_H44441003_PIP  I12
  U5D1   EB77  DDR4_DQ<19>  SKX_EXT_B_BGA1  I172

M_E_DQ<20>      @BASEBOARD_FAB2_LIB.BASEBOARD_FAB2(SCH_1):M_E_DQ<20>
  J4A2   170  DQ<21>  SCONN288_H44441004_PIP  I111
  J6L2    25  DQ<20>  SCONN288_H44441003_PIP  I12
  U5D1   DY81  DDR4_DQ<20>  SKX_EXT_B_BGA1  I172

M_E_DQ<21>      @BASEBOARD_FAB2_LIB.BASEBOARD_FAB2(SCH_1):M_E_DQ<21>
  J4A2    25  DQ<20>  SCONN288_H44441004_PIP  I111
  J6L2   170  DQ<21>  SCONN288_H44441003_PIP  I12
  U5D1   EB81  DDR4_DQ<21>  SKX_EXT_B_BGA1  I172

M_E_DQ<22>      @BASEBOARD_FAB2_LIB.BASEBOARD_FAB2(SCH_1):M_E_DQ<22>
  J4A2   177  DQ<23>  SCONN288_H44441004_PIP  I111
  J6L2    32  DQ<22>  SCONN288_H44441003_PIP  I12
  U5D1   DW78  DDR4_DQ<22>  SKX_EXT_B_BGA1  I172

M_E_DQ<23>      @BASEBOARD_FAB2_LIB.BASEBOARD_FAB2(SCH_1):M_E_DQ<23>
  J4A2    32  DQ<22>  SCONN288_H44441004_PIP  I111
  J6L2   177  DQ<23>  SCONN288_H44441003_PIP  I12
  U5D1   EC78  DDR4_DQ<23>  SKX_EXT_B_BGA1  I172

M_E_DQ<24>      @BASEBOARD_FAB2_LIB.BASEBOARD_FAB2(SCH_1):M_E_DQ<24>
  J4A2   183  DQ<25>  SCONN288_H44441004_PIP  I111
  J6L2    38  DQ<24>  SCONN288_H44441003_PIP  I12
  U5D1   ED75  DDR4_DQ<24>  SKX_EXT_B_BGA1  I172

M_E_DQ<25>      @BASEBOARD_FAB2_LIB.BASEBOARD_FAB2(SCH_1):M_E_DQ<25>
  J4A2    38  DQ<24>  SCONN288_H44441004_PIP  I111
  J6L2   183  DQ<25>  SCONN288_H44441003_PIP  I12
  U5D1   EE74  DDR4_DQ<25>  SKX_EXT_B_BGA1  I172

M_E_DQ<26>      @BASEBOARD_FAB2_LIB.BASEBOARD_FAB2(SCH_1):M_E_DQ<26>
  J4A2   190  DQ<27>  SCONN288_H44441004_PIP  I111
  J6L2    45  DQ<26>  SCONN288_H44441003_PIP  I12
  U5D1   EB71  DDR4_DQ<26>  SKX_EXT_B_BGA1  I172

M_E_DQ<27>      @BASEBOARD_FAB2_LIB.BASEBOARD_FAB2(SCH_1):M_E_DQ<27>
  J4A2    45  DQ<26>  SCONN288_H44441004_PIP  I111
  J6L2   190  DQ<27>  SCONN288_H44441003_PIP  I12
  U5D1   ED71  DDR4_DQ<27>  SKX_EXT_B_BGA1  I172

M_E_DQ<28>      @BASEBOARD_FAB2_LIB.BASEBOARD_FAB2(SCH_1):M_E_DQ<28>
  J4A2   181  DQ<29>  SCONN288_H44441004_PIP  I111
  J6L2    36  DQ<28>  SCONN288_H44441003_PIP  I12
  U5D1   EA74  DDR4_DQ<28>  SKX_EXT_B_BGA1  I172

M_E_DQ<29>      @BASEBOARD_FAB2_LIB.BASEBOARD_FAB2(SCH_1):M_E_DQ<29>
  J4A2    36  DQ<28>  SCONN288_H44441004_PIP  I111
  J6L2   181  DQ<29>  SCONN288_H44441003_PIP  I12
  U5D1   EB75  DDR4_DQ<29>  SKX_EXT_B_BGA1  I172

M_E_DQ<30>      @BASEBOARD_FAB2_LIB.BASEBOARD_FAB2(SCH_1):M_E_DQ<30>
  J4A2   188  DQ<31>  SCONN288_H44441004_PIP  I111
  J6L2    43  DQ<30>  SCONN288_H44441003_PIP  I12
  U5D1   EA72  DDR4_DQ<30>  SKX_EXT_B_BGA1  I172

M_E_DQ<31>      @BASEBOARD_FAB2_LIB.BASEBOARD_FAB2(SCH_1):M_E_DQ<31>
  J4A2    43  DQ<30>  SCONN288_H44441004_PIP  I111
  J6L2   188  DQ<31>  SCONN288_H44441003_PIP  I12
  U5D1   EE72  DDR4_DQ<31>  SKX_EXT_B_BGA1  I172

M_E_DQ<32>      @BASEBOARD_FAB2_LIB.BASEBOARD_FAB2(SCH_1):M_E_DQ<32>
  J4A2   242  DQ<33>  SCONN288_H44441004_PIP  I111
  J6L2    97  DQ<32>  SCONN288_H44441003_PIP  I12
  U5D1   DU42  DDR4_DQ<32>  SKX_EXT_B_BGA1  I172

M_E_DQ<33>      @BASEBOARD_FAB2_LIB.BASEBOARD_FAB2(SCH_1):M_E_DQ<33>
  J4A2    97  DQ<32>  SCONN288_H44441004_PIP  I111
  J6L2   242  DQ<33>  SCONN288_H44441003_PIP  I12
  U5D1   DW42  DDR4_DQ<33>  SKX_EXT_B_BGA1  I172

M_E_DQ<34>      @BASEBOARD_FAB2_LIB.BASEBOARD_FAB2(SCH_1):M_E_DQ<34>
  J4A2   249  DQ<35>  SCONN288_H44441004_PIP  I111
  J6L2   104  DQ<34>  SCONN288_H44441003_PIP  I12
  U5D1   DP39  DDR4_DQ<34>  SKX_EXT_B_BGA1  I172

M_E_DQ<35>      @BASEBOARD_FAB2_LIB.BASEBOARD_FAB2(SCH_1):M_E_DQ<35>
  J4A2   104  DQ<34>  SCONN288_H44441004_PIP  I111
  J6L2   249  DQ<35>  SCONN288_H44441003_PIP  I12
  U5D1   DT39  DDR4_DQ<35>  SKX_EXT_B_BGA1  I172

M_E_DQ<36>      @BASEBOARD_FAB2_LIB.BASEBOARD_FAB2(SCH_1):M_E_DQ<36>
  J4A2   240  DQ<37>  SCONN288_H44441004_PIP  I111
  J6L2    95  DQ<36>  SCONN288_H44441003_PIP  I12
  U5D1   DL42  DDR4_DQ<36>  SKX_EXT_B_BGA1  I172

M_E_DQ<37>      @BASEBOARD_FAB2_LIB.BASEBOARD_FAB2(SCH_1):M_E_DQ<37>
  J4A2    95  DQ<36>  SCONN288_H44441004_PIP  I111
  J6L2   240  DQ<37>  SCONN288_H44441003_PIP  I12
  U5D1   DN42  DDR4_DQ<37>  SKX_EXT_B_BGA1  I172

M_E_DQ<38>      @BASEBOARD_FAB2_LIB.BASEBOARD_FAB2(SCH_1):M_E_DQ<38>
  J4A2   247  DQ<39>  SCONN288_H44441004_PIP  I111
  J6L2   102  DQ<38>  SCONN288_H44441003_PIP  I12
  U5D1   DN40  DDR4_DQ<38>  SKX_EXT_B_BGA1  I172

M_E_DQ<39>      @BASEBOARD_FAB2_LIB.BASEBOARD_FAB2(SCH_1):M_E_DQ<39>
  J4A2   102  DQ<38>  SCONN288_H44441004_PIP  I111
  J6L2   247  DQ<39>  SCONN288_H44441003_PIP  I12
  U5D1   DU40  DDR4_DQ<39>  SKX_EXT_B_BGA1  I172

M_E_DQ<40>      @BASEBOARD_FAB2_LIB.BASEBOARD_FAB2(SCH_1):M_E_DQ<40>
  J4A2   253  DQ<41>  SCONN288_H44441004_PIP  I111
  J6L2   108  DQ<40>  SCONN288_H44441003_PIP  I12
  U5D1   EC34  DDR4_DQ<40>  SKX_EXT_B_BGA1  I172

M_E_DQ<41>      @BASEBOARD_FAB2_LIB.BASEBOARD_FAB2(SCH_1):M_E_DQ<41>
  J4A2   108  DQ<40>  SCONN288_H44441004_PIP  I111
  J6L2   253  DQ<41>  SCONN288_H44441003_PIP  I12
  U5D1   ED33  DDR4_DQ<41>  SKX_EXT_B_BGA1  I172

M_E_DQ<42>      @BASEBOARD_FAB2_LIB.BASEBOARD_FAB2(SCH_1):M_E_DQ<42>
  J4A2   260  DQ<43>  SCONN288_H44441004_PIP  I111
  J6L2   115  DQ<42>  SCONN288_H44441003_PIP  I12
  U5D1   EA30  DDR4_DQ<42>  SKX_EXT_B_BGA1  I172

M_E_DQ<43>      @BASEBOARD_FAB2_LIB.BASEBOARD_FAB2(SCH_1):M_E_DQ<43>
  J4A2   115  DQ<42>  SCONN288_H44441004_PIP  I111
  J6L2   260  DQ<43>  SCONN288_H44441003_PIP  I12
  U5D1   EC30  DDR4_DQ<43>  SKX_EXT_B_BGA1  I172

M_E_DQ<44>      @BASEBOARD_FAB2_LIB.BASEBOARD_FAB2(SCH_1):M_E_DQ<44>
  J4A2   251  DQ<45>  SCONN288_H44441004_PIP  I111
  J6L2   106  DQ<44>  SCONN288_H44441003_PIP  I12
  U5D1   DY33  DDR4_DQ<44>  SKX_EXT_B_BGA1  I172

M_E_DQ<45>      @BASEBOARD_FAB2_LIB.BASEBOARD_FAB2(SCH_1):M_E_DQ<45>
  J4A2   106  DQ<44>  SCONN288_H44441004_PIP  I111
  J6L2   251  DQ<45>  SCONN288_H44441003_PIP  I12
  U5D1   EA34  DDR4_DQ<45>  SKX_EXT_B_BGA1  I172

M_E_DQ<46>      @BASEBOARD_FAB2_LIB.BASEBOARD_FAB2(SCH_1):M_E_DQ<46>
  J4A2   258  DQ<47>  SCONN288_H44441004_PIP  I111
  J6L2   113  DQ<46>  SCONN288_H44441003_PIP  I12
  U5D1   DY31  DDR4_DQ<46>  SKX_EXT_B_BGA1  I172

M_E_DQ<47>      @BASEBOARD_FAB2_LIB.BASEBOARD_FAB2(SCH_1):M_E_DQ<47>
  J4A2   113  DQ<46>  SCONN288_H44441004_PIP  I111
  J6L2   258  DQ<47>  SCONN288_H44441003_PIP  I12
  U5D1   ED31  DDR4_DQ<47>  SKX_EXT_B_BGA1  I172

M_E_DQ<48>      @BASEBOARD_FAB2_LIB.BASEBOARD_FAB2(SCH_1):M_E_DQ<48>
  J4A2   264  DQ<49>  SCONN288_H44441004_PIP  I111
  J6L2   119  DQ<48>  SCONN288_H44441003_PIP  I12
  U5D1   EC28  DDR4_DQ<48>  SKX_EXT_B_BGA1  I172

M_E_DQ<49>      @BASEBOARD_FAB2_LIB.BASEBOARD_FAB2(SCH_1):M_E_DQ<49>
  J4A2   119  DQ<48>  SCONN288_H44441004_PIP  I111
  J6L2   264  DQ<49>  SCONN288_H44441003_PIP  I12
  U5D1   ED27  DDR4_DQ<49>  SKX_EXT_B_BGA1  I172

M_E_DQ<50>      @BASEBOARD_FAB2_LIB.BASEBOARD_FAB2(SCH_1):M_E_DQ<50>
  J4A2   271  DQ<51>  SCONN288_H44441004_PIP  I111
  J6L2   126  DQ<50>  SCONN288_H44441003_PIP  I12
  U5D1   EA24  DDR4_DQ<50>  SKX_EXT_B_BGA1  I172

M_E_DQ<51>      @BASEBOARD_FAB2_LIB.BASEBOARD_FAB2(SCH_1):M_E_DQ<51>
  J4A2   126  DQ<50>  SCONN288_H44441004_PIP  I111
  J6L2   271  DQ<51>  SCONN288_H44441003_PIP  I12
  U5D1   EC24  DDR4_DQ<51>  SKX_EXT_B_BGA1  I172

M_E_DQ<52>      @BASEBOARD_FAB2_LIB.BASEBOARD_FAB2(SCH_1):M_E_DQ<52>
  J4A2   262  DQ<53>  SCONN288_H44441004_PIP  I111
  J6L2   117  DQ<52>  SCONN288_H44441003_PIP  I12
  U5D1   DY27  DDR4_DQ<52>  SKX_EXT_B_BGA1  I172

M_E_DQ<53>      @BASEBOARD_FAB2_LIB.BASEBOARD_FAB2(SCH_1):M_E_DQ<53>
  J4A2   117  DQ<52>  SCONN288_H44441004_PIP  I111
  J6L2   262  DQ<53>  SCONN288_H44441003_PIP  I12
  U5D1   EA28  DDR4_DQ<53>  SKX_EXT_B_BGA1  I172

M_E_DQ<54>      @BASEBOARD_FAB2_LIB.BASEBOARD_FAB2(SCH_1):M_E_DQ<54>
  J4A2   269  DQ<55>  SCONN288_H44441004_PIP  I111
  J6L2   124  DQ<54>  SCONN288_H44441003_PIP  I12
  U5D1   DY25  DDR4_DQ<54>  SKX_EXT_B_BGA1  I172

M_E_DQ<55>      @BASEBOARD_FAB2_LIB.BASEBOARD_FAB2(SCH_1):M_E_DQ<55>
  J4A2   124  DQ<54>  SCONN288_H44441004_PIP  I111
  J6L2   269  DQ<55>  SCONN288_H44441003_PIP  I12
  U5D1   ED25  DDR4_DQ<55>  SKX_EXT_B_BGA1  I172

M_E_DQ<56>      @BASEBOARD_FAB2_LIB.BASEBOARD_FAB2(SCH_1):M_E_DQ<56>
  J4A2   275  DQ<57>  SCONN288_H44441004_PIP  I111
  J6L2   130  DQ<56>  SCONN288_H44441003_PIP  I12
  U5D1   DF27  DDR4_DQ<56>  SKX_EXT_B_BGA1  I172

M_E_DQ<57>      @BASEBOARD_FAB2_LIB.BASEBOARD_FAB2(SCH_1):M_E_DQ<57>
  J4A2   130  DQ<56>  SCONN288_H44441004_PIP  I111
  J6L2   275  DQ<57>  SCONN288_H44441003_PIP  I12
  U5D1   DK27  DDR4_DQ<57>  SKX_EXT_B_BGA1  I172

M_E_DQ<58>      @BASEBOARD_FAB2_LIB.BASEBOARD_FAB2(SCH_1):M_E_DQ<58>
  J4A2   282  DQ<59>  SCONN288_H44441004_PIP  I111
  J6L2   137  DQ<58>  SCONN288_H44441003_PIP  I12
  U5D1   DD25  DDR4_DQ<58>  SKX_EXT_B_BGA1  I172

M_E_DQ<59>      @BASEBOARD_FAB2_LIB.BASEBOARD_FAB2(SCH_1):M_E_DQ<59>
  J4A2   137  DQ<58>  SCONN288_H44441004_PIP  I111
  J6L2   282  DQ<59>  SCONN288_H44441003_PIP  I12
  U5D1   DJ24  DDR4_DQ<59>  SKX_EXT_B_BGA1  I172

M_E_DQ<60>      @BASEBOARD_FAB2_LIB.BASEBOARD_FAB2(SCH_1):M_E_DQ<60>
  J4A2   273  DQ<61>  SCONN288_H44441004_PIP  I111
  J6L2   128  DQ<60>  SCONN288_H44441003_PIP  I12
  U5D1   DG28  DDR4_DQ<60>  SKX_EXT_B_BGA1  I172

M_E_DQ<61>      @BASEBOARD_FAB2_LIB.BASEBOARD_FAB2(SCH_1):M_E_DQ<61>
  J4A2   128  DQ<60>  SCONN288_H44441004_PIP  I111
  J6L2   273  DQ<61>  SCONN288_H44441003_PIP  I12
  U5D1   DJ28  DDR4_DQ<61>  SKX_EXT_B_BGA1  I172

M_E_DQ<62>      @BASEBOARD_FAB2_LIB.BASEBOARD_FAB2(SCH_1):M_E_DQ<62>
  J4A2   280  DQ<63>  SCONN288_H44441004_PIP  I111
  J6L2   135  DQ<62>  SCONN288_H44441003_PIP  I12
  U5D1   DF25  DDR4_DQ<62>  SKX_EXT_B_BGA1  I172

M_E_DQ<63>      @BASEBOARD_FAB2_LIB.BASEBOARD_FAB2(SCH_1):M_E_DQ<63>
  J4A2   135  DQ<62>  SCONN288_H44441004_PIP  I111
  J6L2   280  DQ<63>  SCONN288_H44441003_PIP  I12
  U5D1   DK25  DDR4_DQ<63>  SKX_EXT_B_BGA1  I172

M_E_DQS_DN<0>   @BASEBOARD_FAB2_LIB.BASEBOARD_FAB2(SCH_1):M_E_DQS_DN<0>
  J4A2   152  DQS0N  SCONN288_H44441004_PIP  I66
  J6L2   152  DQS0N  SCONN288_H44441003_PIP  I100
  U5D1   CL82  DDR4_DQS_DN<0>  SKX_EXT_B_BGA1  I172

M_E_DQS_DN<1>   @BASEBOARD_FAB2_LIB.BASEBOARD_FAB2(SCH_1):M_E_DQS_DN<1>
  J4A2   163  DQS1N  SCONN288_H44441004_PIP  I66
  J6L2   163  DQS1N  SCONN288_H44441003_PIP  I100
  U5D1   DA82  DDR4_DQS_DN<1>  SKX_EXT_B_BGA1  I172

M_E_DQS_DN<2>   @BASEBOARD_FAB2_LIB.BASEBOARD_FAB2(SCH_1):M_E_DQS_DN<2>
  J4A2   174  DQS2N  SCONN288_H44441004_PIP  I66
  J6L2   174  DQS2N  SCONN288_H44441003_PIP  I100
  U5D1   ED79  DDR4_DQS_DN<2>  SKX_EXT_B_BGA1  I172

M_E_DQS_DN<3>   @BASEBOARD_FAB2_LIB.BASEBOARD_FAB2(SCH_1):M_E_DQS_DN<3>
  J4A2   185  DQS3N  SCONN288_H44441004_PIP  I66
  J6L2   185  DQS3N  SCONN288_H44441003_PIP  I100
  U5D1   EF73  DDR4_DQS_DN<3>  SKX_EXT_B_BGA1  I172

M_E_DQS_DN<4>   @BASEBOARD_FAB2_LIB.BASEBOARD_FAB2(SCH_1):M_E_DQS_DN<4>
  J4A2   244  DQS4N  SCONN288_H44441004_PIP  I66
  J6L2   244  DQS4N  SCONN288_H44441003_PIP  I100
  U5D1   DV41  DDR4_DQS_DN<4>  SKX_EXT_B_BGA1  I172

M_E_DQS_DN<5>   @BASEBOARD_FAB2_LIB.BASEBOARD_FAB2(SCH_1):M_E_DQS_DN<5>
  J4A2   255  DQS5N  SCONN288_H44441004_PIP  I66
  J6L2   255  DQS5N  SCONN288_H44441003_PIP  I100
  U5D1   EE32  DDR4_DQS_DN<5>  SKX_EXT_B_BGA1  I172

M_E_DQS_DN<6>   @BASEBOARD_FAB2_LIB.BASEBOARD_FAB2(SCH_1):M_E_DQS_DN<6>
  J4A2   266  DQS6N  SCONN288_H44441004_PIP  I66
  J6L2   266  DQS6N  SCONN288_H44441003_PIP  I100
  U5D1   EE26  DDR4_DQS_DN<6>  SKX_EXT_B_BGA1  I172

M_E_DQS_DN<7>   @BASEBOARD_FAB2_LIB.BASEBOARD_FAB2(SCH_1):M_E_DQS_DN<7>
  J4A2   277  DQS7N  SCONN288_H44441004_PIP  I66
  J6L2   277  DQS7N  SCONN288_H44441003_PIP  I100
  U5D1   DL26  DDR4_DQS_DN<7>  SKX_EXT_B_BGA1  I172

M_E_DQS_DN<8>   @BASEBOARD_FAB2_LIB.BASEBOARD_FAB2(SCH_1):M_E_DQS_DN<8>
  J4A2   196  DQS8N  SCONN288_H44441004_PIP  I66
  J6L2   196  DQS8N  SCONN288_H44441003_PIP  I100
  U5D1   EB67  DDR4_DQS_DN<8>  SKX_EXT_B_BGA1  I172

M_E_DQS_DN<9>   @BASEBOARD_FAB2_LIB.BASEBOARD_FAB2(SCH_1):M_E_DQS_DN<9>
  J4A2     8  DQS9N  SCONN288_H44441004_PIP  I66
  J6L2     8  DQS9N  SCONN288_H44441003_PIP  I100
  U5D1   CN80  DDR4_DQS_DN<9>  SKX_EXT_B_BGA1  I172

M_E_DQS_DN<10>   @BASEBOARD_FAB2_LIB.BASEBOARD_FAB2(SCH_1):M_E_DQS_DN<10>
  J4A2    19  DQS10N  SCONN288_H44441004_PIP  I66
  J6L2    19  DQS10N  SCONN288_H44441003_PIP  I100
  U5D1   DC80  DDR4_DQS_DN<10>  SKX_EXT_B_BGA1  I172

M_E_DQS_DN<11>   @BASEBOARD_FAB2_LIB.BASEBOARD_FAB2(SCH_1):M_E_DQS_DN<11>
  J4A2    30  DQS11N  SCONN288_H44441004_PIP  I66
  J6L2    30  DQS11N  SCONN288_H44441003_PIP  I100
  U5D1   DY79  DDR4_DQS_DN<11>  SKX_EXT_B_BGA1  I172

M_E_DQS_DN<12>   @BASEBOARD_FAB2_LIB.BASEBOARD_FAB2(SCH_1):M_E_DQS_DN<12>
  J4A2    41  DQS12N  SCONN288_H44441004_PIP  I66
  J6L2    41  DQS12N  SCONN288_H44441003_PIP  I100
  U5D1   EB73  DDR4_DQS_DN<12>  SKX_EXT_B_BGA1  I172

M_E_DQS_DN<13>   @BASEBOARD_FAB2_LIB.BASEBOARD_FAB2(SCH_1):M_E_DQS_DN<13>
  J4A2   100  DQS13N  SCONN288_H44441004_PIP  I66
  J6L2   100  DQS13N  SCONN288_H44441003_PIP  I100
  U5D1   DP41  DDR4_DQS_DN<13>  SKX_EXT_B_BGA1  I172

M_E_DQS_DN<14>   @BASEBOARD_FAB2_LIB.BASEBOARD_FAB2(SCH_1):M_E_DQS_DN<14>
  J4A2   111  DQS14N  SCONN288_H44441004_PIP  I66
  J6L2   111  DQS14N  SCONN288_H44441003_PIP  I100
  U5D1   EA32  DDR4_DQS_DN<14>  SKX_EXT_B_BGA1  I172

M_E_DQS_DN<15>   @BASEBOARD_FAB2_LIB.BASEBOARD_FAB2(SCH_1):M_E_DQS_DN<15>
  J4A2   122  DQS15N  SCONN288_H44441004_PIP  I66
  J6L2   122  DQS15N  SCONN288_H44441003_PIP  I100
  U5D1   EA26  DDR4_DQS_DN<15>  SKX_EXT_B_BGA1  I172

M_E_DQS_DN<16>   @BASEBOARD_FAB2_LIB.BASEBOARD_FAB2(SCH_1):M_E_DQS_DN<16>
  J4A2   133  DQS16N  SCONN288_H44441004_PIP  I66
  J6L2   133  DQS16N  SCONN288_H44441003_PIP  I100
  U5D1   DG26  DDR4_DQS_DN<16>  SKX_EXT_B_BGA1  I172

M_E_DQS_DN<17>   @BASEBOARD_FAB2_LIB.BASEBOARD_FAB2(SCH_1):M_E_DQS_DN<17>
  J4A2    52  DQS17N  SCONN288_H44441004_PIP  I66
  J6L2    52  DQS17N  SCONN288_H44441003_PIP  I100
  U5D1   DV67  DDR4_DQS_DN<17>  SKX_EXT_B_BGA1  I172

M_E_DQS_DP<0>   @BASEBOARD_FAB2_LIB.BASEBOARD_FAB2(SCH_1):M_E_DQS_DP<0>
  J4A2   153  DQS0P  SCONN288_H44441004_PIP  I66
  J6L2   153  DQS0P  SCONN288_H44441003_PIP  I100
  U5D1   CM81  DDR4_DQS_DP<0>  SKX_EXT_B_BGA1  I172

M_E_DQS_DP<1>   @BASEBOARD_FAB2_LIB.BASEBOARD_FAB2(SCH_1):M_E_DQS_DP<1>
  J4A2   164  DQS1P  SCONN288_H44441004_PIP  I66
  J6L2   164  DQS1P  SCONN288_H44441003_PIP  I100
  U5D1   DB81  DDR4_DQS_DP<1>  SKX_EXT_B_BGA1  I172

M_E_DQS_DP<2>   @BASEBOARD_FAB2_LIB.BASEBOARD_FAB2(SCH_1):M_E_DQS_DP<2>
  J4A2   175  DQS2P  SCONN288_H44441004_PIP  I66
  J6L2   175  DQS2P  SCONN288_H44441003_PIP  I100
  U5D1   EB79  DDR4_DQS_DP<2>  SKX_EXT_B_BGA1  I172

M_E_DQS_DP<3>   @BASEBOARD_FAB2_LIB.BASEBOARD_FAB2(SCH_1):M_E_DQS_DP<3>
  J4A2   186  DQS3P  SCONN288_H44441004_PIP  I66
  J6L2   186  DQS3P  SCONN288_H44441003_PIP  I100
  U5D1   ED73  DDR4_DQS_DP<3>  SKX_EXT_B_BGA1  I172

M_E_DQS_DP<4>   @BASEBOARD_FAB2_LIB.BASEBOARD_FAB2(SCH_1):M_E_DQS_DP<4>
  J4A2   245  DQS4P  SCONN288_H44441004_PIP  I66
  J6L2   245  DQS4P  SCONN288_H44441003_PIP  I100
  U5D1   DT41  DDR4_DQS_DP<4>  SKX_EXT_B_BGA1  I172

M_E_DQS_DP<5>   @BASEBOARD_FAB2_LIB.BASEBOARD_FAB2(SCH_1):M_E_DQS_DP<5>
  J4A2   256  DQS5P  SCONN288_H44441004_PIP  I66
  J6L2   256  DQS5P  SCONN288_H44441003_PIP  I100
  U5D1   EC32  DDR4_DQS_DP<5>  SKX_EXT_B_BGA1  I172

M_E_DQS_DP<6>   @BASEBOARD_FAB2_LIB.BASEBOARD_FAB2(SCH_1):M_E_DQS_DP<6>
  J4A2   267  DQS6P  SCONN288_H44441004_PIP  I66
  J6L2   267  DQS6P  SCONN288_H44441003_PIP  I100
  U5D1   EC26  DDR4_DQS_DP<6>  SKX_EXT_B_BGA1  I172

M_E_DQS_DP<7>   @BASEBOARD_FAB2_LIB.BASEBOARD_FAB2(SCH_1):M_E_DQS_DP<7>
  J4A2   278  DQS7P  SCONN288_H44441004_PIP  I66
  J6L2   278  DQS7P  SCONN288_H44441003_PIP  I100
  U5D1   DJ26  DDR4_DQS_DP<7>  SKX_EXT_B_BGA1  I172

M_E_DQS_DP<8>   @BASEBOARD_FAB2_LIB.BASEBOARD_FAB2(SCH_1):M_E_DQS_DP<8>
  J4A2   197  DQS8P  SCONN288_H44441004_PIP  I66
  J6L2   197  DQS8P  SCONN288_H44441003_PIP  I100
  U5D1   DY67  DDR4_DQS_DP<8>  SKX_EXT_B_BGA1  I172

M_E_DQS_DP<9>   @BASEBOARD_FAB2_LIB.BASEBOARD_FAB2(SCH_1):M_E_DQS_DP<9>
  J4A2     7  DQS9P  SCONN288_H44441004_PIP  I66
  J6L2     7  DQS9P  SCONN288_H44441003_PIP  I100
  U5D1   CP79  DDR4_DQS_DP<9>  SKX_EXT_B_BGA1  I172

M_E_DQS_DP<10>   @BASEBOARD_FAB2_LIB.BASEBOARD_FAB2(SCH_1):M_E_DQS_DP<10>
  J4A2    18  DQS10P  SCONN288_H44441004_PIP  I66
  J6L2    18  DQS10P  SCONN288_H44441003_PIP  I100
  U5D1   DD79  DDR4_DQS_DP<10>  SKX_EXT_B_BGA1  I172

M_E_DQS_DP<11>   @BASEBOARD_FAB2_LIB.BASEBOARD_FAB2(SCH_1):M_E_DQS_DP<11>
  J4A2    29  DQS11P  SCONN288_H44441004_PIP  I66
  J6L2    29  DQS11P  SCONN288_H44441003_PIP  I100
  U5D1   DV79  DDR4_DQS_DP<11>  SKX_EXT_B_BGA1  I172

M_E_DQS_DP<12>   @BASEBOARD_FAB2_LIB.BASEBOARD_FAB2(SCH_1):M_E_DQS_DP<12>
  J4A2    40  DQS12P  SCONN288_H44441004_PIP  I66
  J6L2    40  DQS12P  SCONN288_H44441003_PIP  I100
  U5D1   DY73  DDR4_DQS_DP<12>  SKX_EXT_B_BGA1  I172

M_E_DQS_DP<13>   @BASEBOARD_FAB2_LIB.BASEBOARD_FAB2(SCH_1):M_E_DQS_DP<13>
  J4A2    99  DQS13P  SCONN288_H44441004_PIP  I66
  J6L2    99  DQS13P  SCONN288_H44441003_PIP  I100
  U5D1   DM41  DDR4_DQS_DP<13>  SKX_EXT_B_BGA1  I172

M_E_DQS_DP<14>   @BASEBOARD_FAB2_LIB.BASEBOARD_FAB2(SCH_1):M_E_DQS_DP<14>
  J4A2   110  DQS14P  SCONN288_H44441004_PIP  I66
  J6L2   110  DQS14P  SCONN288_H44441003_PIP  I100
  U5D1   DW32  DDR4_DQS_DP<14>  SKX_EXT_B_BGA1  I172

M_E_DQS_DP<15>   @BASEBOARD_FAB2_LIB.BASEBOARD_FAB2(SCH_1):M_E_DQS_DP<15>
  J4A2   121  DQS15P  SCONN288_H44441004_PIP  I66
  J6L2   121  DQS15P  SCONN288_H44441003_PIP  I100
  U5D1   DW26  DDR4_DQS_DP<15>  SKX_EXT_B_BGA1  I172

M_E_DQS_DP<16>   @BASEBOARD_FAB2_LIB.BASEBOARD_FAB2(SCH_1):M_E_DQS_DP<16>
  J4A2   132  DQS16P  SCONN288_H44441004_PIP  I66
  J6L2   132  DQS16P  SCONN288_H44441003_PIP  I100
  U5D1   DE26  DDR4_DQS_DP<16>  SKX_EXT_B_BGA1  I172

M_E_DQS_DP<17>   @BASEBOARD_FAB2_LIB.BASEBOARD_FAB2(SCH_1):M_E_DQS_DP<17>
  J4A2    51  DQS17P  SCONN288_H44441004_PIP  I66
  J6L2    51  DQS17P  SCONN288_H44441003_PIP  I100
  U5D1   DT67  DDR4_DQS_DP<17>  SKX_EXT_B_BGA1  I172

M_E_ECC<0>      @BASEBOARD_FAB2_LIB.BASEBOARD_FAB2(SCH_1):M_E_ECC<0>
  J4A2   194  CB<1>  SCONN288_H44441004_PIP  I111
  J6L2    49  CB<0>  SCONN288_H44441003_PIP  I12
  U5D1   DY69  DDR4_ECC<0>  SKX_EXT_B_BGA1  I172

M_E_ECC<1>      @BASEBOARD_FAB2_LIB.BASEBOARD_FAB2(SCH_1):M_E_ECC<1>
  J4A2    49  CB<0>  SCONN288_H44441004_PIP  I111
  J6L2   194  CB<1>  SCONN288_H44441003_PIP  I12
  U5D1   EA68  DDR4_ECC<1>  SKX_EXT_B_BGA1  I172

M_E_ECC<2>      @BASEBOARD_FAB2_LIB.BASEBOARD_FAB2(SCH_1):M_E_ECC<2>
  J4A2   201  CB<3>  SCONN288_H44441004_PIP  I111
  J6L2    56  CB<2>  SCONN288_H44441003_PIP  I12
  U5D1   DV65  DDR4_ECC<2>  SKX_EXT_B_BGA1  I172

M_E_ECC<3>      @BASEBOARD_FAB2_LIB.BASEBOARD_FAB2(SCH_1):M_E_ECC<3>
  J4A2    56  CB<2>  SCONN288_H44441004_PIP  I111
  J6L2   201  CB<3>  SCONN288_H44441003_PIP  I12
  U5D1   DY65  DDR4_ECC<3>  SKX_EXT_B_BGA1  I172

M_E_ECC<4>      @BASEBOARD_FAB2_LIB.BASEBOARD_FAB2(SCH_1):M_E_ECC<4>
  J4A2   192  CB<5>  SCONN288_H44441004_PIP  I111
  J6L2    47  CB<4>  SCONN288_H44441003_PIP  I12
  U5D1   DU68  DDR4_ECC<4>  SKX_EXT_B_BGA1  I172

M_E_ECC<5>      @BASEBOARD_FAB2_LIB.BASEBOARD_FAB2(SCH_1):M_E_ECC<5>
  J4A2    47  CB<4>  SCONN288_H44441004_PIP  I111
  J6L2   192  CB<5>  SCONN288_H44441003_PIP  I12
  U5D1   DV69  DDR4_ECC<5>  SKX_EXT_B_BGA1  I172

M_E_ECC<6>      @BASEBOARD_FAB2_LIB.BASEBOARD_FAB2(SCH_1):M_E_ECC<6>
  J4A2   199  CB<7>  SCONN288_H44441004_PIP  I111
  J6L2    54  CB<6>  SCONN288_H44441003_PIP  I12
  U5D1   DU66  DDR4_ECC<6>  SKX_EXT_B_BGA1  I172

M_E_ECC<7>      @BASEBOARD_FAB2_LIB.BASEBOARD_FAB2(SCH_1):M_E_ECC<7>
  J4A2    54  CB<6>  SCONN288_H44441004_PIP  I111
  J6L2   199  CB<7>  SCONN288_H44441003_PIP  I12
  U5D1   EA66  DDR4_ECC<7>  SKX_EXT_B_BGA1  I172

M_E_MA<0>       @BASEBOARD_FAB2_LIB.BASEBOARD_FAB2(SCH_1):M_E_MA<0>
  J4A2    79     A0  SCONN288_H44441004_PIP  I111
  J6L2    79     A0  SCONN288_H44441003_PIP  I12
  U5D1   DW52  DDR4_MA<0>  SKX_EXT_B_BGA1  I172

M_E_MA<1>       @BASEBOARD_FAB2_LIB.BASEBOARD_FAB2(SCH_1):M_E_MA<1>
  J4A2    72     A1  SCONN288_H44441004_PIP  I111
  J6L2    72     A1  SCONN288_H44441003_PIP  I12
  U5D1   DW58  DDR4_MA<1>  SKX_EXT_B_BGA1  I172

M_E_MA<2>       @BASEBOARD_FAB2_LIB.BASEBOARD_FAB2(SCH_1):M_E_MA<2>
  J4A2   216     A2  SCONN288_H44441004_PIP  I111
  J6L2   216     A2  SCONN288_H44441003_PIP  I12
  U5D1   DV57  DDR4_MA<2>  SKX_EXT_B_BGA1  I172

M_E_MA<3>       @BASEBOARD_FAB2_LIB.BASEBOARD_FAB2(SCH_1):M_E_MA<3>
  J4A2    71     A3  SCONN288_H44441004_PIP  I111
  J6L2    71     A3  SCONN288_H44441003_PIP  I12
  U5D1   DR58  DDR4_MA<3>  SKX_EXT_B_BGA1  I172

M_E_MA<4>       @BASEBOARD_FAB2_LIB.BASEBOARD_FAB2(SCH_1):M_E_MA<4>
  J4A2   214     A4  SCONN288_H44441004_PIP  I111
  J6L2   214     A4  SCONN288_H44441003_PIP  I12
  U5D1   DT59  DDR4_MA<4>  SKX_EXT_B_BGA1  I172

M_E_MA<5>       @BASEBOARD_FAB2_LIB.BASEBOARD_FAB2(SCH_1):M_E_MA<5>
  J4A2   213     A5  SCONN288_H44441004_PIP  I111
  J6L2   213     A5  SCONN288_H44441003_PIP  I12
  U5D1   DN58  DDR4_MA<5>  SKX_EXT_B_BGA1  I172

M_E_MA<6>       @BASEBOARD_FAB2_LIB.BASEBOARD_FAB2(SCH_1):M_E_MA<6>
  J4A2    69     A6  SCONN288_H44441004_PIP  I111
  J6L2    69     A6  SCONN288_H44441003_PIP  I12
  U5D1   DM59  DDR4_MA<6>  SKX_EXT_B_BGA1  I172

M_E_MA<7>       @BASEBOARD_FAB2_LIB.BASEBOARD_FAB2(SCH_1):M_E_MA<7>
  J4A2   211     A7  SCONN288_H44441004_PIP  I111
  J6L2   211     A7  SCONN288_H44441003_PIP  I12
  U5D1   DK61  DDR4_MA<7>  SKX_EXT_B_BGA1  I172

M_E_MA<8>       @BASEBOARD_FAB2_LIB.BASEBOARD_FAB2(SCH_1):M_E_MA<8>
  J4A2    68     A8  SCONN288_H44441004_PIP  I111
  J6L2    68     A8  SCONN288_H44441003_PIP  I12
  U5D1   DJ60  DDR4_MA<8>  SKX_EXT_B_BGA1  I172

M_E_MA<9>       @BASEBOARD_FAB2_LIB.BASEBOARD_FAB2(SCH_1):M_E_MA<9>
  J4A2    66     A9  SCONN288_H44441004_PIP  I111
  J6L2    66     A9  SCONN288_H44441003_PIP  I12
  U5D1   DV59  DDR4_MA<9>  SKX_EXT_B_BGA1  I172

M_E_MA<10>      @BASEBOARD_FAB2_LIB.BASEBOARD_FAB2(SCH_1):M_E_MA<10>
  J4A2   225    A10  SCONN288_H44441004_PIP  I111
  J6L2   225    A10  SCONN288_H44441003_PIP  I12
  U5D1   DT55  DDR4_MA<10>  SKX_EXT_B_BGA1  I172

M_E_MA<11>      @BASEBOARD_FAB2_LIB.BASEBOARD_FAB2(SCH_1):M_E_MA<11>
  J4A2   210    A11  SCONN288_H44441004_PIP  I111
  J6L2   210    A11  SCONN288_H44441003_PIP  I12
  U5D1   DR60  DDR4_MA<11>  SKX_EXT_B_BGA1  I172

M_E_MA<12>      @BASEBOARD_FAB2_LIB.BASEBOARD_FAB2(SCH_1):M_E_MA<12>
  J4A2    65    A12  SCONN288_H44441004_PIP  I111
  J6L2    65    A12  SCONN288_H44441003_PIP  I12
  U5D1   DN60  DDR4_MA<12>  SKX_EXT_B_BGA1  I172

M_E_MA<13>      @BASEBOARD_FAB2_LIB.BASEBOARD_FAB2(SCH_1):M_E_MA<13>
  J4A2   232    A13  SCONN288_H44441004_PIP  I111
  J6L2   232    A13  SCONN288_H44441003_PIP  I12
  U5D1   DT51  DDR4_MA<13>  SKX_EXT_B_BGA1  I172

M_E_MA<14>      @BASEBOARD_FAB2_LIB.BASEBOARD_FAB2(SCH_1):M_E_MA<14>
  J4A2   228  A14_WE_N  SCONN288_H44441004_PIP  I111
  J6L2   228  A14_WE_N  SCONN288_H44441003_PIP  I12
  U5D1   DM51  DDR4_MA<14>  SKX_EXT_B_BGA1  I172

M_E_MA<15>      @BASEBOARD_FAB2_LIB.BASEBOARD_FAB2(SCH_1):M_E_MA<15>
  J4A2    86  A15_CAS_N  SCONN288_H44441004_PIP  I111
  J6L2    86  A15_CAS_N  SCONN288_H44441003_PIP  I12
  U5D1   DR52  DDR4_MA<15>  SKX_EXT_B_BGA1  I172

M_E_MA<16>      @BASEBOARD_FAB2_LIB.BASEBOARD_FAB2(SCH_1):M_E_MA<16>
  J4A2    82  A16_RAS_N  SCONN288_H44441004_PIP  I111
  J6L2    82  A16_RAS_N  SCONN288_H44441003_PIP  I12
  U5D1   DN52  DDR4_MA<16>  SKX_EXT_B_BGA1  I172

M_E_MA<17>      @BASEBOARD_FAB2_LIB.BASEBOARD_FAB2(SCH_1):M_E_MA<17>
  J4A2   234    A17  SCONN288_H44441004_PIP  I111
  J6L2   234    A17  SCONN288_H44441003_PIP  I12
  U5D1   DR48  DDR4_MA<17>  SKX_EXT_B_BGA1  I172

M_E_ODT<0>      @BASEBOARD_FAB2_LIB.BASEBOARD_FAB2(SCH_1):M_E_ODT<0>
  J4A2    87  ODT<0>  SCONN288_H44441004_PIP  I111
  U5D1   DR50  DDR4_ODT<0>  SKX_EXT_B_BGA1  I172

M_E_ODT<1>      @BASEBOARD_FAB2_LIB.BASEBOARD_FAB2(SCH_1):M_E_ODT<1>
  J4A2    91  ODT<1>  SCONN288_H44441004_PIP  I111
  U5D1   DN48  DDR4_ODT<1>  SKX_EXT_B_BGA1  I172

M_E_ODT<2>      @BASEBOARD_FAB2_LIB.BASEBOARD_FAB2(SCH_1):M_E_ODT<2>
  J6L2    87  ODT<0>  SCONN288_H44441003_PIP  I12
  U5D1   DT49  DDR4_ODT<2>  SKX_EXT_B_BGA1  I172

M_E_ODT<3>      @BASEBOARD_FAB2_LIB.BASEBOARD_FAB2(SCH_1):M_E_ODT<3>
  J6L2    91  ODT<1>  SCONN288_H44441003_PIP  I12
  U5D1   DM47  DDR4_ODT<3>  SKX_EXT_B_BGA1  I172

M_E_PAR         @BASEBOARD_FAB2_LIB.BASEBOARD_FAB2(SCH_1):M_E_PAR
  J4A2   222    PAR  SCONN288_H44441004_PIP  I111
  J6L2   222    PAR  SCONN288_H44441003_PIP  I12
  U5D1   DV53  DDR4_PAR  SKX_EXT_B_BGA1  I172

M_E_VREF        @BASEBOARD_FAB2_LIB.BASEBOARD_FAB2(SCH_1):M_E_VREF
  C4A18    1      A  CAP_A        I3
  C6L6     1      A  CAP_A       I175
  J4A2   146  VREFCA  SCONN288_H44441004_PIP  I111
  J6L2   146  VREFCA  SCONN288_H44441003_PIP  I12
  R6L12    1      A  RES         I56
  R6L13    2      B  RES         I54
  R6L14    2      B  RES         I58

M_F_ACT_N       @BASEBOARD_FAB2_LIB.BASEBOARD_FAB2(SCH_1):M_F_ACT_N
  J4A1    62  ACT_N  SCONN288_H44441004_PIP  I111
  J6L1    62  ACT_N  SCONN288_H44441003_PIP  I111
  U5D1   DC62  DDR5_ACT_N  SKX_EXT_B_BGA1  I172

M_F_ALERT_N     @BASEBOARD_FAB2_LIB.BASEBOARD_FAB2(SCH_1):M_F_ALERT_N
  J4A1   208  ALERT_N  SCONN288_H44441004_PIP  I111
  J6L1   208  ALERT_N  SCONN288_H44441003_PIP  I111
  U5D1   DD61  DDR5_ALERT_N  SKX_EXT_B_BGA1  I172

M_F_BA<0>       @BASEBOARD_FAB2_LIB.BASEBOARD_FAB2(SCH_1):M_F_BA<0>
  J4A1    81  BA<0>  SCONN288_H44441004_PIP  I111
  J6L1    81  BA<0>  SCONN288_H44441003_PIP  I111
  U5D1   DJ52  DDR5_BA<0>  SKX_EXT_B_BGA1  I172

M_F_BA<1>       @BASEBOARD_FAB2_LIB.BASEBOARD_FAB2(SCH_1):M_F_BA<1>
  J4A1   224  BA<1>  SCONN288_H44441004_PIP  I111
  J6L1   224  BA<1>  SCONN288_H44441003_PIP  I111
  U5D1   DC56  DDR5_BA<1>  SKX_EXT_B_BGA1  I172

M_F_BG<0>       @BASEBOARD_FAB2_LIB.BASEBOARD_FAB2(SCH_1):M_F_BG<0>
  J4A1    63  BG<0>  SCONN288_H44441004_PIP  I111
  J6L1    63  BG<0>  SCONN288_H44441003_PIP  I111
  U5D1   DA62  DDR5_BG<0>  SKX_EXT_B_BGA1  I172

M_F_BG<1>       @BASEBOARD_FAB2_LIB.BASEBOARD_FAB2(SCH_1):M_F_BG<1>
  J4A1   207  BG<1>  SCONN288_H44441004_PIP  I111
  J6L1   207  BG<1>  SCONN288_H44441003_PIP  I111
  U5D1   DF61  DDR5_BG<1>  SKX_EXT_B_BGA1  I172

M_F_C<2>        @BASEBOARD_FAB2_LIB.BASEBOARD_FAB2(SCH_1):M_F_C<2>
  J4A1   235   C<2>  SCONN288_H44441004_PIP  I111
  J6L1   235   C<2>  SCONN288_H44441003_PIP  I111
  U5D1   DF45  DDR5_CID<2>  SKX_EXT_B_BGA1  I172

M_F_CKE<0>      @BASEBOARD_FAB2_LIB.BASEBOARD_FAB2(SCH_1):M_F_CKE<0>
  J4A1    60  CKE<0>  SCONN288_H44441004_PIP  I111
  U5D1   DG62  DDR5_CKE<0>  SKX_EXT_B_BGA1  I172

M_F_CKE<1>      @BASEBOARD_FAB2_LIB.BASEBOARD_FAB2(SCH_1):M_F_CKE<1>
  J4A1   203  CKE<1>  SCONN288_H44441004_PIP  I111
  U5D1   DD63  DDR5_CKE<1>  SKX_EXT_B_BGA1  I172

M_F_CKE<2>      @BASEBOARD_FAB2_LIB.BASEBOARD_FAB2(SCH_1):M_F_CKE<2>
  J6L1    60  CKE<0>  SCONN288_H44441003_PIP  I111
  U5D1   DK63  DDR5_CKE<2>  SKX_EXT_B_BGA1  I172

M_F_CKE<3>      @BASEBOARD_FAB2_LIB.BASEBOARD_FAB2(SCH_1):M_F_CKE<3>
  J6L1   203  CKE<1>  SCONN288_H44441003_PIP  I111
  U5D1   DF63  DDR5_CKE<3>  SKX_EXT_B_BGA1  I172

M_F_CLK_DN<0>   @BASEBOARD_FAB2_LIB.BASEBOARD_FAB2(SCH_1):M_F_CLK_DN<0>
  J4A1    75   CK0N  SCONN288_H44441004_PIP  I111
  U5D1   DK55  DDR5_CLK_DN<0>  SKX_EXT_B_BGA1  I172

M_F_CLK_DN<1>   @BASEBOARD_FAB2_LIB.BASEBOARD_FAB2(SCH_1):M_F_CLK_DN<1>
  J4A1   219   CK1N  SCONN288_H44441004_PIP  I111
  U5D1   DF55  DDR5_CLK_DN<1>  SKX_EXT_B_BGA1  I172

M_F_CLK_DN<2>   @BASEBOARD_FAB2_LIB.BASEBOARD_FAB2(SCH_1):M_F_CLK_DN<2>
  J6L1    75   CK0N  SCONN288_H44441003_PIP  I111
  U5D1   DK57  DDR5_CLK_DN<2>  SKX_EXT_B_BGA1  I172

M_F_CLK_DN<3>   @BASEBOARD_FAB2_LIB.BASEBOARD_FAB2(SCH_1):M_F_CLK_DN<3>
  J6L1   219   CK1N  SCONN288_H44441003_PIP  I111
  U5D1   DF57  DDR5_CLK_DN<3>  SKX_EXT_B_BGA1  I172

M_F_CLK_DP<0>   @BASEBOARD_FAB2_LIB.BASEBOARD_FAB2(SCH_1):M_F_CLK_DP<0>
  J4A1    74   CK0P  SCONN288_H44441004_PIP  I111
  U5D1   DJ54  DDR5_CLK_DP<0>  SKX_EXT_B_BGA1  I172

M_F_CLK_DP<1>   @BASEBOARD_FAB2_LIB.BASEBOARD_FAB2(SCH_1):M_F_CLK_DP<1>
  J4A1   218   CK1P  SCONN288_H44441004_PIP  I111
  U5D1   DG54  DDR5_CLK_DP<1>  SKX_EXT_B_BGA1  I172

M_F_CLK_DP<2>   @BASEBOARD_FAB2_LIB.BASEBOARD_FAB2(SCH_1):M_F_CLK_DP<2>
  J6L1    74   CK0P  SCONN288_H44441003_PIP  I111
  U5D1   DJ56  DDR5_CLK_DP<2>  SKX_EXT_B_BGA1  I172

M_F_CLK_DP<3>   @BASEBOARD_FAB2_LIB.BASEBOARD_FAB2(SCH_1):M_F_CLK_DP<3>
  J6L1   218   CK1P  SCONN288_H44441003_PIP  I111
  U5D1   DG56  DDR5_CLK_DP<3>  SKX_EXT_B_BGA1  I172

M_F_CPU_VREF    @BASEBOARD_FAB2_LIB.BASEBOARD_FAB2(SCH_1):M_F_CPU_VREF
  C6L2     1      A  CAP_A       I67
  R6L3     1      A  RES         I66
  U5D1   CV61  DDR5_CAVREF  SKX_EXT_B_BGA1  I259

M_F_CS_N<0>     @BASEBOARD_FAB2_LIB.BASEBOARD_FAB2(SCH_1):M_F_CS_N<0>
  J4A1    84   S0_N  SCONN288_H44441004_PIP  I111
  U5D1   DK51  DDR5_CS_N<0>  SKX_EXT_B_BGA1  I172

M_F_CS_N<1>     @BASEBOARD_FAB2_LIB.BASEBOARD_FAB2(SCH_1):M_F_CS_N<1>
  J4A1    89   S1_N  SCONN288_H44441004_PIP  I111
  U5D1   DF49  DDR5_CS_N<1>  SKX_EXT_B_BGA1  I172

M_F_CS_N<2>     @BASEBOARD_FAB2_LIB.BASEBOARD_FAB2(SCH_1):M_F_CS_N<2>
  J4A1    93  S2_N_C<0>  SCONN288_H44441004_PIP  I111
  U5D1   DJ46  DDR5_CS_N<2>  SKX_EXT_B_BGA1  I172

M_F_CS_N<3>     @BASEBOARD_FAB2_LIB.BASEBOARD_FAB2(SCH_1):M_F_CS_N<3>
  J4A1   237  S3_N_C<1>  SCONN288_H44441004_PIP  I111
  U5D1   DG46  DDR5_CS_N<3>  SKX_EXT_B_BGA1  I172

M_F_CS_N<4>     @BASEBOARD_FAB2_LIB.BASEBOARD_FAB2(SCH_1):M_F_CS_N<4>
  J6L1    84   S0_N  SCONN288_H44441003_PIP  I111
  U5D1   DF51  DDR5_CS_N<4>  SKX_EXT_B_BGA1  I172

M_F_CS_N<5>     @BASEBOARD_FAB2_LIB.BASEBOARD_FAB2(SCH_1):M_F_CS_N<5>
  J6L1    89   S1_N  SCONN288_H44441003_PIP  I111
  U5D1   DJ48  DDR5_CS_N<5>  SKX_EXT_B_BGA1  I172

M_F_CS_N<6>     @BASEBOARD_FAB2_LIB.BASEBOARD_FAB2(SCH_1):M_F_CS_N<6>
  J6L1    93  S2_N_C<0>  SCONN288_H44441003_PIP  I111
  U5D1   DM45  DDR5_CS_N<6>  SKX_EXT_B_BGA1  I172

M_F_CS_N<7>     @BASEBOARD_FAB2_LIB.BASEBOARD_FAB2(SCH_1):M_F_CS_N<7>
  J6L1   237  S3_N_C<1>  SCONN288_H44441003_PIP  I111
  U5D1   DK45  DDR5_CS_N<7>  SKX_EXT_B_BGA1  I172

M_F_DQ<0>       @BASEBOARD_FAB2_LIB.BASEBOARD_FAB2(SCH_1):M_F_DQ<0>
  J4A1   150  DQ<1>  SCONN288_H44441004_PIP  I111
  J6L1     5  DQ<0>  SCONN288_H44441003_PIP  I111
  U5D1   CR74  DDR5_DQ<0>  SKX_EXT_B_BGA1  I172

M_F_DQ<1>       @BASEBOARD_FAB2_LIB.BASEBOARD_FAB2(SCH_1):M_F_DQ<1>
  J4A1     5  DQ<0>  SCONN288_H44441004_PIP  I111
  J6L1   150  DQ<1>  SCONN288_H44441003_PIP  I111
  U5D1   CN76  DDR5_DQ<1>  SKX_EXT_B_BGA1  I172

M_F_DQ<2>       @BASEBOARD_FAB2_LIB.BASEBOARD_FAB2(SCH_1):M_F_DQ<2>
  J4A1   157  DQ<3>  SCONN288_H44441004_PIP  I111
  J6L1    12  DQ<2>  SCONN288_H44441003_PIP  I111
  U5D1   CW76  DDR5_DQ<2>  SKX_EXT_B_BGA1  I172

M_F_DQ<3>       @BASEBOARD_FAB2_LIB.BASEBOARD_FAB2(SCH_1):M_F_DQ<3>
  J4A1    12  DQ<2>  SCONN288_H44441004_PIP  I111
  J6L1   157  DQ<3>  SCONN288_H44441003_PIP  I111
  U5D1   CV77  DDR5_DQ<3>  SKX_EXT_B_BGA1  I172

M_F_DQ<4>       @BASEBOARD_FAB2_LIB.BASEBOARD_FAB2(SCH_1):M_F_DQ<4>
  J4A1   148  DQ<5>  SCONN288_H44441004_PIP  I111
  J6L1     3  DQ<4>  SCONN288_H44441003_PIP  I111
  U5D1   CN74  DDR5_DQ<4>  SKX_EXT_B_BGA1  I172

M_F_DQ<5>       @BASEBOARD_FAB2_LIB.BASEBOARD_FAB2(SCH_1):M_F_DQ<5>
  J4A1     3  DQ<4>  SCONN288_H44441004_PIP  I111
  J6L1   148  DQ<5>  SCONN288_H44441003_PIP  I111
  U5D1   CM75  DDR5_DQ<5>  SKX_EXT_B_BGA1  I172

M_F_DQ<6>       @BASEBOARD_FAB2_LIB.BASEBOARD_FAB2(SCH_1):M_F_DQ<6>
  J4A1   155  DQ<7>  SCONN288_H44441004_PIP  I111
  J6L1    10  DQ<6>  SCONN288_H44441003_PIP  I111
  U5D1   CV75  DDR5_DQ<6>  SKX_EXT_B_BGA1  I172

M_F_DQ<7>       @BASEBOARD_FAB2_LIB.BASEBOARD_FAB2(SCH_1):M_F_DQ<7>
  J4A1    10  DQ<6>  SCONN288_H44441004_PIP  I111
  J6L1   155  DQ<7>  SCONN288_H44441003_PIP  I111
  U5D1   CT77  DDR5_DQ<7>  SKX_EXT_B_BGA1  I172

M_F_DQ<8>       @BASEBOARD_FAB2_LIB.BASEBOARD_FAB2(SCH_1):M_F_DQ<8>
  J4A1   161  DQ<9>  SCONN288_H44441004_PIP  I111
  J6L1    16  DQ<8>  SCONN288_H44441003_PIP  I111
  U5D1   DE74  DDR5_DQ<8>  SKX_EXT_B_BGA1  I172

M_F_DQ<9>       @BASEBOARD_FAB2_LIB.BASEBOARD_FAB2(SCH_1):M_F_DQ<9>
  J4A1    16  DQ<8>  SCONN288_H44441004_PIP  I111
  J6L1   161  DQ<9>  SCONN288_H44441003_PIP  I111
  U5D1   DC76  DDR5_DQ<9>  SKX_EXT_B_BGA1  I172

M_F_DQ<10>      @BASEBOARD_FAB2_LIB.BASEBOARD_FAB2(SCH_1):M_F_DQ<10>
  J4A1   168  DQ<11>  SCONN288_H44441004_PIP  I111
  J6L1    23  DQ<10>  SCONN288_H44441003_PIP  I111
  U5D1   DH75  DDR5_DQ<10>  SKX_EXT_B_BGA1  I172

M_F_DQ<11>      @BASEBOARD_FAB2_LIB.BASEBOARD_FAB2(SCH_1):M_F_DQ<11>
  J4A1    23  DQ<10>  SCONN288_H44441004_PIP  I111
  J6L1   168  DQ<11>  SCONN288_H44441003_PIP  I111
  U5D1   DJ76  DDR5_DQ<11>  SKX_EXT_B_BGA1  I172

M_F_DQ<12>      @BASEBOARD_FAB2_LIB.BASEBOARD_FAB2(SCH_1):M_F_DQ<12>
  J4A1   159  DQ<13>  SCONN288_H44441004_PIP  I111
  J6L1    14  DQ<12>  SCONN288_H44441003_PIP  I111
  U5D1   DC74  DDR5_DQ<12>  SKX_EXT_B_BGA1  I172

M_F_DQ<13>      @BASEBOARD_FAB2_LIB.BASEBOARD_FAB2(SCH_1):M_F_DQ<13>
  J4A1    14  DQ<12>  SCONN288_H44441004_PIP  I111
  J6L1   159  DQ<13>  SCONN288_H44441003_PIP  I111
  U5D1   DB75  DDR5_DQ<13>  SKX_EXT_B_BGA1  I172

M_F_DQ<14>      @BASEBOARD_FAB2_LIB.BASEBOARD_FAB2(SCH_1):M_F_DQ<14>
  J4A1   166  DQ<15>  SCONN288_H44441004_PIP  I111
  J6L1    21  DQ<14>  SCONN288_H44441003_PIP  I111
  U5D1   DF77  DDR5_DQ<14>  SKX_EXT_B_BGA1  I172

M_F_DQ<15>      @BASEBOARD_FAB2_LIB.BASEBOARD_FAB2(SCH_1):M_F_DQ<15>
  J4A1    21  DQ<14>  SCONN288_H44441004_PIP  I111
  J6L1   166  DQ<15>  SCONN288_H44441003_PIP  I111
  U5D1   DH77  DDR5_DQ<15>  SKX_EXT_B_BGA1  I172

M_F_DQ<16>      @BASEBOARD_FAB2_LIB.BASEBOARD_FAB2(SCH_1):M_F_DQ<16>
  J4A1   172  DQ<17>  SCONN288_H44441004_PIP  I111
  J6L1    27  DQ<16>  SCONN288_H44441003_PIP  I111
  U5D1   DG70  DDR5_DQ<16>  SKX_EXT_B_BGA1  I172

M_F_DQ<17>      @BASEBOARD_FAB2_LIB.BASEBOARD_FAB2(SCH_1):M_F_DQ<17>
  J4A1    27  DQ<16>  SCONN288_H44441004_PIP  I111
  J6L1   172  DQ<17>  SCONN288_H44441003_PIP  I111
  U5D1   DJ72  DDR5_DQ<17>  SKX_EXT_B_BGA1  I172

M_F_DQ<18>      @BASEBOARD_FAB2_LIB.BASEBOARD_FAB2(SCH_1):M_F_DQ<18>
  J4A1   179  DQ<19>  SCONN288_H44441004_PIP  I111
  J6L1    34  DQ<18>  SCONN288_H44441003_PIP  I111
  U5D1   DM69  DDR5_DQ<18>  SKX_EXT_B_BGA1  I172

M_F_DQ<19>      @BASEBOARD_FAB2_LIB.BASEBOARD_FAB2(SCH_1):M_F_DQ<19>
  J4A1    34  DQ<18>  SCONN288_H44441004_PIP  I111
  J6L1   179  DQ<19>  SCONN288_H44441003_PIP  I111
  U5D1   DN70  DDR5_DQ<19>  SKX_EXT_B_BGA1  I172

M_F_DQ<20>      @BASEBOARD_FAB2_LIB.BASEBOARD_FAB2(SCH_1):M_F_DQ<20>
  J4A1   170  DQ<21>  SCONN288_H44441004_PIP  I111
  J6L1    25  DQ<20>  SCONN288_H44441003_PIP  I111
  U5D1   DF71  DDR5_DQ<20>  SKX_EXT_B_BGA1  I172

M_F_DQ<21>      @BASEBOARD_FAB2_LIB.BASEBOARD_FAB2(SCH_1):M_F_DQ<21>
  J4A1    25  DQ<20>  SCONN288_H44441004_PIP  I111
  J6L1   170  DQ<21>  SCONN288_H44441003_PIP  I111
  U5D1   DG72  DDR5_DQ<21>  SKX_EXT_B_BGA1  I172

M_F_DQ<22>      @BASEBOARD_FAB2_LIB.BASEBOARD_FAB2(SCH_1):M_F_DQ<22>
  J4A1   177  DQ<23>  SCONN288_H44441004_PIP  I111
  J6L1    32  DQ<22>  SCONN288_H44441003_PIP  I111
  U5D1   DK69  DDR5_DQ<22>  SKX_EXT_B_BGA1  I172

M_F_DQ<23>      @BASEBOARD_FAB2_LIB.BASEBOARD_FAB2(SCH_1):M_F_DQ<23>
  J4A1    32  DQ<22>  SCONN288_H44441004_PIP  I111
  J6L1   177  DQ<23>  SCONN288_H44441003_PIP  I111
  U5D1   DM71  DDR5_DQ<23>  SKX_EXT_B_BGA1  I172

M_F_DQ<24>      @BASEBOARD_FAB2_LIB.BASEBOARD_FAB2(SCH_1):M_F_DQ<24>
  J4A1   183  DQ<25>  SCONN288_H44441004_PIP  I111
  J6L1    38  DQ<24>  SCONN288_H44441003_PIP  I111
  U5D1   CN66  DDR5_DQ<24>  SKX_EXT_B_BGA1  I172

M_F_DQ<25>      @BASEBOARD_FAB2_LIB.BASEBOARD_FAB2(SCH_1):M_F_DQ<25>
  J4A1    38  DQ<24>  SCONN288_H44441004_PIP  I111
  J6L1   183  DQ<25>  SCONN288_H44441003_PIP  I111
  U5D1   CU66  DDR5_DQ<25>  SKX_EXT_B_BGA1  I172

M_F_DQ<26>      @BASEBOARD_FAB2_LIB.BASEBOARD_FAB2(SCH_1):M_F_DQ<26>
  J4A1   190  DQ<27>  SCONN288_H44441004_PIP  I111
  J6L1    45  DQ<26>  SCONN288_H44441003_PIP  I111
  U5D1   CP63  DDR5_DQ<26>  SKX_EXT_B_BGA1  I172

M_F_DQ<27>      @BASEBOARD_FAB2_LIB.BASEBOARD_FAB2(SCH_1):M_F_DQ<27>
  J4A1    45  DQ<26>  SCONN288_H44441004_PIP  I111
  J6L1   190  DQ<27>  SCONN288_H44441003_PIP  I111
  U5D1   CT63  DDR5_DQ<27>  SKX_EXT_B_BGA1  I172

M_F_DQ<28>      @BASEBOARD_FAB2_LIB.BASEBOARD_FAB2(SCH_1):M_F_DQ<28>
  J4A1   181  DQ<29>  SCONN288_H44441004_PIP  I111
  J6L1    36  DQ<28>  SCONN288_H44441003_PIP  I111
  U5D1   CP67  DDR5_DQ<28>  SKX_EXT_B_BGA1  I172

M_F_DQ<29>      @BASEBOARD_FAB2_LIB.BASEBOARD_FAB2(SCH_1):M_F_DQ<29>
  J4A1    36  DQ<28>  SCONN288_H44441004_PIP  I111
  J6L1   181  DQ<29>  SCONN288_H44441003_PIP  I111
  U5D1   CT67  DDR5_DQ<29>  SKX_EXT_B_BGA1  I172

M_F_DQ<30>      @BASEBOARD_FAB2_LIB.BASEBOARD_FAB2(SCH_1):M_F_DQ<30>
  J4A1   188  DQ<31>  SCONN288_H44441004_PIP  I111
  J6L1    43  DQ<30>  SCONN288_H44441003_PIP  I111
  U5D1   CN64  DDR5_DQ<30>  SKX_EXT_B_BGA1  I172

M_F_DQ<31>      @BASEBOARD_FAB2_LIB.BASEBOARD_FAB2(SCH_1):M_F_DQ<31>
  J4A1    43  DQ<30>  SCONN288_H44441004_PIP  I111
  J6L1   188  DQ<31>  SCONN288_H44441003_PIP  I111
  U5D1   CU64  DDR5_DQ<31>  SKX_EXT_B_BGA1  I172

M_F_DQ<32>      @BASEBOARD_FAB2_LIB.BASEBOARD_FAB2(SCH_1):M_F_DQ<32>
  J4A1   242  DQ<33>  SCONN288_H44441004_PIP  I111
  J6L1    97  DQ<32>  SCONN288_H44441003_PIP  I111
  U5D1   DD41  DDR5_DQ<32>  SKX_EXT_B_BGA1  I172

M_F_DQ<33>      @BASEBOARD_FAB2_LIB.BASEBOARD_FAB2(SCH_1):M_F_DQ<33>
  J4A1    97  DQ<32>  SCONN288_H44441004_PIP  I111
  J6L1   242  DQ<33>  SCONN288_H44441003_PIP  I111
  U5D1   DG42  DDR5_DQ<33>  SKX_EXT_B_BGA1  I172

M_F_DQ<34>      @BASEBOARD_FAB2_LIB.BASEBOARD_FAB2(SCH_1):M_F_DQ<34>
  J4A1   249  DQ<35>  SCONN288_H44441004_PIP  I111
  J6L1   104  DQ<34>  SCONN288_H44441003_PIP  I111
  U5D1   DE38  DDR5_DQ<34>  SKX_EXT_B_BGA1  I172

M_F_DQ<35>      @BASEBOARD_FAB2_LIB.BASEBOARD_FAB2(SCH_1):M_F_DQ<35>
  J4A1   104  DQ<34>  SCONN288_H44441004_PIP  I111
  J6L1   249  DQ<35>  SCONN288_H44441003_PIP  I111
  U5D1   DG38  DDR5_DQ<35>  SKX_EXT_B_BGA1  I172

M_F_DQ<36>      @BASEBOARD_FAB2_LIB.BASEBOARD_FAB2(SCH_1):M_F_DQ<36>
  J4A1   240  DQ<37>  SCONN288_H44441004_PIP  I111
  J6L1    95  DQ<36>  SCONN288_H44441003_PIP  I111
  U5D1   DA42  DDR5_DQ<36>  SKX_EXT_B_BGA1  I172

M_F_DQ<37>      @BASEBOARD_FAB2_LIB.BASEBOARD_FAB2(SCH_1):M_F_DQ<37>
  J4A1    95  DQ<36>  SCONN288_H44441004_PIP  I111
  J6L1   240  DQ<37>  SCONN288_H44441003_PIP  I111
  U5D1   DE42  DDR5_DQ<37>  SKX_EXT_B_BGA1  I172

M_F_DQ<38>      @BASEBOARD_FAB2_LIB.BASEBOARD_FAB2(SCH_1):M_F_DQ<38>
  J4A1   247  DQ<39>  SCONN288_H44441004_PIP  I111
  J6L1   102  DQ<38>  SCONN288_H44441003_PIP  I111
  U5D1   DD39  DDR5_DQ<38>  SKX_EXT_B_BGA1  I172

M_F_DQ<39>      @BASEBOARD_FAB2_LIB.BASEBOARD_FAB2(SCH_1):M_F_DQ<39>
  J4A1   102  DQ<38>  SCONN288_H44441004_PIP  I111
  J6L1   247  DQ<39>  SCONN288_H44441003_PIP  I111
  U5D1   DH39  DDR5_DQ<39>  SKX_EXT_B_BGA1  I172

M_F_DQ<40>      @BASEBOARD_FAB2_LIB.BASEBOARD_FAB2(SCH_1):M_F_DQ<40>
  J4A1   253  DQ<41>  SCONN288_H44441004_PIP  I111
  J6L1   108  DQ<40>  SCONN288_H44441003_PIP  I111
  U5D1   DF33  DDR5_DQ<40>  SKX_EXT_B_BGA1  I172

M_F_DQ<41>      @BASEBOARD_FAB2_LIB.BASEBOARD_FAB2(SCH_1):M_F_DQ<41>
  J4A1   108  DQ<40>  SCONN288_H44441004_PIP  I111
  J6L1   253  DQ<41>  SCONN288_H44441003_PIP  I111
  U5D1   DK33  DDR5_DQ<41>  SKX_EXT_B_BGA1  I172

M_F_DQ<42>      @BASEBOARD_FAB2_LIB.BASEBOARD_FAB2(SCH_1):M_F_DQ<42>
  J4A1   260  DQ<43>  SCONN288_H44441004_PIP  I111
  J6L1   115  DQ<42>  SCONN288_H44441003_PIP  I111
  U5D1   DG30  DDR5_DQ<42>  SKX_EXT_B_BGA1  I172

M_F_DQ<43>      @BASEBOARD_FAB2_LIB.BASEBOARD_FAB2(SCH_1):M_F_DQ<43>
  J4A1   115  DQ<42>  SCONN288_H44441004_PIP  I111
  J6L1   260  DQ<43>  SCONN288_H44441003_PIP  I111
  U5D1   DJ30  DDR5_DQ<43>  SKX_EXT_B_BGA1  I172

M_F_DQ<44>      @BASEBOARD_FAB2_LIB.BASEBOARD_FAB2(SCH_1):M_F_DQ<44>
  J4A1   251  DQ<45>  SCONN288_H44441004_PIP  I111
  J6L1   106  DQ<44>  SCONN288_H44441003_PIP  I111
  U5D1   DG34  DDR5_DQ<44>  SKX_EXT_B_BGA1  I172

M_F_DQ<45>      @BASEBOARD_FAB2_LIB.BASEBOARD_FAB2(SCH_1):M_F_DQ<45>
  J4A1   106  DQ<44>  SCONN288_H44441004_PIP  I111
  J6L1   251  DQ<45>  SCONN288_H44441003_PIP  I111
  U5D1   DJ34  DDR5_DQ<45>  SKX_EXT_B_BGA1  I172

M_F_DQ<46>      @BASEBOARD_FAB2_LIB.BASEBOARD_FAB2(SCH_1):M_F_DQ<46>
  J4A1   258  DQ<47>  SCONN288_H44441004_PIP  I111
  J6L1   113  DQ<46>  SCONN288_H44441003_PIP  I111
  U5D1   DF31  DDR5_DQ<46>  SKX_EXT_B_BGA1  I172

M_F_DQ<47>      @BASEBOARD_FAB2_LIB.BASEBOARD_FAB2(SCH_1):M_F_DQ<47>
  J4A1   113  DQ<46>  SCONN288_H44441004_PIP  I111
  J6L1   258  DQ<47>  SCONN288_H44441003_PIP  I111
  U5D1   DK31  DDR5_DQ<47>  SKX_EXT_B_BGA1  I172

M_F_DQ<48>      @BASEBOARD_FAB2_LIB.BASEBOARD_FAB2(SCH_1):M_F_DQ<48>
  J4A1   264  DQ<49>  SCONN288_H44441004_PIP  I111
  J6L1   119  DQ<48>  SCONN288_H44441003_PIP  I111
  U5D1   CW36  DDR5_DQ<48>  SKX_EXT_B_BGA1  I172

M_F_DQ<49>      @BASEBOARD_FAB2_LIB.BASEBOARD_FAB2(SCH_1):M_F_DQ<49>
  J4A1   119  DQ<48>  SCONN288_H44441004_PIP  I111
  J6L1   264  DQ<49>  SCONN288_H44441003_PIP  I111
  U5D1   DC36  DDR5_DQ<49>  SKX_EXT_B_BGA1  I172

M_F_DQ<50>      @BASEBOARD_FAB2_LIB.BASEBOARD_FAB2(SCH_1):M_F_DQ<50>
  J4A1   271  DQ<51>  SCONN288_H44441004_PIP  I111
  J6L1   126  DQ<50>  SCONN288_H44441003_PIP  I111
  U5D1   CY33  DDR5_DQ<50>  SKX_EXT_B_BGA1  I172

M_F_DQ<51>      @BASEBOARD_FAB2_LIB.BASEBOARD_FAB2(SCH_1):M_F_DQ<51>
  J4A1   126  DQ<50>  SCONN288_H44441004_PIP  I111
  J6L1   271  DQ<51>  SCONN288_H44441003_PIP  I111
  U5D1   DB33  DDR5_DQ<51>  SKX_EXT_B_BGA1  I172

M_F_DQ<52>      @BASEBOARD_FAB2_LIB.BASEBOARD_FAB2(SCH_1):M_F_DQ<52>
  J4A1   262  DQ<53>  SCONN288_H44441004_PIP  I111
  J6L1   117  DQ<52>  SCONN288_H44441003_PIP  I111
  U5D1   CY37  DDR5_DQ<52>  SKX_EXT_B_BGA1  I172

M_F_DQ<53>      @BASEBOARD_FAB2_LIB.BASEBOARD_FAB2(SCH_1):M_F_DQ<53>
  J4A1   117  DQ<52>  SCONN288_H44441004_PIP  I111
  J6L1   262  DQ<53>  SCONN288_H44441003_PIP  I111
  U5D1   DB37  DDR5_DQ<53>  SKX_EXT_B_BGA1  I172

M_F_DQ<54>      @BASEBOARD_FAB2_LIB.BASEBOARD_FAB2(SCH_1):M_F_DQ<54>
  J4A1   269  DQ<55>  SCONN288_H44441004_PIP  I111
  J6L1   124  DQ<54>  SCONN288_H44441003_PIP  I111
  U5D1   CW34  DDR5_DQ<54>  SKX_EXT_B_BGA1  I172

M_F_DQ<55>      @BASEBOARD_FAB2_LIB.BASEBOARD_FAB2(SCH_1):M_F_DQ<55>
  J4A1   124  DQ<54>  SCONN288_H44441004_PIP  I111
  J6L1   269  DQ<55>  SCONN288_H44441003_PIP  I111
  U5D1   DC34  DDR5_DQ<55>  SKX_EXT_B_BGA1  I172

M_F_DQ<56>      @BASEBOARD_FAB2_LIB.BASEBOARD_FAB2(SCH_1):M_F_DQ<56>
  J4A1   275  DQ<57>  SCONN288_H44441004_PIP  I111
  J6L1   130  DQ<56>  SCONN288_H44441003_PIP  I111
  U5D1   CW30  DDR5_DQ<56>  SKX_EXT_B_BGA1  I172

M_F_DQ<57>      @BASEBOARD_FAB2_LIB.BASEBOARD_FAB2(SCH_1):M_F_DQ<57>
  J4A1   130  DQ<56>  SCONN288_H44441004_PIP  I111
  J6L1   275  DQ<57>  SCONN288_H44441003_PIP  I111
  U5D1   DC30  DDR5_DQ<57>  SKX_EXT_B_BGA1  I172

M_F_DQ<58>      @BASEBOARD_FAB2_LIB.BASEBOARD_FAB2(SCH_1):M_F_DQ<58>
  J4A1   282  DQ<59>  SCONN288_H44441004_PIP  I111
  J6L1   137  DQ<58>  SCONN288_H44441003_PIP  I111
  U5D1   CY27  DDR5_DQ<58>  SKX_EXT_B_BGA1  I172

M_F_DQ<59>      @BASEBOARD_FAB2_LIB.BASEBOARD_FAB2(SCH_1):M_F_DQ<59>
  J4A1   137  DQ<58>  SCONN288_H44441004_PIP  I111
  J6L1   282  DQ<59>  SCONN288_H44441003_PIP  I111
  U5D1   DB27  DDR5_DQ<59>  SKX_EXT_B_BGA1  I172

M_F_DQ<60>      @BASEBOARD_FAB2_LIB.BASEBOARD_FAB2(SCH_1):M_F_DQ<60>
  J4A1   273  DQ<61>  SCONN288_H44441004_PIP  I111
  J6L1   128  DQ<60>  SCONN288_H44441003_PIP  I111
  U5D1   CY31  DDR5_DQ<60>  SKX_EXT_B_BGA1  I172

M_F_DQ<61>      @BASEBOARD_FAB2_LIB.BASEBOARD_FAB2(SCH_1):M_F_DQ<61>
  J4A1   128  DQ<60>  SCONN288_H44441004_PIP  I111
  J6L1   273  DQ<61>  SCONN288_H44441003_PIP  I111
  U5D1   DB31  DDR5_DQ<61>  SKX_EXT_B_BGA1  I172

M_F_DQ<62>      @BASEBOARD_FAB2_LIB.BASEBOARD_FAB2(SCH_1):M_F_DQ<62>
  J4A1   280  DQ<63>  SCONN288_H44441004_PIP  I111
  J6L1   135  DQ<62>  SCONN288_H44441003_PIP  I111
  U5D1   CW28  DDR5_DQ<62>  SKX_EXT_B_BGA1  I172

M_F_DQ<63>      @BASEBOARD_FAB2_LIB.BASEBOARD_FAB2(SCH_1):M_F_DQ<63>
  J4A1   135  DQ<62>  SCONN288_H44441004_PIP  I111
  J6L1   280  DQ<63>  SCONN288_H44441003_PIP  I111
  U5D1   DC28  DDR5_DQ<63>  SKX_EXT_B_BGA1  I172

M_F_DQS_DN<0>   @BASEBOARD_FAB2_LIB.BASEBOARD_FAB2(SCH_1):M_F_DQS_DN<0>
  J4A1   152  DQS0N  SCONN288_H44441004_PIP  I66
  J6L1   152  DQS0N  SCONN288_H44441003_PIP  I66
  U5D1   CP77  DDR5_DQS_DN<0>  SKX_EXT_B_BGA1  I172

M_F_DQS_DN<1>   @BASEBOARD_FAB2_LIB.BASEBOARD_FAB2(SCH_1):M_F_DQS_DN<1>
  J4A1   163  DQS1N  SCONN288_H44441004_PIP  I66
  J6L1   163  DQS1N  SCONN288_H44441003_PIP  I66
  U5D1   DD77  DDR5_DQS_DN<1>  SKX_EXT_B_BGA1  I172

M_F_DQS_DN<2>   @BASEBOARD_FAB2_LIB.BASEBOARD_FAB2(SCH_1):M_F_DQS_DN<2>
  J4A1   174  DQS2N  SCONN288_H44441004_PIP  I66
  J6L1   174  DQS2N  SCONN288_H44441003_PIP  I66
  U5D1   DL72  DDR5_DQS_DN<2>  SKX_EXT_B_BGA1  I172

M_F_DQS_DN<3>   @BASEBOARD_FAB2_LIB.BASEBOARD_FAB2(SCH_1):M_F_DQS_DN<3>
  J4A1   185  DQS3N  SCONN288_H44441004_PIP  I66
  J6L1   185  DQS3N  SCONN288_H44441003_PIP  I66
  U5D1   CV65  DDR5_DQS_DN<3>  SKX_EXT_B_BGA1  I172

M_F_DQS_DN<4>   @BASEBOARD_FAB2_LIB.BASEBOARD_FAB2(SCH_1):M_F_DQS_DN<4>
  J4A1   244  DQS4N  SCONN288_H44441004_PIP  I66
  J6L1   244  DQS4N  SCONN288_H44441003_PIP  I66
  U5D1   DG40  DDR5_DQS_DN<4>  SKX_EXT_B_BGA1  I172

M_F_DQS_DN<5>   @BASEBOARD_FAB2_LIB.BASEBOARD_FAB2(SCH_1):M_F_DQS_DN<5>
  J4A1   255  DQS5N  SCONN288_H44441004_PIP  I66
  J6L1   255  DQS5N  SCONN288_H44441003_PIP  I66
  U5D1   DL32  DDR5_DQS_DN<5>  SKX_EXT_B_BGA1  I172

M_F_DQS_DN<6>   @BASEBOARD_FAB2_LIB.BASEBOARD_FAB2(SCH_1):M_F_DQS_DN<6>
  J4A1   266  DQS6N  SCONN288_H44441004_PIP  I66
  J6L1   266  DQS6N  SCONN288_H44441003_PIP  I66
  U5D1   DD35  DDR5_DQS_DN<6>  SKX_EXT_B_BGA1  I172

M_F_DQS_DN<7>   @BASEBOARD_FAB2_LIB.BASEBOARD_FAB2(SCH_1):M_F_DQS_DN<7>
  J4A1   277  DQS7N  SCONN288_H44441004_PIP  I66
  J6L1   277  DQS7N  SCONN288_H44441003_PIP  I66
  U5D1   DD29  DDR5_DQS_DN<7>  SKX_EXT_B_BGA1  I172

M_F_DQS_DN<8>   @BASEBOARD_FAB2_LIB.BASEBOARD_FAB2(SCH_1):M_F_DQS_DN<8>
  J4A1   196  DQS8N  SCONN288_H44441004_PIP  I66
  J6L1   196  DQS8N  SCONN288_H44441003_PIP  I66
  U5D1   CN70  DDR5_DQS_DN<8>  SKX_EXT_B_BGA1  I172

M_F_DQS_DN<9>   @BASEBOARD_FAB2_LIB.BASEBOARD_FAB2(SCH_1):M_F_DQS_DN<9>
  J4A1     8  DQS9N  SCONN288_H44441004_PIP  I66
  J6L1     8  DQS9N  SCONN288_H44441003_PIP  I66
  U5D1   CT75  DDR5_DQS_DN<9>  SKX_EXT_B_BGA1  I172

M_F_DQS_DN<10>   @BASEBOARD_FAB2_LIB.BASEBOARD_FAB2(SCH_1):M_F_DQS_DN<10>
  J4A1    19  DQS10N  SCONN288_H44441004_PIP  I66
  J6L1    19  DQS10N  SCONN288_H44441003_PIP  I66
  U5D1   DF75  DDR5_DQS_DN<10>  SKX_EXT_B_BGA1  I172

M_F_DQS_DN<11>   @BASEBOARD_FAB2_LIB.BASEBOARD_FAB2(SCH_1):M_F_DQS_DN<11>
  J4A1    30  DQS11N  SCONN288_H44441004_PIP  I66
  J6L1    30  DQS11N  SCONN288_H44441003_PIP  I66
  U5D1   DJ70  DDR5_DQS_DN<11>  SKX_EXT_B_BGA1  I172

M_F_DQS_DN<12>   @BASEBOARD_FAB2_LIB.BASEBOARD_FAB2(SCH_1):M_F_DQS_DN<12>
  J4A1    41  DQS12N  SCONN288_H44441004_PIP  I66
  J6L1    41  DQS12N  SCONN288_H44441003_PIP  I66
  U5D1   CP65  DDR5_DQS_DN<12>  SKX_EXT_B_BGA1  I172

M_F_DQS_DN<13>   @BASEBOARD_FAB2_LIB.BASEBOARD_FAB2(SCH_1):M_F_DQS_DN<13>
  J4A1   100  DQS13N  SCONN288_H44441004_PIP  I66
  J6L1   100  DQS13N  SCONN288_H44441003_PIP  I66
  U5D1   DE40  DDR5_DQS_DN<13>  SKX_EXT_B_BGA1  I172

M_F_DQS_DN<14>   @BASEBOARD_FAB2_LIB.BASEBOARD_FAB2(SCH_1):M_F_DQS_DN<14>
  J4A1   111  DQS14N  SCONN288_H44441004_PIP  I66
  J6L1   111  DQS14N  SCONN288_H44441003_PIP  I66
  U5D1   DG32  DDR5_DQS_DN<14>  SKX_EXT_B_BGA1  I172

M_F_DQS_DN<15>   @BASEBOARD_FAB2_LIB.BASEBOARD_FAB2(SCH_1):M_F_DQS_DN<15>
  J4A1   122  DQS15N  SCONN288_H44441004_PIP  I66
  J6L1   122  DQS15N  SCONN288_H44441003_PIP  I66
  U5D1   CY35  DDR5_DQS_DN<15>  SKX_EXT_B_BGA1  I172

M_F_DQS_DN<16>   @BASEBOARD_FAB2_LIB.BASEBOARD_FAB2(SCH_1):M_F_DQS_DN<16>
  J4A1   133  DQS16N  SCONN288_H44441004_PIP  I66
  J6L1   133  DQS16N  SCONN288_H44441003_PIP  I66
  U5D1   CY29  DDR5_DQS_DN<16>  SKX_EXT_B_BGA1  I172

M_F_DQS_DN<17>   @BASEBOARD_FAB2_LIB.BASEBOARD_FAB2(SCH_1):M_F_DQS_DN<17>
  J4A1    52  DQS17N  SCONN288_H44441004_PIP  I66
  J6L1    52  DQS17N  SCONN288_H44441003_PIP  I66
  U5D1   CJ70  DDR5_DQS_DN<17>  SKX_EXT_B_BGA1  I172

M_F_DQS_DP<0>   @BASEBOARD_FAB2_LIB.BASEBOARD_FAB2(SCH_1):M_F_DQS_DP<0>
  J4A1   153  DQS0P  SCONN288_H44441004_PIP  I66
  J6L1   153  DQS0P  SCONN288_H44441003_PIP  I66
  U5D1   CR76  DDR5_DQS_DP<0>  SKX_EXT_B_BGA1  I172

M_F_DQS_DP<1>   @BASEBOARD_FAB2_LIB.BASEBOARD_FAB2(SCH_1):M_F_DQS_DP<1>
  J4A1   164  DQS1P  SCONN288_H44441004_PIP  I66
  J6L1   164  DQS1P  SCONN288_H44441003_PIP  I66
  U5D1   DE76  DDR5_DQS_DP<1>  SKX_EXT_B_BGA1  I172

M_F_DQS_DP<2>   @BASEBOARD_FAB2_LIB.BASEBOARD_FAB2(SCH_1):M_F_DQS_DP<2>
  J4A1   175  DQS2P  SCONN288_H44441004_PIP  I66
  J6L1   175  DQS2P  SCONN288_H44441003_PIP  I66
  U5D1   DK71  DDR5_DQS_DP<2>  SKX_EXT_B_BGA1  I172

M_F_DQS_DP<3>   @BASEBOARD_FAB2_LIB.BASEBOARD_FAB2(SCH_1):M_F_DQS_DP<3>
  J4A1   186  DQS3P  SCONN288_H44441004_PIP  I66
  J6L1   186  DQS3P  SCONN288_H44441003_PIP  I66
  U5D1   CT65  DDR5_DQS_DP<3>  SKX_EXT_B_BGA1  I172

M_F_DQS_DP<4>   @BASEBOARD_FAB2_LIB.BASEBOARD_FAB2(SCH_1):M_F_DQS_DP<4>
  J4A1   245  DQS4P  SCONN288_H44441004_PIP  I66
  J6L1   245  DQS4P  SCONN288_H44441003_PIP  I66
  U5D1   DJ40  DDR5_DQS_DP<4>  SKX_EXT_B_BGA1  I172

M_F_DQS_DP<5>   @BASEBOARD_FAB2_LIB.BASEBOARD_FAB2(SCH_1):M_F_DQS_DP<5>
  J4A1   256  DQS5P  SCONN288_H44441004_PIP  I66
  J6L1   256  DQS5P  SCONN288_H44441003_PIP  I66
  U5D1   DJ32  DDR5_DQS_DP<5>  SKX_EXT_B_BGA1  I172

M_F_DQS_DP<6>   @BASEBOARD_FAB2_LIB.BASEBOARD_FAB2(SCH_1):M_F_DQS_DP<6>
  J4A1   267  DQS6P  SCONN288_H44441004_PIP  I66
  J6L1   267  DQS6P  SCONN288_H44441003_PIP  I66
  U5D1   DB35  DDR5_DQS_DP<6>  SKX_EXT_B_BGA1  I172

M_F_DQS_DP<7>   @BASEBOARD_FAB2_LIB.BASEBOARD_FAB2(SCH_1):M_F_DQS_DP<7>
  J4A1   278  DQS7P  SCONN288_H44441004_PIP  I66
  J6L1   278  DQS7P  SCONN288_H44441003_PIP  I66
  U5D1   DB29  DDR5_DQS_DP<7>  SKX_EXT_B_BGA1  I172

M_F_DQS_DP<8>   @BASEBOARD_FAB2_LIB.BASEBOARD_FAB2(SCH_1):M_F_DQS_DP<8>
  J4A1   197  DQS8P  SCONN288_H44441004_PIP  I66
  J6L1   197  DQS8P  SCONN288_H44441003_PIP  I66
  U5D1   CL70  DDR5_DQS_DP<8>  SKX_EXT_B_BGA1  I172

M_F_DQS_DP<9>   @BASEBOARD_FAB2_LIB.BASEBOARD_FAB2(SCH_1):M_F_DQS_DP<9>
  J4A1     7  DQS9P  SCONN288_H44441004_PIP  I66
  J6L1     7  DQS9P  SCONN288_H44441003_PIP  I66
  U5D1   CU74  DDR5_DQS_DP<9>  SKX_EXT_B_BGA1  I172

M_F_DQS_DP<10>   @BASEBOARD_FAB2_LIB.BASEBOARD_FAB2(SCH_1):M_F_DQS_DP<10>
  J4A1    18  DQS10P  SCONN288_H44441004_PIP  I66
  J6L1    18  DQS10P  SCONN288_H44441003_PIP  I66
  U5D1   DG74  DDR5_DQS_DP<10>  SKX_EXT_B_BGA1  I172

M_F_DQS_DP<11>   @BASEBOARD_FAB2_LIB.BASEBOARD_FAB2(SCH_1):M_F_DQS_DP<11>
  J4A1    29  DQS11P  SCONN288_H44441004_PIP  I66
  J6L1    29  DQS11P  SCONN288_H44441003_PIP  I66
  U5D1   DH69  DDR5_DQS_DP<11>  SKX_EXT_B_BGA1  I172

M_F_DQS_DP<12>   @BASEBOARD_FAB2_LIB.BASEBOARD_FAB2(SCH_1):M_F_DQS_DP<12>
  J4A1    40  DQS12P  SCONN288_H44441004_PIP  I66
  J6L1    40  DQS12P  SCONN288_H44441003_PIP  I66
  U5D1   CM65  DDR5_DQS_DP<12>  SKX_EXT_B_BGA1  I172

M_F_DQS_DP<13>   @BASEBOARD_FAB2_LIB.BASEBOARD_FAB2(SCH_1):M_F_DQS_DP<13>
  J4A1    99  DQS13P  SCONN288_H44441004_PIP  I66
  J6L1    99  DQS13P  SCONN288_H44441003_PIP  I66
  U5D1   DC40  DDR5_DQS_DP<13>  SKX_EXT_B_BGA1  I172

M_F_DQS_DP<14>   @BASEBOARD_FAB2_LIB.BASEBOARD_FAB2(SCH_1):M_F_DQS_DP<14>
  J4A1   110  DQS14P  SCONN288_H44441004_PIP  I66
  J6L1   110  DQS14P  SCONN288_H44441003_PIP  I66
  U5D1   DE32  DDR5_DQS_DP<14>  SKX_EXT_B_BGA1  I172

M_F_DQS_DP<15>   @BASEBOARD_FAB2_LIB.BASEBOARD_FAB2(SCH_1):M_F_DQS_DP<15>
  J4A1   121  DQS15P  SCONN288_H44441004_PIP  I66
  J6L1   121  DQS15P  SCONN288_H44441003_PIP  I66
  U5D1   CV35  DDR5_DQS_DP<15>  SKX_EXT_B_BGA1  I172

M_F_DQS_DP<16>   @BASEBOARD_FAB2_LIB.BASEBOARD_FAB2(SCH_1):M_F_DQS_DP<16>
  J4A1   132  DQS16P  SCONN288_H44441004_PIP  I66
  J6L1   132  DQS16P  SCONN288_H44441003_PIP  I66
  U5D1   CV29  DDR5_DQS_DP<16>  SKX_EXT_B_BGA1  I172

M_F_DQS_DP<17>   @BASEBOARD_FAB2_LIB.BASEBOARD_FAB2(SCH_1):M_F_DQS_DP<17>
  J4A1    51  DQS17P  SCONN288_H44441004_PIP  I66
  J6L1    51  DQS17P  SCONN288_H44441003_PIP  I66
  U5D1   CG70  DDR5_DQS_DP<17>  SKX_EXT_B_BGA1  I172

M_F_ECC<0>      @BASEBOARD_FAB2_LIB.BASEBOARD_FAB2(SCH_1):M_F_ECC<0>
  J4A1   194  CB<1>  SCONN288_H44441004_PIP  I111
  J6L1    49  CB<0>  SCONN288_H44441003_PIP  I111
  U5D1   CH71  DDR5_ECC<0>  SKX_EXT_B_BGA1  I172

M_F_ECC<1>      @BASEBOARD_FAB2_LIB.BASEBOARD_FAB2(SCH_1):M_F_ECC<1>
  J4A1    49  CB<0>  SCONN288_H44441004_PIP  I111
  J6L1   194  CB<1>  SCONN288_H44441003_PIP  I111
  U5D1   CM71  DDR5_ECC<1>  SKX_EXT_B_BGA1  I172

M_F_ECC<2>      @BASEBOARD_FAB2_LIB.BASEBOARD_FAB2(SCH_1):M_F_ECC<2>
  J4A1   201  CB<3>  SCONN288_H44441004_PIP  I111
  J6L1    56  CB<2>  SCONN288_H44441003_PIP  I111
  U5D1   CJ68  DDR5_ECC<2>  SKX_EXT_B_BGA1  I172

M_F_ECC<3>      @BASEBOARD_FAB2_LIB.BASEBOARD_FAB2(SCH_1):M_F_ECC<3>
  J4A1    56  CB<2>  SCONN288_H44441004_PIP  I111
  J6L1   201  CB<3>  SCONN288_H44441003_PIP  I111
  U5D1   CL68  DDR5_ECC<3>  SKX_EXT_B_BGA1  I172

M_F_ECC<4>      @BASEBOARD_FAB2_LIB.BASEBOARD_FAB2(SCH_1):M_F_ECC<4>
  J4A1   192  CB<5>  SCONN288_H44441004_PIP  I111
  J6L1    47  CB<4>  SCONN288_H44441003_PIP  I111
  U5D1   CJ72  DDR5_ECC<4>  SKX_EXT_B_BGA1  I172

M_F_ECC<5>      @BASEBOARD_FAB2_LIB.BASEBOARD_FAB2(SCH_1):M_F_ECC<5>
  J4A1    47  CB<4>  SCONN288_H44441004_PIP  I111
  J6L1   192  CB<5>  SCONN288_H44441003_PIP  I111
  U5D1   CL72  DDR5_ECC<5>  SKX_EXT_B_BGA1  I172

M_F_ECC<6>      @BASEBOARD_FAB2_LIB.BASEBOARD_FAB2(SCH_1):M_F_ECC<6>
  J4A1   199  CB<7>  SCONN288_H44441004_PIP  I111
  J6L1    54  CB<6>  SCONN288_H44441003_PIP  I111
  U5D1   CH69  DDR5_ECC<6>  SKX_EXT_B_BGA1  I172

M_F_ECC<7>      @BASEBOARD_FAB2_LIB.BASEBOARD_FAB2(SCH_1):M_F_ECC<7>
  J4A1    54  CB<6>  SCONN288_H44441004_PIP  I111
  J6L1   199  CB<7>  SCONN288_H44441003_PIP  I111
  U5D1   CM69  DDR5_ECC<7>  SKX_EXT_B_BGA1  I172

M_F_MA<0>       @BASEBOARD_FAB2_LIB.BASEBOARD_FAB2(SCH_1):M_F_MA<0>
  J4A1    79     A0  SCONN288_H44441004_PIP  I111
  J6L1    79     A0  SCONN288_H44441003_PIP  I111
  U5D1   DF53  DDR5_MA<0>  SKX_EXT_B_BGA1  I172

M_F_MA<1>       @BASEBOARD_FAB2_LIB.BASEBOARD_FAB2(SCH_1):M_F_MA<1>
  J4A1    72     A1  SCONN288_H44441004_PIP  I111
  J6L1    72     A1  SCONN288_H44441003_PIP  I111
  U5D1   DC58  DDR5_MA<1>  SKX_EXT_B_BGA1  I172

M_F_MA<2>       @BASEBOARD_FAB2_LIB.BASEBOARD_FAB2(SCH_1):M_F_MA<2>
  J4A1   216     A2  SCONN288_H44441004_PIP  I111
  J6L1   216     A2  SCONN288_H44441003_PIP  I111
  U5D1   DD57  DDR5_MA<2>  SKX_EXT_B_BGA1  I172

M_F_MA<3>       @BASEBOARD_FAB2_LIB.BASEBOARD_FAB2(SCH_1):M_F_MA<3>
  J4A1    71     A3  SCONN288_H44441004_PIP  I111
  J6L1    71     A3  SCONN288_H44441003_PIP  I111
  U5D1   DG58  DDR5_MA<3>  SKX_EXT_B_BGA1  I172

M_F_MA<4>       @BASEBOARD_FAB2_LIB.BASEBOARD_FAB2(SCH_1):M_F_MA<4>
  J4A1   214     A4  SCONN288_H44441004_PIP  I111
  J6L1   214     A4  SCONN288_H44441003_PIP  I111
  U5D1   DJ58  DDR5_MA<4>  SKX_EXT_B_BGA1  I172

M_F_MA<5>       @BASEBOARD_FAB2_LIB.BASEBOARD_FAB2(SCH_1):M_F_MA<5>
  J4A1   213     A5  SCONN288_H44441004_PIP  I111
  J6L1   213     A5  SCONN288_H44441003_PIP  I111
  U5D1   DF59  DDR5_MA<5>  SKX_EXT_B_BGA1  I172

M_F_MA<6>       @BASEBOARD_FAB2_LIB.BASEBOARD_FAB2(SCH_1):M_F_MA<6>
  J4A1    69     A6  SCONN288_H44441004_PIP  I111
  J6L1    69     A6  SCONN288_H44441003_PIP  I111
  U5D1   DK59  DDR5_MA<6>  SKX_EXT_B_BGA1  I172

M_F_MA<7>       @BASEBOARD_FAB2_LIB.BASEBOARD_FAB2(SCH_1):M_F_MA<7>
  J4A1   211     A7  SCONN288_H44441004_PIP  I111
  J6L1   211     A7  SCONN288_H44441003_PIP  I111
  U5D1   DC60  DDR5_MA<7>  SKX_EXT_B_BGA1  I172

M_F_MA<8>       @BASEBOARD_FAB2_LIB.BASEBOARD_FAB2(SCH_1):M_F_MA<8>
  J4A1    68     A8  SCONN288_H44441004_PIP  I111
  J6L1    68     A8  SCONN288_H44441003_PIP  I111
  U5D1   DD59  DDR5_MA<8>  SKX_EXT_B_BGA1  I172

M_F_MA<9>       @BASEBOARD_FAB2_LIB.BASEBOARD_FAB2(SCH_1):M_F_MA<9>
  J4A1    66     A9  SCONN288_H44441004_PIP  I111
  J6L1    66     A9  SCONN288_H44441003_PIP  I111
  U5D1   DA58  DDR5_MA<9>  SKX_EXT_B_BGA1  I172

M_F_MA<10>      @BASEBOARD_FAB2_LIB.BASEBOARD_FAB2(SCH_1):M_F_MA<10>
  J4A1   225    A10  SCONN288_H44441004_PIP  I111
  J6L1   225    A10  SCONN288_H44441003_PIP  I111
  U5D1   DD55  DDR5_MA<10>  SKX_EXT_B_BGA1  I172

M_F_MA<11>      @BASEBOARD_FAB2_LIB.BASEBOARD_FAB2(SCH_1):M_F_MA<11>
  J4A1   210    A11  SCONN288_H44441004_PIP  I111
  J6L1   210    A11  SCONN288_H44441003_PIP  I111
  U5D1   DA60  DDR5_MA<11>  SKX_EXT_B_BGA1  I172

M_F_MA<12>      @BASEBOARD_FAB2_LIB.BASEBOARD_FAB2(SCH_1):M_F_MA<12>
  J4A1    65    A12  SCONN288_H44441004_PIP  I111
  J6L1    65    A12  SCONN288_H44441003_PIP  I111
  U5D1   DG60  DDR5_MA<12>  SKX_EXT_B_BGA1  I172

M_F_MA<13>      @BASEBOARD_FAB2_LIB.BASEBOARD_FAB2(SCH_1):M_F_MA<13>
  J4A1   232    A13  SCONN288_H44441004_PIP  I111
  J6L1   232    A13  SCONN288_H44441003_PIP  I111
  U5D1   DD53  DDR5_MA<13>  SKX_EXT_B_BGA1  I172

M_F_MA<14>      @BASEBOARD_FAB2_LIB.BASEBOARD_FAB2(SCH_1):M_F_MA<14>
  J4A1   228  A14_WE_N  SCONN288_H44441004_PIP  I111
  J6L1   228  A14_WE_N  SCONN288_H44441003_PIP  I111
  U5D1   DJ50  DDR5_MA<14>  SKX_EXT_B_BGA1  I172

M_F_MA<15>      @BASEBOARD_FAB2_LIB.BASEBOARD_FAB2(SCH_1):M_F_MA<15>
  J4A1    86  A15_CAS_N  SCONN288_H44441004_PIP  I111
  J6L1    86  A15_CAS_N  SCONN288_H44441003_PIP  I111
  U5D1   DC54  DDR5_MA<15>  SKX_EXT_B_BGA1  I172

M_F_MA<16>      @BASEBOARD_FAB2_LIB.BASEBOARD_FAB2(SCH_1):M_F_MA<16>
  J4A1    82  A16_RAS_N  SCONN288_H44441004_PIP  I111
  J6L1    82  A16_RAS_N  SCONN288_H44441003_PIP  I111
  U5D1   DG52  DDR5_MA<16>  SKX_EXT_B_BGA1  I172

M_F_MA<17>      @BASEBOARD_FAB2_LIB.BASEBOARD_FAB2(SCH_1):M_F_MA<17>
  J4A1   234    A17  SCONN288_H44441004_PIP  I111
  J6L1   234    A17  SCONN288_H44441003_PIP  I111
  U5D1   DE46  DDR5_MA<17>  SKX_EXT_B_BGA1  I172

M_F_ODT<0>      @BASEBOARD_FAB2_LIB.BASEBOARD_FAB2(SCH_1):M_F_ODT<0>
  J4A1    87  ODT<0>  SCONN288_H44441004_PIP  I111
  U5D1   DG50  DDR5_ODT<0>  SKX_EXT_B_BGA1  I172

M_F_ODT<1>      @BASEBOARD_FAB2_LIB.BASEBOARD_FAB2(SCH_1):M_F_ODT<1>
  J4A1    91  ODT<1>  SCONN288_H44441004_PIP  I111
  U5D1   DG48  DDR5_ODT<1>  SKX_EXT_B_BGA1  I172

M_F_ODT<2>      @BASEBOARD_FAB2_LIB.BASEBOARD_FAB2(SCH_1):M_F_ODT<2>
  J6L1    87  ODT<0>  SCONN288_H44441003_PIP  I111
  U5D1   DK49  DDR5_ODT<2>  SKX_EXT_B_BGA1  I172

M_F_ODT<3>      @BASEBOARD_FAB2_LIB.BASEBOARD_FAB2(SCH_1):M_F_ODT<3>
  J6L1    91  ODT<1>  SCONN288_H44441003_PIP  I111
  U5D1   DF47  DDR5_ODT<3>  SKX_EXT_B_BGA1  I172

M_F_PAR         @BASEBOARD_FAB2_LIB.BASEBOARD_FAB2(SCH_1):M_F_PAR
  J4A1   222    PAR  SCONN288_H44441004_PIP  I111
  J6L1   222    PAR  SCONN288_H44441003_PIP  I111
  U5D1   DK53  DDR5_PAR  SKX_EXT_B_BGA1  I172

M_F_VREF        @BASEBOARD_FAB2_LIB.BASEBOARD_FAB2(SCH_1):M_F_VREF
  C4A5     1      A  CAP_A       I179
  C6L1     1      A  CAP_A       I178
  J4A1   146  VREFCA  SCONN288_H44441004_PIP  I111
  J6L1   146  VREFCA  SCONN288_H44441003_PIP  I111
  R6L1     1      A  RES         I64
  R6L2     2      B  RES         I62
  R6L3     2      B  RES         I66

M_GHJ_RST_N     @BASEBOARD_FAB2_LIB.BASEBOARD_FAB2(SCH_1):M_GHJ_RST_N
  J1G1    58  RESET_N  SCONN288_H44441004_PIP  I111
  J1G2    58  RESET_N  SCONN288_H44441004_PIP  I111
  J1G3    58  RESET_N  SCONN288_H44441004_PIP  I186
  J9T1    58  RESET_N  SCONN288_H44441003_PIP  I13
  J9U1    58  RESET_N  SCONN288_H44441003_PIP  I24
  J9U2    58  RESET_N  SCONN288_H44441003_PIP  I187
  U2D1   U64  DDR012_RESET_N  SKX_EXT_B_BGA1  I172

M_G_ACT_N       @BASEBOARD_FAB2_LIB.BASEBOARD_FAB2(SCH_1):M_G_ACT_N
  J1G1    62  ACT_N  SCONN288_H44441004_PIP  I111
  J9T1    62  ACT_N  SCONN288_H44441003_PIP  I13
  U2D1   J60  DDR0_ACT_N  SKX_EXT_B_BGA1  I172

M_G_ALERT_N     @BASEBOARD_FAB2_LIB.BASEBOARD_FAB2(SCH_1):M_G_ALERT_N
  J1G1   208  ALERT_N  SCONN288_H44441004_PIP  I111
  J9T1   208  ALERT_N  SCONN288_H44441003_PIP  I13
  U2D1   B61  DDR0_ALERT_N  SKX_EXT_B_BGA1  I172

M_G_BA<0>       @BASEBOARD_FAB2_LIB.BASEBOARD_FAB2(SCH_1):M_G_BA<0>
  J1G1    81  BA<0>  SCONN288_H44441004_PIP  I111
  J9T1    81  BA<0>  SCONN288_H44441003_PIP  I13
  U2D1   C52  DDR0_BA<0>  SKX_EXT_B_BGA1  I172

M_G_BA<1>       @BASEBOARD_FAB2_LIB.BASEBOARD_FAB2(SCH_1):M_G_BA<1>
  J1G1   224  BA<1>  SCONN288_H44441004_PIP  I111
  J9T1   224  BA<1>  SCONN288_H44441003_PIP  I13
  U2D1   G54  DDR0_BA<1>  SKX_EXT_B_BGA1  I172

M_G_BG<0>       @BASEBOARD_FAB2_LIB.BASEBOARD_FAB2(SCH_1):M_G_BG<0>
  J1G1    63  BG<0>  SCONN288_H44441004_PIP  I111
  J9T1    63  BG<0>  SCONN288_H44441003_PIP  I13
  U2D1   D61  DDR0_BG<0>  SKX_EXT_B_BGA1  I172

M_G_BG<1>       @BASEBOARD_FAB2_LIB.BASEBOARD_FAB2(SCH_1):M_G_BG<1>
  J1G1   207  BG<1>  SCONN288_H44441004_PIP  I111
  J9T1   207  BG<1>  SCONN288_H44441003_PIP  I13
  U2D1   F63  DDR0_BG<1>  SKX_EXT_B_BGA1  I172

M_G_C<2>        @BASEBOARD_FAB2_LIB.BASEBOARD_FAB2(SCH_1):M_G_C<2>
  J1G1   235   C<2>  SCONN288_H44441004_PIP  I111
  J9T1   235   C<2>  SCONN288_H44441003_PIP  I13
  U2D1   G46  DDR0_CID<2>  SKX_EXT_B_BGA1  I172

M_G_CKE<0>      @BASEBOARD_FAB2_LIB.BASEBOARD_FAB2(SCH_1):M_G_CKE<0>
  J1G1    60  CKE<0>  SCONN288_H44441004_PIP  I111
  U2D1   C62  DDR0_CKE<0>  SKX_EXT_B_BGA1  I172

M_G_CKE<1>      @BASEBOARD_FAB2_LIB.BASEBOARD_FAB2(SCH_1):M_G_CKE<1>
  J1G1   203  CKE<1>  SCONN288_H44441004_PIP  I111
  U2D1   C64  DDR0_CKE<1>  SKX_EXT_B_BGA1  I172

M_G_CKE<2>      @BASEBOARD_FAB2_LIB.BASEBOARD_FAB2(SCH_1):M_G_CKE<2>
  J9T1    60  CKE<0>  SCONN288_H44441003_PIP  I13
  U2D1   B63  DDR0_CKE<2>  SKX_EXT_B_BGA1  I172

M_G_CKE<3>      @BASEBOARD_FAB2_LIB.BASEBOARD_FAB2(SCH_1):M_G_CKE<3>
  J9T1   203  CKE<1>  SCONN288_H44441003_PIP  I13
  U2D1   D63  DDR0_CKE<3>  SKX_EXT_B_BGA1  I172

M_G_CLK_DN<0>   @BASEBOARD_FAB2_LIB.BASEBOARD_FAB2(SCH_1):M_G_CLK_DN<0>
  J1G1    75   CK0N  SCONN288_H44441004_PIP  I111
  U2D1   F55  DDR0_CLK_DN<0>  SKX_EXT_B_BGA1  I172

M_G_CLK_DN<1>   @BASEBOARD_FAB2_LIB.BASEBOARD_FAB2(SCH_1):M_G_CLK_DN<1>
  J1G1   219   CK1N  SCONN288_H44441004_PIP  I111
  U2D1   C54  DDR0_CLK_DN<1>  SKX_EXT_B_BGA1  I172

M_G_CLK_DN<2>   @BASEBOARD_FAB2_LIB.BASEBOARD_FAB2(SCH_1):M_G_CLK_DN<2>
  J9T1    75   CK0N  SCONN288_H44441003_PIP  I13
  U2D1   J56  DDR0_CLK_DN<2>  SKX_EXT_B_BGA1  I172

M_G_CLK_DN<3>   @BASEBOARD_FAB2_LIB.BASEBOARD_FAB2(SCH_1):M_G_CLK_DN<3>
  J9T1   219   CK1N  SCONN288_H44441003_PIP  I13
  U2D1   C56  DDR0_CLK_DN<3>  SKX_EXT_B_BGA1  I172

M_G_CLK_DP<0>   @BASEBOARD_FAB2_LIB.BASEBOARD_FAB2(SCH_1):M_G_CLK_DP<0>
  J1G1    74   CK0P  SCONN288_H44441004_PIP  I111
  U2D1   D55  DDR0_CLK_DP<0>  SKX_EXT_B_BGA1  I172

M_G_CLK_DP<1>   @BASEBOARD_FAB2_LIB.BASEBOARD_FAB2(SCH_1):M_G_CLK_DP<1>
  J1G1   218   CK1P  SCONN288_H44441004_PIP  I111
  U2D1   B55  DDR0_CLK_DP<1>  SKX_EXT_B_BGA1  I172

M_G_CLK_DP<2>   @BASEBOARD_FAB2_LIB.BASEBOARD_FAB2(SCH_1):M_G_CLK_DP<2>
  J9T1    74   CK0P  SCONN288_H44441003_PIP  I13
  U2D1   G56  DDR0_CLK_DP<2>  SKX_EXT_B_BGA1  I172

M_G_CLK_DP<3>   @BASEBOARD_FAB2_LIB.BASEBOARD_FAB2(SCH_1):M_G_CLK_DP<3>
  J9T1   218   CK1P  SCONN288_H44441003_PIP  I13
  U2D1   B57  DDR0_CLK_DP<3>  SKX_EXT_B_BGA1  I172

M_G_CPU_VREF    @BASEBOARD_FAB2_LIB.BASEBOARD_FAB2(SCH_1):M_G_CPU_VREF
  C1F19    1      A  CAP_A        I8
  R1F4     1      A  RES          I7
  U2D1   AJ64  DDR0_CAVREF  SKX_EXT_B_BGA1  I172

M_G_CS_N<0>     @BASEBOARD_FAB2_LIB.BASEBOARD_FAB2(SCH_1):M_G_CS_N<0>
  J1G1    84   S0_N  SCONN288_H44441004_PIP  I111
  U2D1   G52  DDR0_CS_N<0>  SKX_EXT_B_BGA1  I172

M_G_CS_N<1>     @BASEBOARD_FAB2_LIB.BASEBOARD_FAB2(SCH_1):M_G_CS_N<1>
  J1G1    89   S1_N  SCONN288_H44441004_PIP  I111
  U2D1   F49  DDR0_CS_N<1>  SKX_EXT_B_BGA1  I172

M_G_CS_N<2>     @BASEBOARD_FAB2_LIB.BASEBOARD_FAB2(SCH_1):M_G_CS_N<2>
  J1G1    93  S2_N_C<0>  SCONN288_H44441004_PIP  I111
  U2D1   D47  DDR0_CS_N<2>  SKX_EXT_B_BGA1  I172

M_G_CS_N<3>     @BASEBOARD_FAB2_LIB.BASEBOARD_FAB2(SCH_1):M_G_CS_N<3>
  J1G1   237  S3_N_C<1>  SCONN288_H44441004_PIP  I111
  U2D1   F47  DDR0_CS_N<3>  SKX_EXT_B_BGA1  I172

M_G_CS_N<4>     @BASEBOARD_FAB2_LIB.BASEBOARD_FAB2(SCH_1):M_G_CS_N<4>
  J9T1    84   S0_N  SCONN288_H44441003_PIP  I13
  U2D1   B51  DDR0_CS_N<4>  SKX_EXT_B_BGA1  I172

M_G_CS_N<5>     @BASEBOARD_FAB2_LIB.BASEBOARD_FAB2(SCH_1):M_G_CS_N<5>
  J9T1    89   S1_N  SCONN288_H44441003_PIP  I13
  U2D1   D49  DDR0_CS_N<5>  SKX_EXT_B_BGA1  I172

M_G_CS_N<6>     @BASEBOARD_FAB2_LIB.BASEBOARD_FAB2(SCH_1):M_G_CS_N<6>
  J9T1    93  S2_N_C<0>  SCONN288_H44441003_PIP  I13
  U2D1   F45  DDR0_CS_N<6>  SKX_EXT_B_BGA1  I172

M_G_CS_N<7>     @BASEBOARD_FAB2_LIB.BASEBOARD_FAB2(SCH_1):M_G_CS_N<7>
  J9T1   237  S3_N_C<1>  SCONN288_H44441003_PIP  I13
  U2D1   K45  DDR0_CS_N<7>  SKX_EXT_B_BGA1  I172

M_G_DQ<0>       @BASEBOARD_FAB2_LIB.BASEBOARD_FAB2(SCH_1):M_G_DQ<0>
  J1G1   150  DQ<1>  SCONN288_H44441004_PIP  I111
  J9T1     5  DQ<0>  SCONN288_H44441003_PIP  I13
  U2D1   AN86  DDR0_DQ<0>  SKX_EXT_B_BGA1  I172

M_G_DQ<1>       @BASEBOARD_FAB2_LIB.BASEBOARD_FAB2(SCH_1):M_G_DQ<1>
  J1G1     5  DQ<0>  SCONN288_H44441004_PIP  I111
  J9T1   150  DQ<1>  SCONN288_H44441003_PIP  I13
  U2D1   AN84  DDR0_DQ<1>  SKX_EXT_B_BGA1  I172

M_G_DQ<2>       @BASEBOARD_FAB2_LIB.BASEBOARD_FAB2(SCH_1):M_G_DQ<2>
  J1G1   157  DQ<3>  SCONN288_H44441004_PIP  I111
  J9T1    12  DQ<2>  SCONN288_H44441003_PIP  I13
  U2D1   AE86  DDR0_DQ<2>  SKX_EXT_B_BGA1  I172

M_G_DQ<3>       @BASEBOARD_FAB2_LIB.BASEBOARD_FAB2(SCH_1):M_G_DQ<3>
  J1G1    12  DQ<2>  SCONN288_H44441004_PIP  I111
  J9T1   157  DQ<3>  SCONN288_H44441003_PIP  I13
  U2D1   AE84  DDR0_DQ<3>  SKX_EXT_B_BGA1  I172

M_G_DQ<4>       @BASEBOARD_FAB2_LIB.BASEBOARD_FAB2(SCH_1):M_G_DQ<4>
  J1G1   148  DQ<5>  SCONN288_H44441004_PIP  I111
  J9T1     3  DQ<4>  SCONN288_H44441003_PIP  I13
  U2D1   AR86  DDR0_DQ<4>  SKX_EXT_B_BGA1  I172

M_G_DQ<5>       @BASEBOARD_FAB2_LIB.BASEBOARD_FAB2(SCH_1):M_G_DQ<5>
  J1G1     3  DQ<4>  SCONN288_H44441004_PIP  I111
  J9T1   148  DQ<5>  SCONN288_H44441003_PIP  I13
  U2D1   AR84  DDR0_DQ<5>  SKX_EXT_B_BGA1  I172

M_G_DQ<6>       @BASEBOARD_FAB2_LIB.BASEBOARD_FAB2(SCH_1):M_G_DQ<6>
  J1G1   155  DQ<7>  SCONN288_H44441004_PIP  I111
  J9T1    10  DQ<6>  SCONN288_H44441003_PIP  I13
  U2D1   AG86  DDR0_DQ<6>  SKX_EXT_B_BGA1  I172

M_G_DQ<7>       @BASEBOARD_FAB2_LIB.BASEBOARD_FAB2(SCH_1):M_G_DQ<7>
  J1G1    10  DQ<6>  SCONN288_H44441004_PIP  I111
  J9T1   155  DQ<7>  SCONN288_H44441003_PIP  I13
  U2D1   AG84  DDR0_DQ<7>  SKX_EXT_B_BGA1  I172

M_G_DQ<8>       @BASEBOARD_FAB2_LIB.BASEBOARD_FAB2(SCH_1):M_G_DQ<8>
  J1G1   161  DQ<9>  SCONN288_H44441004_PIP  I111
  J9T1    16  DQ<8>  SCONN288_H44441003_PIP  I13
  U2D1   W86  DDR0_DQ<8>  SKX_EXT_B_BGA1  I172

M_G_DQ<9>       @BASEBOARD_FAB2_LIB.BASEBOARD_FAB2(SCH_1):M_G_DQ<9>
  J1G1    16  DQ<8>  SCONN288_H44441004_PIP  I111
  J9T1   161  DQ<9>  SCONN288_H44441003_PIP  I13
  U2D1   W84  DDR0_DQ<9>  SKX_EXT_B_BGA1  I172

M_G_DQ<10>      @BASEBOARD_FAB2_LIB.BASEBOARD_FAB2(SCH_1):M_G_DQ<10>
  J1G1   168  DQ<11>  SCONN288_H44441004_PIP  I111
  J9T1    23  DQ<10>  SCONN288_H44441003_PIP  I13
  U2D1   L86  DDR0_DQ<10>  SKX_EXT_B_BGA1  I172

M_G_DQ<11>      @BASEBOARD_FAB2_LIB.BASEBOARD_FAB2(SCH_1):M_G_DQ<11>
  J1G1    23  DQ<10>  SCONN288_H44441004_PIP  I111
  J9T1   168  DQ<11>  SCONN288_H44441003_PIP  I13
  U2D1   L84  DDR0_DQ<11>  SKX_EXT_B_BGA1  I172

M_G_DQ<12>      @BASEBOARD_FAB2_LIB.BASEBOARD_FAB2(SCH_1):M_G_DQ<12>
  J1G1   159  DQ<13>  SCONN288_H44441004_PIP  I111
  J9T1    14  DQ<12>  SCONN288_H44441003_PIP  I13
  U2D1   AA86  DDR0_DQ<12>  SKX_EXT_B_BGA1  I172

M_G_DQ<13>      @BASEBOARD_FAB2_LIB.BASEBOARD_FAB2(SCH_1):M_G_DQ<13>
  J1G1    14  DQ<12>  SCONN288_H44441004_PIP  I111
  J9T1   159  DQ<13>  SCONN288_H44441003_PIP  I13
  U2D1   AA84  DDR0_DQ<13>  SKX_EXT_B_BGA1  I172

M_G_DQ<14>      @BASEBOARD_FAB2_LIB.BASEBOARD_FAB2(SCH_1):M_G_DQ<14>
  J1G1   166  DQ<15>  SCONN288_H44441004_PIP  I111
  J9T1    21  DQ<14>  SCONN288_H44441003_PIP  I13
  U2D1   N86  DDR0_DQ<14>  SKX_EXT_B_BGA1  I172

M_G_DQ<15>      @BASEBOARD_FAB2_LIB.BASEBOARD_FAB2(SCH_1):M_G_DQ<15>
  J1G1    21  DQ<14>  SCONN288_H44441004_PIP  I111
  J9T1   166  DQ<15>  SCONN288_H44441003_PIP  I13
  U2D1   N84  DDR0_DQ<15>  SKX_EXT_B_BGA1  I172

M_G_DQ<16>      @BASEBOARD_FAB2_LIB.BASEBOARD_FAB2(SCH_1):M_G_DQ<16>
  J1G1   172  DQ<17>  SCONN288_H44441004_PIP  I111
  J9T1    27  DQ<16>  SCONN288_H44441003_PIP  I13
  U2D1   V81  DDR0_DQ<16>  SKX_EXT_B_BGA1  I172

M_G_DQ<17>      @BASEBOARD_FAB2_LIB.BASEBOARD_FAB2(SCH_1):M_G_DQ<17>
  J1G1    27  DQ<16>  SCONN288_H44441004_PIP  I111
  J9T1   172  DQ<17>  SCONN288_H44441003_PIP  I13
  U2D1   T79  DDR0_DQ<17>  SKX_EXT_B_BGA1  I172

M_G_DQ<18>      @BASEBOARD_FAB2_LIB.BASEBOARD_FAB2(SCH_1):M_G_DQ<18>
  J1G1   179  DQ<19>  SCONN288_H44441004_PIP  I111
  J9T1    34  DQ<18>  SCONN288_H44441003_PIP  I13
  U2D1   N82  DDR0_DQ<18>  SKX_EXT_B_BGA1  I172

M_G_DQ<19>      @BASEBOARD_FAB2_LIB.BASEBOARD_FAB2(SCH_1):M_G_DQ<19>
  J1G1    34  DQ<18>  SCONN288_H44441004_PIP  I111
  J9T1   179  DQ<19>  SCONN288_H44441003_PIP  I13
  U2D1   M81  DDR0_DQ<19>  SKX_EXT_B_BGA1  I172

M_G_DQ<20>      @BASEBOARD_FAB2_LIB.BASEBOARD_FAB2(SCH_1):M_G_DQ<20>
  J1G1   170  DQ<21>  SCONN288_H44441004_PIP  I111
  J9T1    25  DQ<20>  SCONN288_H44441003_PIP  I13
  U2D1   W80  DDR0_DQ<20>  SKX_EXT_B_BGA1  I172

M_G_DQ<21>      @BASEBOARD_FAB2_LIB.BASEBOARD_FAB2(SCH_1):M_G_DQ<21>
  J1G1    25  DQ<20>  SCONN288_H44441004_PIP  I111
  J9T1   170  DQ<21>  SCONN288_H44441003_PIP  I13
  U2D1   V79  DDR0_DQ<21>  SKX_EXT_B_BGA1  I172

M_G_DQ<22>      @BASEBOARD_FAB2_LIB.BASEBOARD_FAB2(SCH_1):M_G_DQ<22>
  J1G1   177  DQ<23>  SCONN288_H44441004_PIP  I111
  J9T1    32  DQ<22>  SCONN288_H44441003_PIP  I13
  U2D1   R82  DDR0_DQ<22>  SKX_EXT_B_BGA1  I172

M_G_DQ<23>      @BASEBOARD_FAB2_LIB.BASEBOARD_FAB2(SCH_1):M_G_DQ<23>
  J1G1    32  DQ<22>  SCONN288_H44441004_PIP  I111
  J9T1   177  DQ<23>  SCONN288_H44441003_PIP  I13
  U2D1   N80  DDR0_DQ<23>  SKX_EXT_B_BGA1  I172

M_G_DQ<24>      @BASEBOARD_FAB2_LIB.BASEBOARD_FAB2(SCH_1):M_G_DQ<24>
  J1G1   183  DQ<25>  SCONN288_H44441004_PIP  I111
  J9T1    38  DQ<24>  SCONN288_H44441003_PIP  I13
  U2D1   L76  DDR0_DQ<24>  SKX_EXT_B_BGA1  I172

M_G_DQ<25>      @BASEBOARD_FAB2_LIB.BASEBOARD_FAB2(SCH_1):M_G_DQ<25>
  J1G1    38  DQ<24>  SCONN288_H44441004_PIP  I111
  J9T1   183  DQ<25>  SCONN288_H44441003_PIP  I13
  U2D1   R76  DDR0_DQ<25>  SKX_EXT_B_BGA1  I172

M_G_DQ<26>      @BASEBOARD_FAB2_LIB.BASEBOARD_FAB2(SCH_1):M_G_DQ<26>
  J1G1   190  DQ<27>  SCONN288_H44441004_PIP  I111
  J9T1    45  DQ<26>  SCONN288_H44441003_PIP  I13
  U2D1   M73  DDR0_DQ<26>  SKX_EXT_B_BGA1  I172

M_G_DQ<27>      @BASEBOARD_FAB2_LIB.BASEBOARD_FAB2(SCH_1):M_G_DQ<27>
  J1G1    45  DQ<26>  SCONN288_H44441004_PIP  I111
  J9T1   190  DQ<27>  SCONN288_H44441003_PIP  I13
  U2D1   P73  DDR0_DQ<27>  SKX_EXT_B_BGA1  I172

M_G_DQ<28>      @BASEBOARD_FAB2_LIB.BASEBOARD_FAB2(SCH_1):M_G_DQ<28>
  J1G1   181  DQ<29>  SCONN288_H44441004_PIP  I111
  J9T1    36  DQ<28>  SCONN288_H44441003_PIP  I13
  U2D1   M77  DDR0_DQ<28>  SKX_EXT_B_BGA1  I172

M_G_DQ<29>      @BASEBOARD_FAB2_LIB.BASEBOARD_FAB2(SCH_1):M_G_DQ<29>
  J1G1    36  DQ<28>  SCONN288_H44441004_PIP  I111
  J9T1   181  DQ<29>  SCONN288_H44441003_PIP  I13
  U2D1   P77  DDR0_DQ<29>  SKX_EXT_B_BGA1  I172

M_G_DQ<30>      @BASEBOARD_FAB2_LIB.BASEBOARD_FAB2(SCH_1):M_G_DQ<30>
  J1G1   188  DQ<31>  SCONN288_H44441004_PIP  I111
  J9T1    43  DQ<30>  SCONN288_H44441003_PIP  I13
  U2D1   L74  DDR0_DQ<30>  SKX_EXT_B_BGA1  I172

M_G_DQ<31>      @BASEBOARD_FAB2_LIB.BASEBOARD_FAB2(SCH_1):M_G_DQ<31>
  J1G1    43  DQ<30>  SCONN288_H44441004_PIP  I111
  J9T1   188  DQ<31>  SCONN288_H44441003_PIP  I13
  U2D1   R74  DDR0_DQ<31>  SKX_EXT_B_BGA1  I172

M_G_DQ<32>      @BASEBOARD_FAB2_LIB.BASEBOARD_FAB2(SCH_1):M_G_DQ<32>
  J1G1   242  DQ<33>  SCONN288_H44441004_PIP  I111
  J9T1    97  DQ<32>  SCONN288_H44441003_PIP  I13
  U2D1   C42  DDR0_DQ<32>  SKX_EXT_B_BGA1  I172

M_G_DQ<33>      @BASEBOARD_FAB2_LIB.BASEBOARD_FAB2(SCH_1):M_G_DQ<33>
  J1G1    97  DQ<32>  SCONN288_H44441004_PIP  I111
  J9T1   242  DQ<33>  SCONN288_H44441003_PIP  I13
  U2D1   B41  DDR0_DQ<33>  SKX_EXT_B_BGA1  I172

M_G_DQ<34>      @BASEBOARD_FAB2_LIB.BASEBOARD_FAB2(SCH_1):M_G_DQ<34>
  J1G1   249  DQ<35>  SCONN288_H44441004_PIP  I111
  J9T1   104  DQ<34>  SCONN288_H44441003_PIP  I13
  U2D1   C38  DDR0_DQ<34>  SKX_EXT_B_BGA1  I172

M_G_DQ<35>      @BASEBOARD_FAB2_LIB.BASEBOARD_FAB2(SCH_1):M_G_DQ<35>
  J1G1   104  DQ<34>  SCONN288_H44441004_PIP  I111
  J9T1   249  DQ<35>  SCONN288_H44441003_PIP  I13
  U2D1   E38  DDR0_DQ<35>  SKX_EXT_B_BGA1  I172

M_G_DQ<36>      @BASEBOARD_FAB2_LIB.BASEBOARD_FAB2(SCH_1):M_G_DQ<36>
  J1G1   240  DQ<37>  SCONN288_H44441004_PIP  I111
  J9T1    95  DQ<36>  SCONN288_H44441003_PIP  I13
  U2D1   E42  DDR0_DQ<36>  SKX_EXT_B_BGA1  I172

M_G_DQ<37>      @BASEBOARD_FAB2_LIB.BASEBOARD_FAB2(SCH_1):M_G_DQ<37>
  J1G1    95  DQ<36>  SCONN288_H44441004_PIP  I111
  J9T1   240  DQ<37>  SCONN288_H44441003_PIP  I13
  U2D1   F41  DDR0_DQ<37>  SKX_EXT_B_BGA1  I172

M_G_DQ<38>      @BASEBOARD_FAB2_LIB.BASEBOARD_FAB2(SCH_1):M_G_DQ<38>
  J1G1   247  DQ<39>  SCONN288_H44441004_PIP  I111
  J9T1   102  DQ<38>  SCONN288_H44441003_PIP  I13
  U2D1   B39  DDR0_DQ<38>  SKX_EXT_B_BGA1  I172

M_G_DQ<39>      @BASEBOARD_FAB2_LIB.BASEBOARD_FAB2(SCH_1):M_G_DQ<39>
  J1G1   102  DQ<38>  SCONN288_H44441004_PIP  I111
  J9T1   247  DQ<39>  SCONN288_H44441003_PIP  I13
  U2D1   F39  DDR0_DQ<39>  SKX_EXT_B_BGA1  I172

M_G_DQ<40>      @BASEBOARD_FAB2_LIB.BASEBOARD_FAB2(SCH_1):M_G_DQ<40>
  J1G1   253  DQ<41>  SCONN288_H44441004_PIP  I111
  J9T1   108  DQ<40>  SCONN288_H44441003_PIP  I13
  U2D1   K37  DDR0_DQ<40>  SKX_EXT_B_BGA1  I172

M_G_DQ<41>      @BASEBOARD_FAB2_LIB.BASEBOARD_FAB2(SCH_1):M_G_DQ<41>
  J1G1   108  DQ<40>  SCONN288_H44441004_PIP  I111
  J9T1   253  DQ<41>  SCONN288_H44441003_PIP  I13
  U2D1   P37  DDR0_DQ<41>  SKX_EXT_B_BGA1  I172

M_G_DQ<42>      @BASEBOARD_FAB2_LIB.BASEBOARD_FAB2(SCH_1):M_G_DQ<42>
  J1G1   260  DQ<43>  SCONN288_H44441004_PIP  I111
  J9T1   115  DQ<42>  SCONN288_H44441003_PIP  I13
  U2D1   L34  DDR0_DQ<42>  SKX_EXT_B_BGA1  I172

M_G_DQ<43>      @BASEBOARD_FAB2_LIB.BASEBOARD_FAB2(SCH_1):M_G_DQ<43>
  J1G1   115  DQ<42>  SCONN288_H44441004_PIP  I111
  J9T1   260  DQ<43>  SCONN288_H44441003_PIP  I13
  U2D1   N34  DDR0_DQ<43>  SKX_EXT_B_BGA1  I172

M_G_DQ<44>      @BASEBOARD_FAB2_LIB.BASEBOARD_FAB2(SCH_1):M_G_DQ<44>
  J1G1   251  DQ<45>  SCONN288_H44441004_PIP  I111
  J9T1   106  DQ<44>  SCONN288_H44441003_PIP  I13
  U2D1   L38  DDR0_DQ<44>  SKX_EXT_B_BGA1  I172

M_G_DQ<45>      @BASEBOARD_FAB2_LIB.BASEBOARD_FAB2(SCH_1):M_G_DQ<45>
  J1G1   106  DQ<44>  SCONN288_H44441004_PIP  I111
  J9T1   251  DQ<45>  SCONN288_H44441003_PIP  I13
  U2D1   N38  DDR0_DQ<45>  SKX_EXT_B_BGA1  I172

M_G_DQ<46>      @BASEBOARD_FAB2_LIB.BASEBOARD_FAB2(SCH_1):M_G_DQ<46>
  J1G1   258  DQ<47>  SCONN288_H44441004_PIP  I111
  J9T1   113  DQ<46>  SCONN288_H44441003_PIP  I13
  U2D1   K35  DDR0_DQ<46>  SKX_EXT_B_BGA1  I172

M_G_DQ<47>      @BASEBOARD_FAB2_LIB.BASEBOARD_FAB2(SCH_1):M_G_DQ<47>
  J1G1   113  DQ<46>  SCONN288_H44441004_PIP  I111
  J9T1   258  DQ<47>  SCONN288_H44441003_PIP  I13
  U2D1   P35  DDR0_DQ<47>  SKX_EXT_B_BGA1  I172

M_G_DQ<48>      @BASEBOARD_FAB2_LIB.BASEBOARD_FAB2(SCH_1):M_G_DQ<48>
  J1G1   264  DQ<49>  SCONN288_H44441004_PIP  I111
  J9T1   119  DQ<48>  SCONN288_H44441003_PIP  I13
  U2D1   K31  DDR0_DQ<48>  SKX_EXT_B_BGA1  I172

M_G_DQ<49>      @BASEBOARD_FAB2_LIB.BASEBOARD_FAB2(SCH_1):M_G_DQ<49>
  J1G1   119  DQ<48>  SCONN288_H44441004_PIP  I111
  J9T1   264  DQ<49>  SCONN288_H44441003_PIP  I13
  U2D1   P31  DDR0_DQ<49>  SKX_EXT_B_BGA1  I172

M_G_DQ<50>      @BASEBOARD_FAB2_LIB.BASEBOARD_FAB2(SCH_1):M_G_DQ<50>
  J1G1   271  DQ<51>  SCONN288_H44441004_PIP  I111
  J9T1   126  DQ<50>  SCONN288_H44441003_PIP  I13
  U2D1   L28  DDR0_DQ<50>  SKX_EXT_B_BGA1  I172

M_G_DQ<51>      @BASEBOARD_FAB2_LIB.BASEBOARD_FAB2(SCH_1):M_G_DQ<51>
  J1G1   126  DQ<50>  SCONN288_H44441004_PIP  I111
  J9T1   271  DQ<51>  SCONN288_H44441003_PIP  I13
  U2D1   N28  DDR0_DQ<51>  SKX_EXT_B_BGA1  I172

M_G_DQ<52>      @BASEBOARD_FAB2_LIB.BASEBOARD_FAB2(SCH_1):M_G_DQ<52>
  J1G1   262  DQ<53>  SCONN288_H44441004_PIP  I111
  J9T1   117  DQ<52>  SCONN288_H44441003_PIP  I13
  U2D1   L32  DDR0_DQ<52>  SKX_EXT_B_BGA1  I172

M_G_DQ<53>      @BASEBOARD_FAB2_LIB.BASEBOARD_FAB2(SCH_1):M_G_DQ<53>
  J1G1   117  DQ<52>  SCONN288_H44441004_PIP  I111
  J9T1   262  DQ<53>  SCONN288_H44441003_PIP  I13
  U2D1   N32  DDR0_DQ<53>  SKX_EXT_B_BGA1  I172

M_G_DQ<54>      @BASEBOARD_FAB2_LIB.BASEBOARD_FAB2(SCH_1):M_G_DQ<54>
  J1G1   269  DQ<55>  SCONN288_H44441004_PIP  I111
  J9T1   124  DQ<54>  SCONN288_H44441003_PIP  I13
  U2D1   K29  DDR0_DQ<54>  SKX_EXT_B_BGA1  I172

M_G_DQ<55>      @BASEBOARD_FAB2_LIB.BASEBOARD_FAB2(SCH_1):M_G_DQ<55>
  J1G1   124  DQ<54>  SCONN288_H44441004_PIP  I111
  J9T1   269  DQ<55>  SCONN288_H44441003_PIP  I13
  U2D1   P29  DDR0_DQ<55>  SKX_EXT_B_BGA1  I172

M_G_DQ<56>      @BASEBOARD_FAB2_LIB.BASEBOARD_FAB2(SCH_1):M_G_DQ<56>
  J1G1   275  DQ<57>  SCONN288_H44441004_PIP  I111
  J9T1   130  DQ<56>  SCONN288_H44441003_PIP  I13
  U2D1   K25  DDR0_DQ<56>  SKX_EXT_B_BGA1  I172

M_G_DQ<57>      @BASEBOARD_FAB2_LIB.BASEBOARD_FAB2(SCH_1):M_G_DQ<57>
  J1G1   130  DQ<56>  SCONN288_H44441004_PIP  I111
  J9T1   275  DQ<57>  SCONN288_H44441003_PIP  I13
  U2D1   P25  DDR0_DQ<57>  SKX_EXT_B_BGA1  I172

M_G_DQ<58>      @BASEBOARD_FAB2_LIB.BASEBOARD_FAB2(SCH_1):M_G_DQ<58>
  J1G1   282  DQ<59>  SCONN288_H44441004_PIP  I111
  J9T1   137  DQ<58>  SCONN288_H44441003_PIP  I13
  U2D1   P23  DDR0_DQ<58>  SKX_EXT_B_BGA1  I172

M_G_DQ<59>      @BASEBOARD_FAB2_LIB.BASEBOARD_FAB2(SCH_1):M_G_DQ<59>
  J1G1   137  DQ<58>  SCONN288_H44441004_PIP  I111
  J9T1   282  DQ<59>  SCONN288_H44441003_PIP  I13
  U2D1   T23  DDR0_DQ<59>  SKX_EXT_B_BGA1  I172

M_G_DQ<60>      @BASEBOARD_FAB2_LIB.BASEBOARD_FAB2(SCH_1):M_G_DQ<60>
  J1G1   273  DQ<61>  SCONN288_H44441004_PIP  I111
  J9T1   128  DQ<60>  SCONN288_H44441003_PIP  I13
  U2D1   L26  DDR0_DQ<60>  SKX_EXT_B_BGA1  I172

M_G_DQ<61>      @BASEBOARD_FAB2_LIB.BASEBOARD_FAB2(SCH_1):M_G_DQ<61>
  J1G1   128  DQ<60>  SCONN288_H44441004_PIP  I111
  J9T1   273  DQ<61>  SCONN288_H44441003_PIP  I13
  U2D1   N26  DDR0_DQ<61>  SKX_EXT_B_BGA1  I172

M_G_DQ<62>      @BASEBOARD_FAB2_LIB.BASEBOARD_FAB2(SCH_1):M_G_DQ<62>
  J1G1   280  DQ<63>  SCONN288_H44441004_PIP  I111
  J9T1   135  DQ<62>  SCONN288_H44441003_PIP  I13
  U2D1   H23  DDR0_DQ<62>  SKX_EXT_B_BGA1  I172

M_G_DQ<63>      @BASEBOARD_FAB2_LIB.BASEBOARD_FAB2(SCH_1):M_G_DQ<63>
  J1G1   135  DQ<62>  SCONN288_H44441004_PIP  I111
  J9T1   280  DQ<63>  SCONN288_H44441003_PIP  I13
  U2D1   K23  DDR0_DQ<63>  SKX_EXT_B_BGA1  I172

M_G_DQS_DN<0>   @BASEBOARD_FAB2_LIB.BASEBOARD_FAB2(SCH_1):M_G_DQS_DN<0>
  J1G1   152  DQS0N  SCONN288_H44441004_PIP  I66
  J9T1   152  DQS0N  SCONN288_H44441003_PIP  I120
  U2D1   AJ84  DDR0_DQS_DN<0>  SKX_EXT_B_BGA1  I172

M_G_DQS_DN<1>   @BASEBOARD_FAB2_LIB.BASEBOARD_FAB2(SCH_1):M_G_DQS_DN<1>
  J1G1   163  DQS1N  SCONN288_H44441004_PIP  I66
  J9T1   163  DQS1N  SCONN288_H44441003_PIP  I120
  U2D1   R84  DDR0_DQS_DN<1>  SKX_EXT_B_BGA1  I172

M_G_DQS_DN<2>   @BASEBOARD_FAB2_LIB.BASEBOARD_FAB2(SCH_1):M_G_DQS_DN<2>
  J1G1   174  DQS2N  SCONN288_H44441004_PIP  I66
  J9T1   174  DQS2N  SCONN288_H44441003_PIP  I120
  U2D1   P79  DDR0_DQS_DN<2>  SKX_EXT_B_BGA1  I172

M_G_DQS_DN<3>   @BASEBOARD_FAB2_LIB.BASEBOARD_FAB2(SCH_1):M_G_DQS_DN<3>
  J1G1   185  DQS3N  SCONN288_H44441004_PIP  I66
  J9T1   185  DQS3N  SCONN288_H44441003_PIP  I120
  U2D1   T75  DDR0_DQS_DN<3>  SKX_EXT_B_BGA1  I172

M_G_DQS_DN<4>   @BASEBOARD_FAB2_LIB.BASEBOARD_FAB2(SCH_1):M_G_DQS_DN<4>
  J1G1   244  DQS4N  SCONN288_H44441004_PIP  I66
  J9T1   244  DQS4N  SCONN288_H44441003_PIP  I120
  U2D1   G40  DDR0_DQS_DN<4>  SKX_EXT_B_BGA1  I172

M_G_DQS_DN<5>   @BASEBOARD_FAB2_LIB.BASEBOARD_FAB2(SCH_1):M_G_DQS_DN<5>
  J1G1   255  DQS5N  SCONN288_H44441004_PIP  I66
  J9T1   255  DQS5N  SCONN288_H44441003_PIP  I120
  U2D1   R36  DDR0_DQS_DN<5>  SKX_EXT_B_BGA1  I172

M_G_DQS_DN<6>   @BASEBOARD_FAB2_LIB.BASEBOARD_FAB2(SCH_1):M_G_DQS_DN<6>
  J1G1   266  DQS6N  SCONN288_H44441004_PIP  I66
  J9T1   266  DQS6N  SCONN288_H44441003_PIP  I120
  U2D1   R30  DDR0_DQS_DN<6>  SKX_EXT_B_BGA1  I172

M_G_DQS_DN<7>   @BASEBOARD_FAB2_LIB.BASEBOARD_FAB2(SCH_1):M_G_DQS_DN<7>
  J1G1   277  DQS7N  SCONN288_H44441004_PIP  I66
  J9T1   277  DQS7N  SCONN288_H44441003_PIP  I120
  U2D1   N24  DDR0_DQS_DN<7>  SKX_EXT_B_BGA1  I172

M_G_DQS_DN<8>   @BASEBOARD_FAB2_LIB.BASEBOARD_FAB2(SCH_1):M_G_DQS_DN<8>
  J1G1   196  DQS8N  SCONN288_H44441004_PIP  I66
  J9T1   196  DQS8N  SCONN288_H44441003_PIP  I120
  U2D1   AH67  DDR0_DQS_DN<8>  SKX_EXT_B_BGA1  I172

M_G_DQS_DN<9>   @BASEBOARD_FAB2_LIB.BASEBOARD_FAB2(SCH_1):M_G_DQS_DN<9>
  J1G1     8  DQS9N  SCONN288_H44441004_PIP  I66
  J9T1     8  DQS9N  SCONN288_H44441003_PIP  I120
  U2D1   AL84  DDR0_DQS_DN<9>  SKX_EXT_B_BGA1  I172

M_G_DQS_DN<10>   @BASEBOARD_FAB2_LIB.BASEBOARD_FAB2(SCH_1):M_G_DQS_DN<10>
  J1G1    19  DQS10N  SCONN288_H44441004_PIP  I66
  J9T1    19  DQS10N  SCONN288_H44441003_PIP  I120
  U2D1   U84  DDR0_DQS_DN<10>  SKX_EXT_B_BGA1  I172

M_G_DQS_DN<11>   @BASEBOARD_FAB2_LIB.BASEBOARD_FAB2(SCH_1):M_G_DQS_DN<11>
  J1G1    30  DQS11N  SCONN288_H44441004_PIP  I66
  J9T1    30  DQS11N  SCONN288_H44441003_PIP  I120
  U2D1   U82  DDR0_DQS_DN<11>  SKX_EXT_B_BGA1  I172

M_G_DQS_DN<12>   @BASEBOARD_FAB2_LIB.BASEBOARD_FAB2(SCH_1):M_G_DQS_DN<12>
  J1G1    41  DQS12N  SCONN288_H44441004_PIP  I66
  J9T1    41  DQS12N  SCONN288_H44441003_PIP  I120
  U2D1   K75  DDR0_DQS_DN<12>  SKX_EXT_B_BGA1  I172

M_G_DQS_DN<13>   @BASEBOARD_FAB2_LIB.BASEBOARD_FAB2(SCH_1):M_G_DQS_DN<13>
  J1G1   100  DQS13N  SCONN288_H44441004_PIP  I66
  J9T1   100  DQS13N  SCONN288_H44441003_PIP  I120
  U2D1   A40  DDR0_DQS_DN<13>  SKX_EXT_B_BGA1  I172

M_G_DQS_DN<14>   @BASEBOARD_FAB2_LIB.BASEBOARD_FAB2(SCH_1):M_G_DQS_DN<14>
  J1G1   111  DQS14N  SCONN288_H44441004_PIP  I66
  J9T1   111  DQS14N  SCONN288_H44441003_PIP  I120
  U2D1   J36  DDR0_DQS_DN<14>  SKX_EXT_B_BGA1  I172

M_G_DQS_DN<15>   @BASEBOARD_FAB2_LIB.BASEBOARD_FAB2(SCH_1):M_G_DQS_DN<15>
  J1G1   122  DQS15N  SCONN288_H44441004_PIP  I66
  J9T1   122  DQS15N  SCONN288_H44441003_PIP  I120
  U2D1   J30  DDR0_DQS_DN<15>  SKX_EXT_B_BGA1  I172

M_G_DQS_DN<16>   @BASEBOARD_FAB2_LIB.BASEBOARD_FAB2(SCH_1):M_G_DQS_DN<16>
  J1G1   133  DQS16N  SCONN288_H44441004_PIP  I66
  J9T1   133  DQS16N  SCONN288_H44441003_PIP  I120
  U2D1   J24  DDR0_DQS_DN<16>  SKX_EXT_B_BGA1  I172

M_G_DQS_DN<17>   @BASEBOARD_FAB2_LIB.BASEBOARD_FAB2(SCH_1):M_G_DQS_DN<17>
  J1G1    52  DQS17N  SCONN288_H44441004_PIP  I66
  J9T1    52  DQS17N  SCONN288_H44441003_PIP  I120
  U2D1   AB67  DDR0_DQS_DN<17>  SKX_EXT_B_BGA1  I172

M_G_DQS_DP<0>   @BASEBOARD_FAB2_LIB.BASEBOARD_FAB2(SCH_1):M_G_DQS_DP<0>
  J1G1   153  DQS0P  SCONN288_H44441004_PIP  I66
  J9T1   153  DQS0P  SCONN288_H44441003_PIP  I120
  U2D1   AH85  DDR0_DQS_DP<0>  SKX_EXT_B_BGA1  I172

M_G_DQS_DP<1>   @BASEBOARD_FAB2_LIB.BASEBOARD_FAB2(SCH_1):M_G_DQS_DP<1>
  J1G1   164  DQS1P  SCONN288_H44441004_PIP  I66
  J9T1   164  DQS1P  SCONN288_H44441003_PIP  I120
  U2D1   P85  DDR0_DQS_DP<1>  SKX_EXT_B_BGA1  I172

M_G_DQS_DP<2>   @BASEBOARD_FAB2_LIB.BASEBOARD_FAB2(SCH_1):M_G_DQS_DP<2>
  J1G1   175  DQS2P  SCONN288_H44441004_PIP  I66
  J9T1   175  DQS2P  SCONN288_H44441003_PIP  I120
  U2D1   R80  DDR0_DQS_DP<2>  SKX_EXT_B_BGA1  I172

M_G_DQS_DP<3>   @BASEBOARD_FAB2_LIB.BASEBOARD_FAB2(SCH_1):M_G_DQS_DP<3>
  J1G1   186  DQS3P  SCONN288_H44441004_PIP  I66
  J9T1   186  DQS3P  SCONN288_H44441003_PIP  I120
  U2D1   P75  DDR0_DQS_DP<3>  SKX_EXT_B_BGA1  I172

M_G_DQS_DP<4>   @BASEBOARD_FAB2_LIB.BASEBOARD_FAB2(SCH_1):M_G_DQS_DP<4>
  J1G1   245  DQS4P  SCONN288_H44441004_PIP  I66
  J9T1   245  DQS4P  SCONN288_H44441003_PIP  I120
  U2D1   E40  DDR0_DQS_DP<4>  SKX_EXT_B_BGA1  I172

M_G_DQS_DP<5>   @BASEBOARD_FAB2_LIB.BASEBOARD_FAB2(SCH_1):M_G_DQS_DP<5>
  J1G1   256  DQS5P  SCONN288_H44441004_PIP  I66
  J9T1   256  DQS5P  SCONN288_H44441003_PIP  I120
  U2D1   N36  DDR0_DQS_DP<5>  SKX_EXT_B_BGA1  I172

M_G_DQS_DP<6>   @BASEBOARD_FAB2_LIB.BASEBOARD_FAB2(SCH_1):M_G_DQS_DP<6>
  J1G1   267  DQS6P  SCONN288_H44441004_PIP  I66
  J9T1   267  DQS6P  SCONN288_H44441003_PIP  I120
  U2D1   N30  DDR0_DQS_DP<6>  SKX_EXT_B_BGA1  I172

M_G_DQS_DP<7>   @BASEBOARD_FAB2_LIB.BASEBOARD_FAB2(SCH_1):M_G_DQS_DP<7>
  J1G1   278  DQS7P  SCONN288_H44441004_PIP  I66
  J9T1   278  DQS7P  SCONN288_H44441003_PIP  I120
  U2D1   R24  DDR0_DQS_DP<7>  SKX_EXT_B_BGA1  I172

M_G_DQS_DP<8>   @BASEBOARD_FAB2_LIB.BASEBOARD_FAB2(SCH_1):M_G_DQS_DP<8>
  J1G1   197  DQS8P  SCONN288_H44441004_PIP  I66
  J9T1   197  DQS8P  SCONN288_H44441003_PIP  I120
  U2D1   AF67  DDR0_DQS_DP<8>  SKX_EXT_B_BGA1  I172

M_G_DQS_DP<9>   @BASEBOARD_FAB2_LIB.BASEBOARD_FAB2(SCH_1):M_G_DQS_DP<9>
  J1G1     7  DQS9P  SCONN288_H44441004_PIP  I66
  J9T1     7  DQS9P  SCONN288_H44441003_PIP  I120
  U2D1   AM85  DDR0_DQS_DP<9>  SKX_EXT_B_BGA1  I172

M_G_DQS_DP<10>   @BASEBOARD_FAB2_LIB.BASEBOARD_FAB2(SCH_1):M_G_DQS_DP<10>
  J1G1    18  DQS10P  SCONN288_H44441004_PIP  I66
  J9T1    18  DQS10P  SCONN288_H44441003_PIP  I120
  U2D1   V85  DDR0_DQS_DP<10>  SKX_EXT_B_BGA1  I172

M_G_DQS_DP<11>   @BASEBOARD_FAB2_LIB.BASEBOARD_FAB2(SCH_1):M_G_DQS_DP<11>
  J1G1    29  DQS11P  SCONN288_H44441004_PIP  I66
  J9T1    29  DQS11P  SCONN288_H44441003_PIP  I120
  U2D1   T81  DDR0_DQS_DP<11>  SKX_EXT_B_BGA1  I172

M_G_DQS_DP<12>   @BASEBOARD_FAB2_LIB.BASEBOARD_FAB2(SCH_1):M_G_DQS_DP<12>
  J1G1    40  DQS12P  SCONN288_H44441004_PIP  I66
  J9T1    40  DQS12P  SCONN288_H44441003_PIP  I120
  U2D1   M75  DDR0_DQS_DP<12>  SKX_EXT_B_BGA1  I172

M_G_DQS_DP<13>   @BASEBOARD_FAB2_LIB.BASEBOARD_FAB2(SCH_1):M_G_DQS_DP<13>
  J1G1    99  DQS13P  SCONN288_H44441004_PIP  I66
  J9T1    99  DQS13P  SCONN288_H44441003_PIP  I120
  U2D1   C40  DDR0_DQS_DP<13>  SKX_EXT_B_BGA1  I172

M_G_DQS_DP<14>   @BASEBOARD_FAB2_LIB.BASEBOARD_FAB2(SCH_1):M_G_DQS_DP<14>
  J1G1   110  DQS14P  SCONN288_H44441004_PIP  I66
  J9T1   110  DQS14P  SCONN288_H44441003_PIP  I120
  U2D1   L36  DDR0_DQS_DP<14>  SKX_EXT_B_BGA1  I172

M_G_DQS_DP<15>   @BASEBOARD_FAB2_LIB.BASEBOARD_FAB2(SCH_1):M_G_DQS_DP<15>
  J1G1   121  DQS15P  SCONN288_H44441004_PIP  I66
  J9T1   121  DQS15P  SCONN288_H44441003_PIP  I120
  U2D1   L30  DDR0_DQS_DP<15>  SKX_EXT_B_BGA1  I172

M_G_DQS_DP<16>   @BASEBOARD_FAB2_LIB.BASEBOARD_FAB2(SCH_1):M_G_DQS_DP<16>
  J1G1   132  DQS16P  SCONN288_H44441004_PIP  I66
  J9T1   132  DQS16P  SCONN288_H44441003_PIP  I120
  U2D1   L24  DDR0_DQS_DP<16>  SKX_EXT_B_BGA1  I172

M_G_DQS_DP<17>   @BASEBOARD_FAB2_LIB.BASEBOARD_FAB2(SCH_1):M_G_DQS_DP<17>
  J1G1    51  DQS17P  SCONN288_H44441004_PIP  I66
  J9T1    51  DQS17P  SCONN288_H44441003_PIP  I120
  U2D1   AD67  DDR0_DQS_DP<17>  SKX_EXT_B_BGA1  I172

M_G_ECC<0>      @BASEBOARD_FAB2_LIB.BASEBOARD_FAB2(SCH_1):M_G_ECC<0>
  J1G1   194  CB<1>  SCONN288_H44441004_PIP  I111
  J9T1    49  CB<0>  SCONN288_H44441003_PIP  I13
  U2D1   AC68  DDR0_ECC<0>  SKX_EXT_B_BGA1  I172

M_G_ECC<1>      @BASEBOARD_FAB2_LIB.BASEBOARD_FAB2(SCH_1):M_G_ECC<1>
  J1G1    49  CB<0>  SCONN288_H44441004_PIP  I111
  J9T1   194  CB<1>  SCONN288_H44441003_PIP  I13
  U2D1   AG68  DDR0_ECC<1>  SKX_EXT_B_BGA1  I172

M_G_ECC<2>      @BASEBOARD_FAB2_LIB.BASEBOARD_FAB2(SCH_1):M_G_ECC<2>
  J1G1   201  CB<3>  SCONN288_H44441004_PIP  I111
  J9T1    56  CB<2>  SCONN288_H44441003_PIP  I13
  U2D1   AD65  DDR0_ECC<2>  SKX_EXT_B_BGA1  I172

M_G_ECC<3>      @BASEBOARD_FAB2_LIB.BASEBOARD_FAB2(SCH_1):M_G_ECC<3>
  J1G1    56  CB<2>  SCONN288_H44441004_PIP  I111
  J9T1   201  CB<3>  SCONN288_H44441003_PIP  I13
  U2D1   AF65  DDR0_ECC<3>  SKX_EXT_B_BGA1  I172

M_G_ECC<4>      @BASEBOARD_FAB2_LIB.BASEBOARD_FAB2(SCH_1):M_G_ECC<4>
  J1G1   192  CB<5>  SCONN288_H44441004_PIP  I111
  J9T1    47  CB<4>  SCONN288_H44441003_PIP  I13
  U2D1   AD69  DDR0_ECC<4>  SKX_EXT_B_BGA1  I172

M_G_ECC<5>      @BASEBOARD_FAB2_LIB.BASEBOARD_FAB2(SCH_1):M_G_ECC<5>
  J1G1    47  CB<4>  SCONN288_H44441004_PIP  I111
  J9T1   192  CB<5>  SCONN288_H44441003_PIP  I13
  U2D1   AF69  DDR0_ECC<5>  SKX_EXT_B_BGA1  I172

M_G_ECC<6>      @BASEBOARD_FAB2_LIB.BASEBOARD_FAB2(SCH_1):M_G_ECC<6>
  J1G1   199  CB<7>  SCONN288_H44441004_PIP  I111
  J9T1    54  CB<6>  SCONN288_H44441003_PIP  I13
  U2D1   AC66  DDR0_ECC<6>  SKX_EXT_B_BGA1  I172

M_G_ECC<7>      @BASEBOARD_FAB2_LIB.BASEBOARD_FAB2(SCH_1):M_G_ECC<7>
  J1G1    54  CB<6>  SCONN288_H44441004_PIP  I111
  J9T1   199  CB<7>  SCONN288_H44441003_PIP  I13
  U2D1   AG66  DDR0_ECC<7>  SKX_EXT_B_BGA1  I172

M_G_MA<0>       @BASEBOARD_FAB2_LIB.BASEBOARD_FAB2(SCH_1):M_G_MA<0>
  J1G1    79     A0  SCONN288_H44441004_PIP  I111
  J9T1    79     A0  SCONN288_H44441003_PIP  I13
  U2D1   F53  DDR0_MA<0>  SKX_EXT_B_BGA1  I172

M_G_MA<1>       @BASEBOARD_FAB2_LIB.BASEBOARD_FAB2(SCH_1):M_G_MA<1>
  J1G1    72     A1  SCONN288_H44441004_PIP  I111
  J9T1    72     A1  SCONN288_H44441003_PIP  I13
  U2D1   F57  DDR0_MA<1>  SKX_EXT_B_BGA1  I172

M_G_MA<2>       @BASEBOARD_FAB2_LIB.BASEBOARD_FAB2(SCH_1):M_G_MA<2>
  J1G1   216     A2  SCONN288_H44441004_PIP  I111
  J9T1   216     A2  SCONN288_H44441003_PIP  I13
  U2D1   D57  DDR0_MA<2>  SKX_EXT_B_BGA1  I172

M_G_MA<3>       @BASEBOARD_FAB2_LIB.BASEBOARD_FAB2(SCH_1):M_G_MA<3>
  J1G1    71     A3  SCONN288_H44441004_PIP  I111
  J9T1    71     A3  SCONN288_H44441003_PIP  I13
  U2D1   C58  DDR0_MA<3>  SKX_EXT_B_BGA1  I172

M_G_MA<4>       @BASEBOARD_FAB2_LIB.BASEBOARD_FAB2(SCH_1):M_G_MA<4>
  J1G1   214     A4  SCONN288_H44441004_PIP  I111
  J9T1   214     A4  SCONN288_H44441003_PIP  I13
  U2D1   G58  DDR0_MA<4>  SKX_EXT_B_BGA1  I172

M_G_MA<5>       @BASEBOARD_FAB2_LIB.BASEBOARD_FAB2(SCH_1):M_G_MA<5>
  J1G1   213     A5  SCONN288_H44441004_PIP  I111
  J9T1   213     A5  SCONN288_H44441003_PIP  I13
  U2D1   F59  DDR0_MA<5>  SKX_EXT_B_BGA1  I172

M_G_MA<6>       @BASEBOARD_FAB2_LIB.BASEBOARD_FAB2(SCH_1):M_G_MA<6>
  J1G1    69     A6  SCONN288_H44441004_PIP  I111
  J9T1    69     A6  SCONN288_H44441003_PIP  I13
  U2D1   D59  DDR0_MA<6>  SKX_EXT_B_BGA1  I172

M_G_MA<7>       @BASEBOARD_FAB2_LIB.BASEBOARD_FAB2(SCH_1):M_G_MA<7>
  J1G1   211     A7  SCONN288_H44441004_PIP  I111
  J9T1   211     A7  SCONN288_H44441003_PIP  I13
  U2D1   G60  DDR0_MA<7>  SKX_EXT_B_BGA1  I172

M_G_MA<8>       @BASEBOARD_FAB2_LIB.BASEBOARD_FAB2(SCH_1):M_G_MA<8>
  J1G1    68     A8  SCONN288_H44441004_PIP  I111
  J9T1    68     A8  SCONN288_H44441003_PIP  I13
  U2D1   C60  DDR0_MA<8>  SKX_EXT_B_BGA1  I172

M_G_MA<9>       @BASEBOARD_FAB2_LIB.BASEBOARD_FAB2(SCH_1):M_G_MA<9>
  J1G1    66     A9  SCONN288_H44441004_PIP  I111
  J9T1    66     A9  SCONN288_H44441003_PIP  I13
  U2D1   F61  DDR0_MA<9>  SKX_EXT_B_BGA1  I172

M_G_MA<10>      @BASEBOARD_FAB2_LIB.BASEBOARD_FAB2(SCH_1):M_G_MA<10>
  J1G1   225    A10  SCONN288_H44441004_PIP  I111
  J9T1   225    A10  SCONN288_H44441003_PIP  I13
  U2D1   J54  DDR0_MA<10>  SKX_EXT_B_BGA1  I172

M_G_MA<11>      @BASEBOARD_FAB2_LIB.BASEBOARD_FAB2(SCH_1):M_G_MA<11>
  J1G1   210    A11  SCONN288_H44441004_PIP  I111
  J9T1   210    A11  SCONN288_H44441003_PIP  I13
  U2D1   G62  DDR0_MA<11>  SKX_EXT_B_BGA1  I172

M_G_MA<12>      @BASEBOARD_FAB2_LIB.BASEBOARD_FAB2(SCH_1):M_G_MA<12>
  J1G1    65    A12  SCONN288_H44441004_PIP  I111
  J9T1    65    A12  SCONN288_H44441003_PIP  I13
  U2D1   J64  DDR0_MA<12>  SKX_EXT_B_BGA1  I172

M_G_MA<13>      @BASEBOARD_FAB2_LIB.BASEBOARD_FAB2(SCH_1):M_G_MA<13>
  J1G1   232    A13  SCONN288_H44441004_PIP  I111
  J9T1   232    A13  SCONN288_H44441003_PIP  I13
  U2D1   J48  DDR0_MA<13>  SKX_EXT_B_BGA1  I172

M_G_MA<14>      @BASEBOARD_FAB2_LIB.BASEBOARD_FAB2(SCH_1):M_G_MA<14>
  J1G1   228  A14_WE_N  SCONN288_H44441004_PIP  I111
  J9T1   228  A14_WE_N  SCONN288_H44441003_PIP  I13
  U2D1   F51  DDR0_MA<14>  SKX_EXT_B_BGA1  I172

M_G_MA<15>      @BASEBOARD_FAB2_LIB.BASEBOARD_FAB2(SCH_1):M_G_MA<15>
  J1G1    86  A15_CAS_N  SCONN288_H44441004_PIP  I111
  J9T1    86  A15_CAS_N  SCONN288_H44441003_PIP  I13
  U2D1   K49  DDR0_MA<15>  SKX_EXT_B_BGA1  I172

M_G_MA<16>      @BASEBOARD_FAB2_LIB.BASEBOARD_FAB2(SCH_1):M_G_MA<16>
  J1G1    82  A16_RAS_N  SCONN288_H44441004_PIP  I111
  J9T1    82  A16_RAS_N  SCONN288_H44441003_PIP  I13
  U2D1   D51  DDR0_MA<16>  SKX_EXT_B_BGA1  I172

M_G_MA<17>      @BASEBOARD_FAB2_LIB.BASEBOARD_FAB2(SCH_1):M_G_MA<17>
  J1G1   234    A17  SCONN288_H44441004_PIP  I111
  J9T1   234    A17  SCONN288_H44441003_PIP  I13
  U2D1   K47  DDR0_MA<17>  SKX_EXT_B_BGA1  I172

M_G_ODT<0>      @BASEBOARD_FAB2_LIB.BASEBOARD_FAB2(SCH_1):M_G_ODT<0>
  J1G1    87  ODT<0>  SCONN288_H44441004_PIP  I111
  U2D1   C50  DDR0_ODT<0>  SKX_EXT_B_BGA1  I172

M_G_ODT<1>      @BASEBOARD_FAB2_LIB.BASEBOARD_FAB2(SCH_1):M_G_ODT<1>
  J1G1    91  ODT<1>  SCONN288_H44441004_PIP  I111
  U2D1   C48  DDR0_ODT<1>  SKX_EXT_B_BGA1  I172

M_G_ODT<2>      @BASEBOARD_FAB2_LIB.BASEBOARD_FAB2(SCH_1):M_G_ODT<2>
  J9T1    87  ODT<0>  SCONN288_H44441003_PIP  I13
  U2D1   G50  DDR0_ODT<2>  SKX_EXT_B_BGA1  I172

M_G_ODT<3>      @BASEBOARD_FAB2_LIB.BASEBOARD_FAB2(SCH_1):M_G_ODT<3>
  J9T1    91  ODT<1>  SCONN288_H44441003_PIP  I13
  U2D1   G48  DDR0_ODT<3>  SKX_EXT_B_BGA1  I172

M_G_PAR         @BASEBOARD_FAB2_LIB.BASEBOARD_FAB2(SCH_1):M_G_PAR
  J1G1   222    PAR  SCONN288_H44441004_PIP  I111
  J9T1   222    PAR  SCONN288_H44441003_PIP  I13
  U2D1   D53  DDR0_PAR  SKX_EXT_B_BGA1  I172

M_G_VREF        @BASEBOARD_FAB2_LIB.BASEBOARD_FAB2(SCH_1):M_G_VREF
  C1F22    1      A  CAP_A       I181
  C9T7     1      A  CAP_A        I2
  J1G1   146  VREFCA  SCONN288_H44441004_PIP  I111
  J9T1   146  VREFCA  SCONN288_H44441003_PIP  I13
  R1F4     2      B  RES          I7
  R1F5     2      B  RES          I6
  R1F6     1      A  RES          I2

M_H_ACT_N       @BASEBOARD_FAB2_LIB.BASEBOARD_FAB2(SCH_1):M_H_ACT_N
  J1G2    62  ACT_N  SCONN288_H44441004_PIP  I111
  J9U1    62  ACT_N  SCONN288_H44441003_PIP  I24
  U2D1   T63  DDR1_ACT_N  SKX_EXT_B_BGA1  I172

M_H_ALERT_N     @BASEBOARD_FAB2_LIB.BASEBOARD_FAB2(SCH_1):M_H_ALERT_N
  J1G2   208  ALERT_N  SCONN288_H44441004_PIP  I111
  J9U1   208  ALERT_N  SCONN288_H44441003_PIP  I24
  U2D1   W62  DDR1_ALERT_N  SKX_EXT_B_BGA1  I172

M_H_BA<0>       @BASEBOARD_FAB2_LIB.BASEBOARD_FAB2(SCH_1):M_H_BA<0>
  J1G2    81  BA<0>  SCONN288_H44441004_PIP  I111
  J9U1    81  BA<0>  SCONN288_H44441003_PIP  I24
  U2D1   T53  DDR1_BA<0>  SKX_EXT_B_BGA1  I172

M_H_BA<1>       @BASEBOARD_FAB2_LIB.BASEBOARD_FAB2(SCH_1):M_H_BA<1>
  J1G2   224  BA<1>  SCONN288_H44441004_PIP  I111
  J9U1   224  BA<1>  SCONN288_H44441003_PIP  I24
  U2D1   K55  DDR1_BA<1>  SKX_EXT_B_BGA1  I172

M_H_BG<0>       @BASEBOARD_FAB2_LIB.BASEBOARD_FAB2(SCH_1):M_H_BG<0>
  J1G2    63  BG<0>  SCONN288_H44441004_PIP  I111
  J9U1    63  BG<0>  SCONN288_H44441003_PIP  I24
  U2D1   M61  DDR1_BG<0>  SKX_EXT_B_BGA1  I172

M_H_BG<1>       @BASEBOARD_FAB2_LIB.BASEBOARD_FAB2(SCH_1):M_H_BG<1>
  J1G2   207  BG<1>  SCONN288_H44441004_PIP  I111
  J9U1   207  BG<1>  SCONN288_H44441003_PIP  I24
  U2D1   N60  DDR1_BG<1>  SKX_EXT_B_BGA1  I172

M_H_C<2>        @BASEBOARD_FAB2_LIB.BASEBOARD_FAB2(SCH_1):M_H_C<2>
  J1G2   235   C<2>  SCONN288_H44441004_PIP  I111
  J9U1   235   C<2>  SCONN288_H44441003_PIP  I24
  U2D1   M47  DDR1_CID<2>  SKX_EXT_B_BGA1  I172

M_H_CKE<0>      @BASEBOARD_FAB2_LIB.BASEBOARD_FAB2(SCH_1):M_H_CKE<0>
  J1G2    60  CKE<0>  SCONN288_H44441004_PIP  I111
  U2D1   N62  DDR1_CKE<0>  SKX_EXT_B_BGA1  I172

M_H_CKE<1>      @BASEBOARD_FAB2_LIB.BASEBOARD_FAB2(SCH_1):M_H_CKE<1>
  J1G2   203  CKE<1>  SCONN288_H44441004_PIP  I111
  U2D1   R64  DDR1_CKE<1>  SKX_EXT_B_BGA1  I172

M_H_CKE<2>      @BASEBOARD_FAB2_LIB.BASEBOARD_FAB2(SCH_1):M_H_CKE<2>
  J9U1    60  CKE<0>  SCONN288_H44441003_PIP  I24
  U2D1   K63  DDR1_CKE<2>  SKX_EXT_B_BGA1  I172

M_H_CKE<3>      @BASEBOARD_FAB2_LIB.BASEBOARD_FAB2(SCH_1):M_H_CKE<3>
  J9U1   203  CKE<1>  SCONN288_H44441003_PIP  I24
  U2D1   L64  DDR1_CKE<3>  SKX_EXT_B_BGA1  I172

M_H_CLK_DN<0>   @BASEBOARD_FAB2_LIB.BASEBOARD_FAB2(SCH_1):M_H_CLK_DN<0>
  J1G2    75   CK0N  SCONN288_H44441004_PIP  I111
  U2D1   M53  DDR1_CLK_DN<0>  SKX_EXT_B_BGA1  I172

M_H_CLK_DN<1>   @BASEBOARD_FAB2_LIB.BASEBOARD_FAB2(SCH_1):M_H_CLK_DN<1>
  J1G2   219   CK1N  SCONN288_H44441004_PIP  I111
  U2D1   R54  DDR1_CLK_DN<1>  SKX_EXT_B_BGA1  I172

M_H_CLK_DN<2>   @BASEBOARD_FAB2_LIB.BASEBOARD_FAB2(SCH_1):M_H_CLK_DN<2>
  J9U1    75   CK0N  SCONN288_H44441003_PIP  I24
  U2D1   N56  DDR1_CLK_DN<2>  SKX_EXT_B_BGA1  I172

M_H_CLK_DN<3>   @BASEBOARD_FAB2_LIB.BASEBOARD_FAB2(SCH_1):M_H_CLK_DN<3>
  J9U1   219   CK1N  SCONN288_H44441003_PIP  I24
  U2D1   R56  DDR1_CLK_DN<3>  SKX_EXT_B_BGA1  I172

M_H_CLK_DP<0>   @BASEBOARD_FAB2_LIB.BASEBOARD_FAB2(SCH_1):M_H_CLK_DP<0>
  J1G2    74   CK0P  SCONN288_H44441004_PIP  I111
  U2D1   N54  DDR1_CLK_DP<0>  SKX_EXT_B_BGA1  I172

M_H_CLK_DP<1>   @BASEBOARD_FAB2_LIB.BASEBOARD_FAB2(SCH_1):M_H_CLK_DP<1>
  J1G2   218   CK1P  SCONN288_H44441004_PIP  I111
  U2D1   T55  DDR1_CLK_DP<1>  SKX_EXT_B_BGA1  I172

M_H_CLK_DP<2>   @BASEBOARD_FAB2_LIB.BASEBOARD_FAB2(SCH_1):M_H_CLK_DP<2>
  J9U1    74   CK0P  SCONN288_H44441003_PIP  I24
  U2D1   M57  DDR1_CLK_DP<2>  SKX_EXT_B_BGA1  I172

M_H_CLK_DP<3>   @BASEBOARD_FAB2_LIB.BASEBOARD_FAB2(SCH_1):M_H_CLK_DP<3>
  J9U1   218   CK1P  SCONN288_H44441003_PIP  I24
  U2D1   T57  DDR1_CLK_DP<3>  SKX_EXT_B_BGA1  I172

M_H_CPU_VREF    @BASEBOARD_FAB2_LIB.BASEBOARD_FAB2(SCH_1):M_H_CPU_VREF
  C1G8     1      A  CAP_A       I26
  R1G1     1      A  RES         I25
  U2D1   AK63  DDR1_CAVREF  SKX_EXT_B_BGA1  I172

M_H_CS_N<0>     @BASEBOARD_FAB2_LIB.BASEBOARD_FAB2(SCH_1):M_H_CS_N<0>
  J1G2    84   S0_N  SCONN288_H44441004_PIP  I111
  U2D1   K51  DDR1_CS_N<0>  SKX_EXT_B_BGA1  I172

M_H_CS_N<1>     @BASEBOARD_FAB2_LIB.BASEBOARD_FAB2(SCH_1):M_H_CS_N<1>
  J1G2    89   S1_N  SCONN288_H44441004_PIP  I111
  U2D1   R50  DDR1_CS_N<1>  SKX_EXT_B_BGA1  I172

M_H_CS_N<2>     @BASEBOARD_FAB2_LIB.BASEBOARD_FAB2(SCH_1):M_H_CS_N<2>
  J1G2    93  S2_N_C<0>  SCONN288_H44441004_PIP  I111
  U2D1   N46  DDR1_CS_N<2>  SKX_EXT_B_BGA1  I172

M_H_CS_N<3>     @BASEBOARD_FAB2_LIB.BASEBOARD_FAB2(SCH_1):M_H_CS_N<3>
  J1G2   237  S3_N_C<1>  SCONN288_H44441004_PIP  I111
  U2D1   V47  DDR1_CS_N<3>  SKX_EXT_B_BGA1  I172

M_H_CS_N<4>     @BASEBOARD_FAB2_LIB.BASEBOARD_FAB2(SCH_1):M_H_CS_N<4>
  J9U1    84   S0_N  SCONN288_H44441003_PIP  I24
  U2D1   J50  DDR1_CS_N<4>  SKX_EXT_B_BGA1  I172

M_H_CS_N<5>     @BASEBOARD_FAB2_LIB.BASEBOARD_FAB2(SCH_1):M_H_CS_N<5>
  J9U1    89   S1_N  SCONN288_H44441003_PIP  I24
  U2D1   T49  DDR1_CS_N<5>  SKX_EXT_B_BGA1  I172

M_H_CS_N<6>     @BASEBOARD_FAB2_LIB.BASEBOARD_FAB2(SCH_1):M_H_CS_N<6>
  J9U1    93  S2_N_C<0>  SCONN288_H44441003_PIP  I24
  U2D1   M45  DDR1_CS_N<6>  SKX_EXT_B_BGA1  I172

M_H_CS_N<7>     @BASEBOARD_FAB2_LIB.BASEBOARD_FAB2(SCH_1):M_H_CS_N<7>
  J9U1   237  S3_N_C<1>  SCONN288_H44441003_PIP  I24
  U2D1   R46  DDR1_CS_N<7>  SKX_EXT_B_BGA1  I172

M_H_DQ<0>       @BASEBOARD_FAB2_LIB.BASEBOARD_FAB2(SCH_1):M_H_DQ<0>
  J1G2   150  DQ<1>  SCONN288_H44441004_PIP  I111
  J9U1     5  DQ<0>  SCONN288_H44441003_PIP  I24
  U2D1   AV81  DDR1_DQ<0>  SKX_EXT_B_BGA1  I172

M_H_DQ<1>       @BASEBOARD_FAB2_LIB.BASEBOARD_FAB2(SCH_1):M_H_DQ<1>
  J1G2     5  DQ<0>  SCONN288_H44441004_PIP  I111
  J9U1   150  DQ<1>  SCONN288_H44441003_PIP  I24
  U2D1   AT79  DDR1_DQ<1>  SKX_EXT_B_BGA1  I172

M_H_DQ<2>       @BASEBOARD_FAB2_LIB.BASEBOARD_FAB2(SCH_1):M_H_DQ<2>
  J1G2   157  DQ<3>  SCONN288_H44441004_PIP  I111
  J9U1    12  DQ<2>  SCONN288_H44441003_PIP  I24
  U2D1   AN82  DDR1_DQ<2>  SKX_EXT_B_BGA1  I172

M_H_DQ<3>       @BASEBOARD_FAB2_LIB.BASEBOARD_FAB2(SCH_1):M_H_DQ<3>
  J1G2    12  DQ<2>  SCONN288_H44441004_PIP  I111
  J9U1   157  DQ<3>  SCONN288_H44441003_PIP  I24
  U2D1   AM81  DDR1_DQ<3>  SKX_EXT_B_BGA1  I172

M_H_DQ<4>       @BASEBOARD_FAB2_LIB.BASEBOARD_FAB2(SCH_1):M_H_DQ<4>
  J1G2   148  DQ<5>  SCONN288_H44441004_PIP  I111
  J9U1     3  DQ<4>  SCONN288_H44441003_PIP  I24
  U2D1   AW80  DDR1_DQ<4>  SKX_EXT_B_BGA1  I172

M_H_DQ<5>       @BASEBOARD_FAB2_LIB.BASEBOARD_FAB2(SCH_1):M_H_DQ<5>
  J1G2     3  DQ<4>  SCONN288_H44441004_PIP  I111
  J9U1   148  DQ<5>  SCONN288_H44441003_PIP  I24
  U2D1   AV79  DDR1_DQ<5>  SKX_EXT_B_BGA1  I172

M_H_DQ<6>       @BASEBOARD_FAB2_LIB.BASEBOARD_FAB2(SCH_1):M_H_DQ<6>
  J1G2   155  DQ<7>  SCONN288_H44441004_PIP  I111
  J9U1    10  DQ<6>  SCONN288_H44441003_PIP  I24
  U2D1   AR82  DDR1_DQ<6>  SKX_EXT_B_BGA1  I172

M_H_DQ<7>       @BASEBOARD_FAB2_LIB.BASEBOARD_FAB2(SCH_1):M_H_DQ<7>
  J1G2    10  DQ<6>  SCONN288_H44441004_PIP  I111
  J9U1   155  DQ<7>  SCONN288_H44441003_PIP  I24
  U2D1   AN80  DDR1_DQ<7>  SKX_EXT_B_BGA1  I172

M_H_DQ<8>       @BASEBOARD_FAB2_LIB.BASEBOARD_FAB2(SCH_1):M_H_DQ<8>
  J1G2   161  DQ<9>  SCONN288_H44441004_PIP  I111
  J9U1    16  DQ<8>  SCONN288_H44441003_PIP  I24
  U2D1   AH81  DDR1_DQ<8>  SKX_EXT_B_BGA1  I172

M_H_DQ<9>       @BASEBOARD_FAB2_LIB.BASEBOARD_FAB2(SCH_1):M_H_DQ<9>
  J1G2    16  DQ<8>  SCONN288_H44441004_PIP  I111
  J9U1   161  DQ<9>  SCONN288_H44441003_PIP  I24
  U2D1   AF79  DDR1_DQ<9>  SKX_EXT_B_BGA1  I172

M_H_DQ<10>      @BASEBOARD_FAB2_LIB.BASEBOARD_FAB2(SCH_1):M_H_DQ<10>
  J1G2   168  DQ<11>  SCONN288_H44441004_PIP  I111
  J9U1    23  DQ<10>  SCONN288_H44441003_PIP  I24
  U2D1   AC82  DDR1_DQ<10>  SKX_EXT_B_BGA1  I172

M_H_DQ<11>      @BASEBOARD_FAB2_LIB.BASEBOARD_FAB2(SCH_1):M_H_DQ<11>
  J1G2    23  DQ<10>  SCONN288_H44441004_PIP  I111
  J9U1   168  DQ<11>  SCONN288_H44441003_PIP  I24
  U2D1   AB81  DDR1_DQ<11>  SKX_EXT_B_BGA1  I172

M_H_DQ<12>      @BASEBOARD_FAB2_LIB.BASEBOARD_FAB2(SCH_1):M_H_DQ<12>
  J1G2   159  DQ<13>  SCONN288_H44441004_PIP  I111
  J9U1    14  DQ<12>  SCONN288_H44441003_PIP  I24
  U2D1   AJ80  DDR1_DQ<12>  SKX_EXT_B_BGA1  I172

M_H_DQ<13>      @BASEBOARD_FAB2_LIB.BASEBOARD_FAB2(SCH_1):M_H_DQ<13>
  J1G2    14  DQ<12>  SCONN288_H44441004_PIP  I111
  J9U1   159  DQ<13>  SCONN288_H44441003_PIP  I24
  U2D1   AH79  DDR1_DQ<13>  SKX_EXT_B_BGA1  I172

M_H_DQ<14>      @BASEBOARD_FAB2_LIB.BASEBOARD_FAB2(SCH_1):M_H_DQ<14>
  J1G2   166  DQ<15>  SCONN288_H44441004_PIP  I111
  J9U1    21  DQ<14>  SCONN288_H44441003_PIP  I24
  U2D1   AE82  DDR1_DQ<14>  SKX_EXT_B_BGA1  I172

M_H_DQ<15>      @BASEBOARD_FAB2_LIB.BASEBOARD_FAB2(SCH_1):M_H_DQ<15>
  J1G2    21  DQ<14>  SCONN288_H44441004_PIP  I111
  J9U1   166  DQ<15>  SCONN288_H44441003_PIP  I24
  U2D1   AC80  DDR1_DQ<15>  SKX_EXT_B_BGA1  I172

M_H_DQ<16>      @BASEBOARD_FAB2_LIB.BASEBOARD_FAB2(SCH_1):M_H_DQ<16>
  J1G2   172  DQ<17>  SCONN288_H44441004_PIP  I111
  J9U1    27  DQ<16>  SCONN288_H44441003_PIP  I24
  U2D1   E80  DDR1_DQ<16>  SKX_EXT_B_BGA1  I172

M_H_DQ<17>      @BASEBOARD_FAB2_LIB.BASEBOARD_FAB2(SCH_1):M_H_DQ<17>
  J1G2    27  DQ<16>  SCONN288_H44441004_PIP  I111
  J9U1   172  DQ<17>  SCONN288_H44441003_PIP  I24
  U2D1   J80  DDR1_DQ<17>  SKX_EXT_B_BGA1  I172

M_H_DQ<18>      @BASEBOARD_FAB2_LIB.BASEBOARD_FAB2(SCH_1):M_H_DQ<18>
  J1G2   179  DQ<19>  SCONN288_H44441004_PIP  I111
  J9U1    34  DQ<18>  SCONN288_H44441003_PIP  I24
  U2D1   F77  DDR1_DQ<18>  SKX_EXT_B_BGA1  I172

M_H_DQ<19>      @BASEBOARD_FAB2_LIB.BASEBOARD_FAB2(SCH_1):M_H_DQ<19>
  J1G2    34  DQ<18>  SCONN288_H44441004_PIP  I111
  J9U1   179  DQ<19>  SCONN288_H44441003_PIP  I24
  U2D1   H77  DDR1_DQ<19>  SKX_EXT_B_BGA1  I172

M_H_DQ<20>      @BASEBOARD_FAB2_LIB.BASEBOARD_FAB2(SCH_1):M_H_DQ<20>
  J1G2   170  DQ<21>  SCONN288_H44441004_PIP  I111
  J9U1    25  DQ<20>  SCONN288_H44441003_PIP  I24
  U2D1   F81  DDR1_DQ<20>  SKX_EXT_B_BGA1  I172

M_H_DQ<21>      @BASEBOARD_FAB2_LIB.BASEBOARD_FAB2(SCH_1):M_H_DQ<21>
  J1G2    25  DQ<20>  SCONN288_H44441004_PIP  I111
  J9U1   170  DQ<21>  SCONN288_H44441003_PIP  I24
  U2D1   H81  DDR1_DQ<21>  SKX_EXT_B_BGA1  I172

M_H_DQ<22>      @BASEBOARD_FAB2_LIB.BASEBOARD_FAB2(SCH_1):M_H_DQ<22>
  J1G2   177  DQ<23>  SCONN288_H44441004_PIP  I111
  J9U1    32  DQ<22>  SCONN288_H44441003_PIP  I24
  U2D1   E78  DDR1_DQ<22>  SKX_EXT_B_BGA1  I172

M_H_DQ<23>      @BASEBOARD_FAB2_LIB.BASEBOARD_FAB2(SCH_1):M_H_DQ<23>
  J1G2    32  DQ<22>  SCONN288_H44441004_PIP  I111
  J9U1   177  DQ<23>  SCONN288_H44441003_PIP  I24
  U2D1   J78  DDR1_DQ<23>  SKX_EXT_B_BGA1  I172

M_H_DQ<24>      @BASEBOARD_FAB2_LIB.BASEBOARD_FAB2(SCH_1):M_H_DQ<24>
  J1G2   183  DQ<25>  SCONN288_H44441004_PIP  I111
  J9U1    38  DQ<24>  SCONN288_H44441003_PIP  I24
  U2D1   D75  DDR1_DQ<24>  SKX_EXT_B_BGA1  I172

M_H_DQ<25>      @BASEBOARD_FAB2_LIB.BASEBOARD_FAB2(SCH_1):M_H_DQ<25>
  J1G2    38  DQ<24>  SCONN288_H44441004_PIP  I111
  J9U1   183  DQ<25>  SCONN288_H44441003_PIP  I24
  U2D1   C74  DDR1_DQ<25>  SKX_EXT_B_BGA1  I172

M_H_DQ<26>      @BASEBOARD_FAB2_LIB.BASEBOARD_FAB2(SCH_1):M_H_DQ<26>
  J1G2   190  DQ<27>  SCONN288_H44441004_PIP  I111
  J9U1    45  DQ<26>  SCONN288_H44441003_PIP  I24
  U2D1   D71  DDR1_DQ<26>  SKX_EXT_B_BGA1  I172

M_H_DQ<27>      @BASEBOARD_FAB2_LIB.BASEBOARD_FAB2(SCH_1):M_H_DQ<27>
  J1G2    45  DQ<26>  SCONN288_H44441004_PIP  I111
  J9U1   190  DQ<27>  SCONN288_H44441003_PIP  I24
  U2D1   F71  DDR1_DQ<27>  SKX_EXT_B_BGA1  I172

M_H_DQ<28>      @BASEBOARD_FAB2_LIB.BASEBOARD_FAB2(SCH_1):M_H_DQ<28>
  J1G2   181  DQ<29>  SCONN288_H44441004_PIP  I111
  J9U1    36  DQ<28>  SCONN288_H44441003_PIP  I24
  U2D1   F75  DDR1_DQ<28>  SKX_EXT_B_BGA1  I172

M_H_DQ<29>      @BASEBOARD_FAB2_LIB.BASEBOARD_FAB2(SCH_1):M_H_DQ<29>
  J1G2    36  DQ<28>  SCONN288_H44441004_PIP  I111
  J9U1   181  DQ<29>  SCONN288_H44441003_PIP  I24
  U2D1   G74  DDR1_DQ<29>  SKX_EXT_B_BGA1  I172

M_H_DQ<30>      @BASEBOARD_FAB2_LIB.BASEBOARD_FAB2(SCH_1):M_H_DQ<30>
  J1G2   188  DQ<31>  SCONN288_H44441004_PIP  I111
  J9U1    43  DQ<30>  SCONN288_H44441003_PIP  I24
  U2D1   C72  DDR1_DQ<30>  SKX_EXT_B_BGA1  I172

M_H_DQ<31>      @BASEBOARD_FAB2_LIB.BASEBOARD_FAB2(SCH_1):M_H_DQ<31>
  J1G2    43  DQ<30>  SCONN288_H44441004_PIP  I111
  J9U1   188  DQ<31>  SCONN288_H44441003_PIP  I24
  U2D1   G72  DDR1_DQ<31>  SKX_EXT_B_BGA1  I172

M_H_DQ<32>      @BASEBOARD_FAB2_LIB.BASEBOARD_FAB2(SCH_1):M_H_DQ<32>
  J1G2   242  DQ<33>  SCONN288_H44441004_PIP  I111
  J9U1    97  DQ<32>  SCONN288_H44441003_PIP  I24
  U2D1   K43  DDR1_DQ<32>  SKX_EXT_B_BGA1  I172

M_H_DQ<33>      @BASEBOARD_FAB2_LIB.BASEBOARD_FAB2(SCH_1):M_H_DQ<33>
  J1G2    97  DQ<32>  SCONN288_H44441004_PIP  I111
  J9U1   242  DQ<33>  SCONN288_H44441003_PIP  I24
  U2D1   H43  DDR1_DQ<33>  SKX_EXT_B_BGA1  I172

M_H_DQ<34>      @BASEBOARD_FAB2_LIB.BASEBOARD_FAB2(SCH_1):M_H_DQ<34>
  J1G2   249  DQ<35>  SCONN288_H44441004_PIP  I111
  J9U1   104  DQ<34>  SCONN288_H44441003_PIP  I24
  U2D1   L40  DDR1_DQ<34>  SKX_EXT_B_BGA1  I172

M_H_DQ<35>      @BASEBOARD_FAB2_LIB.BASEBOARD_FAB2(SCH_1):M_H_DQ<35>
  J1G2   104  DQ<34>  SCONN288_H44441004_PIP  I111
  J9U1   249  DQ<35>  SCONN288_H44441003_PIP  I24
  U2D1   N40  DDR1_DQ<35>  SKX_EXT_B_BGA1  I172

M_H_DQ<36>      @BASEBOARD_FAB2_LIB.BASEBOARD_FAB2(SCH_1):M_H_DQ<36>
  J1G2   240  DQ<37>  SCONN288_H44441004_PIP  I111
  J9U1    95  DQ<36>  SCONN288_H44441003_PIP  I24
  U2D1   P43  DDR1_DQ<36>  SKX_EXT_B_BGA1  I172

M_H_DQ<37>      @BASEBOARD_FAB2_LIB.BASEBOARD_FAB2(SCH_1):M_H_DQ<37>
  J1G2    95  DQ<36>  SCONN288_H44441004_PIP  I111
  J9U1   240  DQ<37>  SCONN288_H44441003_PIP  I24
  U2D1   T43  DDR1_DQ<37>  SKX_EXT_B_BGA1  I172

M_H_DQ<38>      @BASEBOARD_FAB2_LIB.BASEBOARD_FAB2(SCH_1):M_H_DQ<38>
  J1G2   247  DQ<39>  SCONN288_H44441004_PIP  I111
  J9U1   102  DQ<38>  SCONN288_H44441003_PIP  I24
  U2D1   K41  DDR1_DQ<38>  SKX_EXT_B_BGA1  I172

M_H_DQ<39>      @BASEBOARD_FAB2_LIB.BASEBOARD_FAB2(SCH_1):M_H_DQ<39>
  J1G2   102  DQ<38>  SCONN288_H44441004_PIP  I111
  J9U1   247  DQ<39>  SCONN288_H44441003_PIP  I24
  U2D1   P41  DDR1_DQ<39>  SKX_EXT_B_BGA1  I172

M_H_DQ<40>      @BASEBOARD_FAB2_LIB.BASEBOARD_FAB2(SCH_1):M_H_DQ<40>
  J1G2   253  DQ<41>  SCONN288_H44441004_PIP  I111
  J9U1   108  DQ<40>  SCONN288_H44441003_PIP  I24
  U2D1   C36  DDR1_DQ<40>  SKX_EXT_B_BGA1  I172

M_H_DQ<41>      @BASEBOARD_FAB2_LIB.BASEBOARD_FAB2(SCH_1):M_H_DQ<41>
  J1G2   108  DQ<40>  SCONN288_H44441004_PIP  I111
  J9U1   253  DQ<41>  SCONN288_H44441003_PIP  I24
  U2D1   B35  DDR1_DQ<41>  SKX_EXT_B_BGA1  I172

M_H_DQ<42>      @BASEBOARD_FAB2_LIB.BASEBOARD_FAB2(SCH_1):M_H_DQ<42>
  J1G2   260  DQ<43>  SCONN288_H44441004_PIP  I111
  J9U1   115  DQ<42>  SCONN288_H44441003_PIP  I24
  U2D1   C32  DDR1_DQ<42>  SKX_EXT_B_BGA1  I172

M_H_DQ<43>      @BASEBOARD_FAB2_LIB.BASEBOARD_FAB2(SCH_1):M_H_DQ<43>
  J1G2   115  DQ<42>  SCONN288_H44441004_PIP  I111
  J9U1   260  DQ<43>  SCONN288_H44441003_PIP  I24
  U2D1   E32  DDR1_DQ<43>  SKX_EXT_B_BGA1  I172

M_H_DQ<44>      @BASEBOARD_FAB2_LIB.BASEBOARD_FAB2(SCH_1):M_H_DQ<44>
  J1G2   251  DQ<45>  SCONN288_H44441004_PIP  I111
  J9U1   106  DQ<44>  SCONN288_H44441003_PIP  I24
  U2D1   E36  DDR1_DQ<44>  SKX_EXT_B_BGA1  I172

M_H_DQ<45>      @BASEBOARD_FAB2_LIB.BASEBOARD_FAB2(SCH_1):M_H_DQ<45>
  J1G2   106  DQ<44>  SCONN288_H44441004_PIP  I111
  J9U1   251  DQ<45>  SCONN288_H44441003_PIP  I24
  U2D1   F35  DDR1_DQ<45>  SKX_EXT_B_BGA1  I172

M_H_DQ<46>      @BASEBOARD_FAB2_LIB.BASEBOARD_FAB2(SCH_1):M_H_DQ<46>
  J1G2   258  DQ<47>  SCONN288_H44441004_PIP  I111
  J9U1   113  DQ<46>  SCONN288_H44441003_PIP  I24
  U2D1   B33  DDR1_DQ<46>  SKX_EXT_B_BGA1  I172

M_H_DQ<47>      @BASEBOARD_FAB2_LIB.BASEBOARD_FAB2(SCH_1):M_H_DQ<47>
  J1G2   113  DQ<46>  SCONN288_H44441004_PIP  I111
  J9U1   258  DQ<47>  SCONN288_H44441003_PIP  I24
  U2D1   F33  DDR1_DQ<47>  SKX_EXT_B_BGA1  I172

M_H_DQ<48>      @BASEBOARD_FAB2_LIB.BASEBOARD_FAB2(SCH_1):M_H_DQ<48>
  J1G2   264  DQ<49>  SCONN288_H44441004_PIP  I111
  J9U1   119  DQ<48>  SCONN288_H44441003_PIP  I24
  U2D1   C30  DDR1_DQ<48>  SKX_EXT_B_BGA1  I172

M_H_DQ<49>      @BASEBOARD_FAB2_LIB.BASEBOARD_FAB2(SCH_1):M_H_DQ<49>
  J1G2   119  DQ<48>  SCONN288_H44441004_PIP  I111
  J9U1   264  DQ<49>  SCONN288_H44441003_PIP  I24
  U2D1   B29  DDR1_DQ<49>  SKX_EXT_B_BGA1  I172

M_H_DQ<50>      @BASEBOARD_FAB2_LIB.BASEBOARD_FAB2(SCH_1):M_H_DQ<50>
  J1G2   271  DQ<51>  SCONN288_H44441004_PIP  I111
  J9U1   126  DQ<50>  SCONN288_H44441003_PIP  I24
  U2D1   C26  DDR1_DQ<50>  SKX_EXT_B_BGA1  I172

M_H_DQ<51>      @BASEBOARD_FAB2_LIB.BASEBOARD_FAB2(SCH_1):M_H_DQ<51>
  J1G2   126  DQ<50>  SCONN288_H44441004_PIP  I111
  J9U1   271  DQ<51>  SCONN288_H44441003_PIP  I24
  U2D1   E26  DDR1_DQ<51>  SKX_EXT_B_BGA1  I172

M_H_DQ<52>      @BASEBOARD_FAB2_LIB.BASEBOARD_FAB2(SCH_1):M_H_DQ<52>
  J1G2   262  DQ<53>  SCONN288_H44441004_PIP  I111
  J9U1   117  DQ<52>  SCONN288_H44441003_PIP  I24
  U2D1   E30  DDR1_DQ<52>  SKX_EXT_B_BGA1  I172

M_H_DQ<53>      @BASEBOARD_FAB2_LIB.BASEBOARD_FAB2(SCH_1):M_H_DQ<53>
  J1G2   117  DQ<52>  SCONN288_H44441004_PIP  I111
  J9U1   262  DQ<53>  SCONN288_H44441003_PIP  I24
  U2D1   F29  DDR1_DQ<53>  SKX_EXT_B_BGA1  I172

M_H_DQ<54>      @BASEBOARD_FAB2_LIB.BASEBOARD_FAB2(SCH_1):M_H_DQ<54>
  J1G2   269  DQ<55>  SCONN288_H44441004_PIP  I111
  J9U1   124  DQ<54>  SCONN288_H44441003_PIP  I24
  U2D1   B27  DDR1_DQ<54>  SKX_EXT_B_BGA1  I172

M_H_DQ<55>      @BASEBOARD_FAB2_LIB.BASEBOARD_FAB2(SCH_1):M_H_DQ<55>
  J1G2   124  DQ<54>  SCONN288_H44441004_PIP  I111
  J9U1   269  DQ<55>  SCONN288_H44441003_PIP  I24
  U2D1   F27  DDR1_DQ<55>  SKX_EXT_B_BGA1  I172

M_H_DQ<56>      @BASEBOARD_FAB2_LIB.BASEBOARD_FAB2(SCH_1):M_H_DQ<56>
  J1G2   275  DQ<57>  SCONN288_H44441004_PIP  I111
  J9U1   130  DQ<56>  SCONN288_H44441003_PIP  I24
  U2D1   U28  DDR1_DQ<56>  SKX_EXT_B_BGA1  I172

M_H_DQ<57>      @BASEBOARD_FAB2_LIB.BASEBOARD_FAB2(SCH_1):M_H_DQ<57>
  J1G2   130  DQ<56>  SCONN288_H44441004_PIP  I111
  J9U1   275  DQ<57>  SCONN288_H44441003_PIP  I24
  U2D1   AA28  DDR1_DQ<57>  SKX_EXT_B_BGA1  I172

M_H_DQ<58>      @BASEBOARD_FAB2_LIB.BASEBOARD_FAB2(SCH_1):M_H_DQ<58>
  J1G2   282  DQ<59>  SCONN288_H44441004_PIP  I111
  J9U1   137  DQ<58>  SCONN288_H44441003_PIP  I24
  U2D1   V25  DDR1_DQ<58>  SKX_EXT_B_BGA1  I172

M_H_DQ<59>      @BASEBOARD_FAB2_LIB.BASEBOARD_FAB2(SCH_1):M_H_DQ<59>
  J1G2   137  DQ<58>  SCONN288_H44441004_PIP  I111
  J9U1   282  DQ<59>  SCONN288_H44441003_PIP  I24
  U2D1   Y25  DDR1_DQ<59>  SKX_EXT_B_BGA1  I172

M_H_DQ<60>      @BASEBOARD_FAB2_LIB.BASEBOARD_FAB2(SCH_1):M_H_DQ<60>
  J1G2   273  DQ<61>  SCONN288_H44441004_PIP  I111
  J9U1   128  DQ<60>  SCONN288_H44441003_PIP  I24
  U2D1   V29  DDR1_DQ<60>  SKX_EXT_B_BGA1  I172

M_H_DQ<61>      @BASEBOARD_FAB2_LIB.BASEBOARD_FAB2(SCH_1):M_H_DQ<61>
  J1G2   128  DQ<60>  SCONN288_H44441004_PIP  I111
  J9U1   273  DQ<61>  SCONN288_H44441003_PIP  I24
  U2D1   Y29  DDR1_DQ<61>  SKX_EXT_B_BGA1  I172

M_H_DQ<62>      @BASEBOARD_FAB2_LIB.BASEBOARD_FAB2(SCH_1):M_H_DQ<62>
  J1G2   280  DQ<63>  SCONN288_H44441004_PIP  I111
  J9U1   135  DQ<62>  SCONN288_H44441003_PIP  I24
  U2D1   U26  DDR1_DQ<62>  SKX_EXT_B_BGA1  I172

M_H_DQ<63>      @BASEBOARD_FAB2_LIB.BASEBOARD_FAB2(SCH_1):M_H_DQ<63>
  J1G2   135  DQ<62>  SCONN288_H44441004_PIP  I111
  J9U1   280  DQ<63>  SCONN288_H44441003_PIP  I24
  U2D1   AA26  DDR1_DQ<63>  SKX_EXT_B_BGA1  I172

M_H_DQS_DN<0>   @BASEBOARD_FAB2_LIB.BASEBOARD_FAB2(SCH_1):M_H_DQS_DN<0>
  J1G2   152  DQS0N  SCONN288_H44441004_PIP  I64
  J9U1   152  DQS0N  SCONN288_H44441003_PIP  I101
  U2D1   AP79  DDR1_DQS_DN<0>  SKX_EXT_B_BGA1  I172

M_H_DQS_DN<1>   @BASEBOARD_FAB2_LIB.BASEBOARD_FAB2(SCH_1):M_H_DQS_DN<1>
  J1G2   163  DQS1N  SCONN288_H44441004_PIP  I64
  J9U1   163  DQS1N  SCONN288_H44441003_PIP  I101
  U2D1   AD79  DDR1_DQS_DN<1>  SKX_EXT_B_BGA1  I172

M_H_DQS_DN<2>   @BASEBOARD_FAB2_LIB.BASEBOARD_FAB2(SCH_1):M_H_DQS_DN<2>
  J1G2   174  DQS2N  SCONN288_H44441004_PIP  I64
  J9U1   174  DQS2N  SCONN288_H44441003_PIP  I101
  U2D1   K79  DDR1_DQS_DN<2>  SKX_EXT_B_BGA1  I172

M_H_DQS_DN<3>   @BASEBOARD_FAB2_LIB.BASEBOARD_FAB2(SCH_1):M_H_DQS_DN<3>
  J1G2   185  DQS3N  SCONN288_H44441004_PIP  I64
  J9U1   185  DQS3N  SCONN288_H44441003_PIP  I101
  U2D1   H73  DDR1_DQS_DN<3>  SKX_EXT_B_BGA1  I172

M_H_DQS_DN<4>   @BASEBOARD_FAB2_LIB.BASEBOARD_FAB2(SCH_1):M_H_DQS_DN<4>
  J1G2   244  DQS4N  SCONN288_H44441004_PIP  I64
  J9U1   244  DQS4N  SCONN288_H44441003_PIP  I101
  U2D1   N42  DDR1_DQS_DN<4>  SKX_EXT_B_BGA1  I172

M_H_DQS_DN<5>   @BASEBOARD_FAB2_LIB.BASEBOARD_FAB2(SCH_1):M_H_DQS_DN<5>
  J1G2   255  DQS5N  SCONN288_H44441004_PIP  I64
  J9U1   255  DQS5N  SCONN288_H44441003_PIP  I101
  U2D1   G34  DDR1_DQS_DN<5>  SKX_EXT_B_BGA1  I172

M_H_DQS_DN<6>   @BASEBOARD_FAB2_LIB.BASEBOARD_FAB2(SCH_1):M_H_DQS_DN<6>
  J1G2   266  DQS6N  SCONN288_H44441004_PIP  I64
  J9U1   266  DQS6N  SCONN288_H44441003_PIP  I101
  U2D1   G28  DDR1_DQS_DN<6>  SKX_EXT_B_BGA1  I172

M_H_DQS_DN<7>   @BASEBOARD_FAB2_LIB.BASEBOARD_FAB2(SCH_1):M_H_DQS_DN<7>
  J1G2   277  DQS7N  SCONN288_H44441004_PIP  I64
  J9U1   277  DQS7N  SCONN288_H44441003_PIP  I101
  U2D1   AB27  DDR1_DQS_DN<7>  SKX_EXT_B_BGA1  I172

M_H_DQS_DN<8>   @BASEBOARD_FAB2_LIB.BASEBOARD_FAB2(SCH_1):M_H_DQS_DN<8>
  J1G2   196  DQS8N  SCONN288_H44441004_PIP  I64
  J9U1   196  DQS8N  SCONN288_H44441003_PIP  I101
  U2D1   N68  DDR1_DQS_DN<8>  SKX_EXT_B_BGA1  I172

M_H_DQS_DN<9>   @BASEBOARD_FAB2_LIB.BASEBOARD_FAB2(SCH_1):M_H_DQS_DN<9>
  J1G2     8  DQS9N  SCONN288_H44441004_PIP  I64
  J9U1     8  DQS9N  SCONN288_H44441003_PIP  I101
  U2D1   AU82  DDR1_DQS_DN<9>  SKX_EXT_B_BGA1  I172

M_H_DQS_DN<10>   @BASEBOARD_FAB2_LIB.BASEBOARD_FAB2(SCH_1):M_H_DQS_DN<10>
  J1G2    19  DQS10N  SCONN288_H44441004_PIP  I64
  J9U1    19  DQS10N  SCONN288_H44441003_PIP  I101
  U2D1   AG82  DDR1_DQS_DN<10>  SKX_EXT_B_BGA1  I172

M_H_DQS_DN<11>   @BASEBOARD_FAB2_LIB.BASEBOARD_FAB2(SCH_1):M_H_DQS_DN<11>
  J1G2    30  DQS11N  SCONN288_H44441004_PIP  I64
  J9U1    30  DQS11N  SCONN288_H44441003_PIP  I101
  U2D1   D79  DDR1_DQS_DN<11>  SKX_EXT_B_BGA1  I172

M_H_DQS_DN<12>   @BASEBOARD_FAB2_LIB.BASEBOARD_FAB2(SCH_1):M_H_DQS_DN<12>
  J1G2    41  DQS12N  SCONN288_H44441004_PIP  I64
  J9U1    41  DQS12N  SCONN288_H44441003_PIP  I101
  U2D1   B73  DDR1_DQS_DN<12>  SKX_EXT_B_BGA1  I172

M_H_DQS_DN<13>   @BASEBOARD_FAB2_LIB.BASEBOARD_FAB2(SCH_1):M_H_DQS_DN<13>
  J1G2   100  DQS13N  SCONN288_H44441004_PIP  I64
  J9U1   100  DQS13N  SCONN288_H44441003_PIP  I101
  U2D1   J42  DDR1_DQS_DN<13>  SKX_EXT_B_BGA1  I172

M_H_DQS_DN<14>   @BASEBOARD_FAB2_LIB.BASEBOARD_FAB2(SCH_1):M_H_DQS_DN<14>
  J1G2   111  DQS14N  SCONN288_H44441004_PIP  I64
  J9U1   111  DQS14N  SCONN288_H44441003_PIP  I101
  U2D1   A34  DDR1_DQS_DN<14>  SKX_EXT_B_BGA1  I172

M_H_DQS_DN<15>   @BASEBOARD_FAB2_LIB.BASEBOARD_FAB2(SCH_1):M_H_DQS_DN<15>
  J1G2   122  DQS15N  SCONN288_H44441004_PIP  I64
  J9U1   122  DQS15N  SCONN288_H44441003_PIP  I101
  U2D1   A28  DDR1_DQS_DN<15>  SKX_EXT_B_BGA1  I172

M_H_DQS_DN<16>   @BASEBOARD_FAB2_LIB.BASEBOARD_FAB2(SCH_1):M_H_DQS_DN<16>
  J1G2   133  DQS16N  SCONN288_H44441004_PIP  I64
  J9U1   133  DQS16N  SCONN288_H44441003_PIP  I101
  U2D1   T27  DDR1_DQS_DN<16>  SKX_EXT_B_BGA1  I172

M_H_DQS_DN<17>   @BASEBOARD_FAB2_LIB.BASEBOARD_FAB2(SCH_1):M_H_DQS_DN<17>
  J1G2    52  DQS17N  SCONN288_H44441004_PIP  I64
  J9U1    52  DQS17N  SCONN288_H44441003_PIP  I101
  U2D1   G68  DDR1_DQS_DN<17>  SKX_EXT_B_BGA1  I172

M_H_DQS_DP<0>   @BASEBOARD_FAB2_LIB.BASEBOARD_FAB2(SCH_1):M_H_DQS_DP<0>
  J1G2   153  DQS0P  SCONN288_H44441004_PIP  I64
  J9U1   153  DQS0P  SCONN288_H44441003_PIP  I101
  U2D1   AR80  DDR1_DQS_DP<0>  SKX_EXT_B_BGA1  I172

M_H_DQS_DP<1>   @BASEBOARD_FAB2_LIB.BASEBOARD_FAB2(SCH_1):M_H_DQS_DP<1>
  J1G2   164  DQS1P  SCONN288_H44441004_PIP  I64
  J9U1   164  DQS1P  SCONN288_H44441003_PIP  I101
  U2D1   AE80  DDR1_DQS_DP<1>  SKX_EXT_B_BGA1  I172

M_H_DQS_DP<2>   @BASEBOARD_FAB2_LIB.BASEBOARD_FAB2(SCH_1):M_H_DQS_DP<2>
  J1G2   175  DQS2P  SCONN288_H44441004_PIP  I64
  J9U1   175  DQS2P  SCONN288_H44441003_PIP  I101
  U2D1   H79  DDR1_DQS_DP<2>  SKX_EXT_B_BGA1  I172

M_H_DQS_DP<3>   @BASEBOARD_FAB2_LIB.BASEBOARD_FAB2(SCH_1):M_H_DQS_DP<3>
  J1G2   186  DQS3P  SCONN288_H44441004_PIP  I64
  J9U1   186  DQS3P  SCONN288_H44441003_PIP  I101
  U2D1   F73  DDR1_DQS_DP<3>  SKX_EXT_B_BGA1  I172

M_H_DQS_DP<4>   @BASEBOARD_FAB2_LIB.BASEBOARD_FAB2(SCH_1):M_H_DQS_DP<4>
  J1G2   245  DQS4P  SCONN288_H44441004_PIP  I64
  J9U1   245  DQS4P  SCONN288_H44441003_PIP  I101
  U2D1   R42  DDR1_DQS_DP<4>  SKX_EXT_B_BGA1  I172

M_H_DQS_DP<5>   @BASEBOARD_FAB2_LIB.BASEBOARD_FAB2(SCH_1):M_H_DQS_DP<5>
  J1G2   256  DQS5P  SCONN288_H44441004_PIP  I64
  J9U1   256  DQS5P  SCONN288_H44441003_PIP  I101
  U2D1   E34  DDR1_DQS_DP<5>  SKX_EXT_B_BGA1  I172

M_H_DQS_DP<6>   @BASEBOARD_FAB2_LIB.BASEBOARD_FAB2(SCH_1):M_H_DQS_DP<6>
  J1G2   267  DQS6P  SCONN288_H44441004_PIP  I64
  J9U1   267  DQS6P  SCONN288_H44441003_PIP  I101
  U2D1   E28  DDR1_DQS_DP<6>  SKX_EXT_B_BGA1  I172

M_H_DQS_DP<7>   @BASEBOARD_FAB2_LIB.BASEBOARD_FAB2(SCH_1):M_H_DQS_DP<7>
  J1G2   278  DQS7P  SCONN288_H44441004_PIP  I64
  J9U1   278  DQS7P  SCONN288_H44441003_PIP  I101
  U2D1   Y27  DDR1_DQS_DP<7>  SKX_EXT_B_BGA1  I172

M_H_DQS_DP<8>   @BASEBOARD_FAB2_LIB.BASEBOARD_FAB2(SCH_1):M_H_DQS_DP<8>
  J1G2   197  DQS8P  SCONN288_H44441004_PIP  I64
  J9U1   197  DQS8P  SCONN288_H44441003_PIP  I101
  U2D1   L68  DDR1_DQS_DP<8>  SKX_EXT_B_BGA1  I172

M_H_DQS_DP<9>   @BASEBOARD_FAB2_LIB.BASEBOARD_FAB2(SCH_1):M_H_DQS_DP<9>
  J1G2     7  DQS9P  SCONN288_H44441004_PIP  I64
  J9U1     7  DQS9P  SCONN288_H44441003_PIP  I101
  U2D1   AT81  DDR1_DQS_DP<9>  SKX_EXT_B_BGA1  I172

M_H_DQS_DP<10>   @BASEBOARD_FAB2_LIB.BASEBOARD_FAB2(SCH_1):M_H_DQS_DP<10>
  J1G2    18  DQS10P  SCONN288_H44441004_PIP  I64
  J9U1    18  DQS10P  SCONN288_H44441003_PIP  I101
  U2D1   AF81  DDR1_DQS_DP<10>  SKX_EXT_B_BGA1  I172

M_H_DQS_DP<11>   @BASEBOARD_FAB2_LIB.BASEBOARD_FAB2(SCH_1):M_H_DQS_DP<11>
  J1G2    29  DQS11P  SCONN288_H44441004_PIP  I64
  J9U1    29  DQS11P  SCONN288_H44441003_PIP  I101
  U2D1   F79  DDR1_DQS_DP<11>  SKX_EXT_B_BGA1  I172

M_H_DQS_DP<12>   @BASEBOARD_FAB2_LIB.BASEBOARD_FAB2(SCH_1):M_H_DQS_DP<12>
  J1G2    40  DQS12P  SCONN288_H44441004_PIP  I64
  J9U1    40  DQS12P  SCONN288_H44441003_PIP  I101
  U2D1   D73  DDR1_DQS_DP<12>  SKX_EXT_B_BGA1  I172

M_H_DQS_DP<13>   @BASEBOARD_FAB2_LIB.BASEBOARD_FAB2(SCH_1):M_H_DQS_DP<13>
  J1G2    99  DQS13P  SCONN288_H44441004_PIP  I64
  J9U1    99  DQS13P  SCONN288_H44441003_PIP  I101
  U2D1   L42  DDR1_DQS_DP<13>  SKX_EXT_B_BGA1  I172

M_H_DQS_DP<14>   @BASEBOARD_FAB2_LIB.BASEBOARD_FAB2(SCH_1):M_H_DQS_DP<14>
  J1G2   110  DQS14P  SCONN288_H44441004_PIP  I64
  J9U1   110  DQS14P  SCONN288_H44441003_PIP  I101
  U2D1   C34  DDR1_DQS_DP<14>  SKX_EXT_B_BGA1  I172

M_H_DQS_DP<15>   @BASEBOARD_FAB2_LIB.BASEBOARD_FAB2(SCH_1):M_H_DQS_DP<15>
  J1G2   121  DQS15P  SCONN288_H44441004_PIP  I64
  J9U1   121  DQS15P  SCONN288_H44441003_PIP  I101
  U2D1   C28  DDR1_DQS_DP<15>  SKX_EXT_B_BGA1  I172

M_H_DQS_DP<16>   @BASEBOARD_FAB2_LIB.BASEBOARD_FAB2(SCH_1):M_H_DQS_DP<16>
  J1G2   132  DQS16P  SCONN288_H44441004_PIP  I64
  J9U1   132  DQS16P  SCONN288_H44441003_PIP  I101
  U2D1   V27  DDR1_DQS_DP<16>  SKX_EXT_B_BGA1  I172

M_H_DQS_DP<17>   @BASEBOARD_FAB2_LIB.BASEBOARD_FAB2(SCH_1):M_H_DQS_DP<17>
  J1G2    51  DQS17P  SCONN288_H44441004_PIP  I64
  J9U1    51  DQS17P  SCONN288_H44441003_PIP  I101
  U2D1   J68  DDR1_DQS_DP<17>  SKX_EXT_B_BGA1  I172

M_H_ECC<0>      @BASEBOARD_FAB2_LIB.BASEBOARD_FAB2(SCH_1):M_H_ECC<0>
  J1G2   194  CB<1>  SCONN288_H44441004_PIP  I111
  J9U1    49  CB<0>  SCONN288_H44441003_PIP  I24
  U2D1   J70  DDR1_ECC<0>  SKX_EXT_B_BGA1  I172

M_H_ECC<1>      @BASEBOARD_FAB2_LIB.BASEBOARD_FAB2(SCH_1):M_H_ECC<1>
  J1G2    49  CB<0>  SCONN288_H44441004_PIP  I111
  J9U1   194  CB<1>  SCONN288_H44441003_PIP  I24
  U2D1   H69  DDR1_ECC<1>  SKX_EXT_B_BGA1  I172

M_H_ECC<2>      @BASEBOARD_FAB2_LIB.BASEBOARD_FAB2(SCH_1):M_H_ECC<2>
  J1G2   201  CB<3>  SCONN288_H44441004_PIP  I111
  J9U1    56  CB<2>  SCONN288_H44441003_PIP  I24
  U2D1   J66  DDR1_ECC<2>  SKX_EXT_B_BGA1  I172

M_H_ECC<3>      @BASEBOARD_FAB2_LIB.BASEBOARD_FAB2(SCH_1):M_H_ECC<3>
  J1G2    56  CB<2>  SCONN288_H44441004_PIP  I111
  J9U1   201  CB<3>  SCONN288_H44441003_PIP  I24
  U2D1   L66  DDR1_ECC<3>  SKX_EXT_B_BGA1  I172

M_H_ECC<4>      @BASEBOARD_FAB2_LIB.BASEBOARD_FAB2(SCH_1):M_H_ECC<4>
  J1G2   192  CB<5>  SCONN288_H44441004_PIP  I111
  J9U1    47  CB<4>  SCONN288_H44441003_PIP  I24
  U2D1   L70  DDR1_ECC<4>  SKX_EXT_B_BGA1  I172

M_H_ECC<5>      @BASEBOARD_FAB2_LIB.BASEBOARD_FAB2(SCH_1):M_H_ECC<5>
  J1G2    47  CB<4>  SCONN288_H44441004_PIP  I111
  J9U1   192  CB<5>  SCONN288_H44441003_PIP  I24
  U2D1   M69  DDR1_ECC<5>  SKX_EXT_B_BGA1  I172

M_H_ECC<6>      @BASEBOARD_FAB2_LIB.BASEBOARD_FAB2(SCH_1):M_H_ECC<6>
  J1G2   199  CB<7>  SCONN288_H44441004_PIP  I111
  J9U1    54  CB<6>  SCONN288_H44441003_PIP  I24
  U2D1   H67  DDR1_ECC<6>  SKX_EXT_B_BGA1  I172

M_H_ECC<7>      @BASEBOARD_FAB2_LIB.BASEBOARD_FAB2(SCH_1):M_H_ECC<7>
  J1G2    54  CB<6>  SCONN288_H44441004_PIP  I111
  J9U1   199  CB<7>  SCONN288_H44441003_PIP  I24
  U2D1   M67  DDR1_ECC<7>  SKX_EXT_B_BGA1  I172

M_H_MA<0>       @BASEBOARD_FAB2_LIB.BASEBOARD_FAB2(SCH_1):M_H_MA<0>
  J1G2    79     A0  SCONN288_H44441004_PIP  I111
  J9U1    79     A0  SCONN288_H44441003_PIP  I24
  U2D1   J52  DDR1_MA<0>  SKX_EXT_B_BGA1  I172

M_H_MA<1>       @BASEBOARD_FAB2_LIB.BASEBOARD_FAB2(SCH_1):M_H_MA<1>
  J1G2    72     A1  SCONN288_H44441004_PIP  I111
  J9U1    72     A1  SCONN288_H44441003_PIP  I24
  U2D1   J58  DDR1_MA<1>  SKX_EXT_B_BGA1  I172

M_H_MA<2>       @BASEBOARD_FAB2_LIB.BASEBOARD_FAB2(SCH_1):M_H_MA<2>
  J1G2   216     A2  SCONN288_H44441004_PIP  I111
  J9U1   216     A2  SCONN288_H44441003_PIP  I24
  U2D1   K57  DDR1_MA<2>  SKX_EXT_B_BGA1  I172

M_H_MA<3>       @BASEBOARD_FAB2_LIB.BASEBOARD_FAB2(SCH_1):M_H_MA<3>
  J1G2    71     A3  SCONN288_H44441004_PIP  I111
  J9U1    71     A3  SCONN288_H44441003_PIP  I24
  U2D1   N58  DDR1_MA<3>  SKX_EXT_B_BGA1  I172

M_H_MA<4>       @BASEBOARD_FAB2_LIB.BASEBOARD_FAB2(SCH_1):M_H_MA<4>
  J1G2   214     A4  SCONN288_H44441004_PIP  I111
  J9U1   214     A4  SCONN288_H44441003_PIP  I24
  U2D1   M59  DDR1_MA<4>  SKX_EXT_B_BGA1  I172

M_H_MA<5>       @BASEBOARD_FAB2_LIB.BASEBOARD_FAB2(SCH_1):M_H_MA<5>
  J1G2   213     A5  SCONN288_H44441004_PIP  I111
  J9U1   213     A5  SCONN288_H44441003_PIP  I24
  U2D1   R58  DDR1_MA<5>  SKX_EXT_B_BGA1  I172

M_H_MA<6>       @BASEBOARD_FAB2_LIB.BASEBOARD_FAB2(SCH_1):M_H_MA<6>
  J1G2    69     A6  SCONN288_H44441004_PIP  I111
  J9U1    69     A6  SCONN288_H44441003_PIP  I24
  U2D1   T59  DDR1_MA<6>  SKX_EXT_B_BGA1  I172

M_H_MA<7>       @BASEBOARD_FAB2_LIB.BASEBOARD_FAB2(SCH_1):M_H_MA<7>
  J1G2   211     A7  SCONN288_H44441004_PIP  I111
  J9U1   211     A7  SCONN288_H44441003_PIP  I24
  U2D1   V61  DDR1_MA<7>  SKX_EXT_B_BGA1  I172

M_H_MA<8>       @BASEBOARD_FAB2_LIB.BASEBOARD_FAB2(SCH_1):M_H_MA<8>
  J1G2    68     A8  SCONN288_H44441004_PIP  I111
  J9U1    68     A8  SCONN288_H44441003_PIP  I24
  U2D1   W60  DDR1_MA<8>  SKX_EXT_B_BGA1  I172

M_H_MA<9>       @BASEBOARD_FAB2_LIB.BASEBOARD_FAB2(SCH_1):M_H_MA<9>
  J1G2    66     A9  SCONN288_H44441004_PIP  I111
  J9U1    66     A9  SCONN288_H44441003_PIP  I24
  U2D1   K59  DDR1_MA<9>  SKX_EXT_B_BGA1  I172

M_H_MA<10>      @BASEBOARD_FAB2_LIB.BASEBOARD_FAB2(SCH_1):M_H_MA<10>
  J1G2   225    A10  SCONN288_H44441004_PIP  I111
  J9U1   225    A10  SCONN288_H44441003_PIP  I24
  U2D1   M55  DDR1_MA<10>  SKX_EXT_B_BGA1  I172

M_H_MA<11>      @BASEBOARD_FAB2_LIB.BASEBOARD_FAB2(SCH_1):M_H_MA<11>
  J1G2   210    A11  SCONN288_H44441004_PIP  I111
  J9U1   210    A11  SCONN288_H44441003_PIP  I24
  U2D1   R60  DDR1_MA<11>  SKX_EXT_B_BGA1  I172

M_H_MA<12>      @BASEBOARD_FAB2_LIB.BASEBOARD_FAB2(SCH_1):M_H_MA<12>
  J1G2    65    A12  SCONN288_H44441004_PIP  I111
  J9U1    65    A12  SCONN288_H44441003_PIP  I24
  U2D1   T61  DDR1_MA<12>  SKX_EXT_B_BGA1  I172

M_H_MA<13>      @BASEBOARD_FAB2_LIB.BASEBOARD_FAB2(SCH_1):M_H_MA<13>
  J1G2   232    A13  SCONN288_H44441004_PIP  I111
  J9U1   232    A13  SCONN288_H44441003_PIP  I24
  U2D1   M51  DDR1_MA<13>  SKX_EXT_B_BGA1  I172

M_H_MA<14>      @BASEBOARD_FAB2_LIB.BASEBOARD_FAB2(SCH_1):M_H_MA<14>
  J1G2   228  A14_WE_N  SCONN288_H44441004_PIP  I111
  J9U1   228  A14_WE_N  SCONN288_H44441003_PIP  I24
  U2D1   T51  DDR1_MA<14>  SKX_EXT_B_BGA1  I172

M_H_MA<15>      @BASEBOARD_FAB2_LIB.BASEBOARD_FAB2(SCH_1):M_H_MA<15>
  J1G2    86  A15_CAS_N  SCONN288_H44441004_PIP  I111
  J9U1    86  A15_CAS_N  SCONN288_H44441003_PIP  I24
  U2D1   N52  DDR1_MA<15>  SKX_EXT_B_BGA1  I172

M_H_MA<16>      @BASEBOARD_FAB2_LIB.BASEBOARD_FAB2(SCH_1):M_H_MA<16>
  J1G2    82  A16_RAS_N  SCONN288_H44441004_PIP  I111
  J9U1    82  A16_RAS_N  SCONN288_H44441003_PIP  I24
  U2D1   R52  DDR1_MA<16>  SKX_EXT_B_BGA1  I172

M_H_MA<17>      @BASEBOARD_FAB2_LIB.BASEBOARD_FAB2(SCH_1):M_H_MA<17>
  J1G2   234    A17  SCONN288_H44441004_PIP  I111
  J9U1   234    A17  SCONN288_H44441003_PIP  I24
  U2D1   N48  DDR1_MA<17>  SKX_EXT_B_BGA1  I172

M_H_ODT<0>      @BASEBOARD_FAB2_LIB.BASEBOARD_FAB2(SCH_1):M_H_ODT<0>
  J1G2    87  ODT<0>  SCONN288_H44441004_PIP  I111
  U2D1   N50  DDR1_ODT<0>  SKX_EXT_B_BGA1  I172

M_H_ODT<1>      @BASEBOARD_FAB2_LIB.BASEBOARD_FAB2(SCH_1):M_H_ODT<1>
  J1G2    91  ODT<1>  SCONN288_H44441004_PIP  I111
  U2D1   R48  DDR1_ODT<1>  SKX_EXT_B_BGA1  I172

M_H_ODT<2>      @BASEBOARD_FAB2_LIB.BASEBOARD_FAB2(SCH_1):M_H_ODT<2>
  J9U1    87  ODT<0>  SCONN288_H44441003_PIP  I24
  U2D1   M49  DDR1_ODT<2>  SKX_EXT_B_BGA1  I172

M_H_ODT<3>      @BASEBOARD_FAB2_LIB.BASEBOARD_FAB2(SCH_1):M_H_ODT<3>
  J9U1    91  ODT<1>  SCONN288_H44441003_PIP  I24
  U2D1   T47  DDR1_ODT<3>  SKX_EXT_B_BGA1  I172

M_H_PAR         @BASEBOARD_FAB2_LIB.BASEBOARD_FAB2(SCH_1):M_H_PAR
  J1G2   222    PAR  SCONN288_H44441004_PIP  I111
  J9U1   222    PAR  SCONN288_H44441003_PIP  I24
  U2D1   K53  DDR1_PAR  SKX_EXT_B_BGA1  I172

M_H_VREF        @BASEBOARD_FAB2_LIB.BASEBOARD_FAB2(SCH_1):M_H_VREF
  C1G10    1      A  CAP_A        I3
  C9U7     1      A  CAP_A       I178
  J1G2   146  VREFCA  SCONN288_H44441004_PIP  I111
  J9U1   146  VREFCA  SCONN288_H44441003_PIP  I24
  R1G1     2      B  RES         I25
  R1G2     2      B  RES         I19
  R1G3     1      A  RES         I20

M_J_ACT_N       @BASEBOARD_FAB2_LIB.BASEBOARD_FAB2(SCH_1):M_J_ACT_N
  J1G3    62  ACT_N  SCONN288_H44441004_PIP  I186
  J9U2    62  ACT_N  SCONN288_H44441003_PIP  I187
  U2D1   AB61  DDR2_ACT_N  SKX_EXT_B_BGA1  I172

M_J_ALERT_N     @BASEBOARD_FAB2_LIB.BASEBOARD_FAB2(SCH_1):M_J_ALERT_N
  J1G3   208  ALERT_N  SCONN288_H44441004_PIP  I186
  J9U2   208  ALERT_N  SCONN288_H44441003_PIP  I187
  U2D1   AD61  DDR2_ALERT_N  SKX_EXT_B_BGA1  I172

M_J_BA<0>       @BASEBOARD_FAB2_LIB.BASEBOARD_FAB2(SCH_1):M_J_BA<0>
  J1G3    81  BA<0>  SCONN288_H44441004_PIP  I186
  J9U2    81  BA<0>  SCONN288_H44441003_PIP  I187
  U2D1   W52  DDR2_BA<0>  SKX_EXT_B_BGA1  I172

M_J_BA<1>       @BASEBOARD_FAB2_LIB.BASEBOARD_FAB2(SCH_1):M_J_BA<1>
  J1G3   224  BA<1>  SCONN288_H44441004_PIP  I186
  J9U2   224  BA<1>  SCONN288_H44441003_PIP  I187
  U2D1   AE56  DDR2_BA<1>  SKX_EXT_B_BGA1  I172

M_J_BG<0>       @BASEBOARD_FAB2_LIB.BASEBOARD_FAB2(SCH_1):M_J_BG<0>
  J1G3    63  BG<0>  SCONN288_H44441004_PIP  I186
  J9U2    63  BG<0>  SCONN288_H44441003_PIP  I187
  U2D1   AA60  DDR2_BG<0>  SKX_EXT_B_BGA1  I172

M_J_BG<1>       @BASEBOARD_FAB2_LIB.BASEBOARD_FAB2(SCH_1):M_J_BG<1>
  J1G3   207  BG<1>  SCONN288_H44441004_PIP  I186
  J9U2   207  BG<1>  SCONN288_H44441003_PIP  I187
  U2D1   AE62  DDR2_BG<1>  SKX_EXT_B_BGA1  I172

M_J_C<2>        @BASEBOARD_FAB2_LIB.BASEBOARD_FAB2(SCH_1):M_J_C<2>
  J1G3   235   C<2>  SCONN288_H44441004_PIP  I186
  J9U2   235   C<2>  SCONN288_H44441003_PIP  I187
  U2D1   AB45  DDR2_CID<2>  SKX_EXT_B_BGA1  I172

M_J_CKE<0>      @BASEBOARD_FAB2_LIB.BASEBOARD_FAB2(SCH_1):M_J_CKE<0>
  J1G3    60  CKE<0>  SCONN288_H44441004_PIP  I186
  U2D1   AA62  DDR2_CKE<0>  SKX_EXT_B_BGA1  I172

M_J_CKE<1>      @BASEBOARD_FAB2_LIB.BASEBOARD_FAB2(SCH_1):M_J_CKE<1>
  J1G3   203  CKE<1>  SCONN288_H44441004_PIP  I186
  U2D1   AD63  DDR2_CKE<1>  SKX_EXT_B_BGA1  I172

M_J_CKE<2>      @BASEBOARD_FAB2_LIB.BASEBOARD_FAB2(SCH_1):M_J_CKE<2>
  J9U2    60  CKE<0>  SCONN288_H44441003_PIP  I187
  U2D1   V63  DDR2_CKE<2>  SKX_EXT_B_BGA1  I172

M_J_CKE<3>      @BASEBOARD_FAB2_LIB.BASEBOARD_FAB2(SCH_1):M_J_CKE<3>
  J9U2   203  CKE<1>  SCONN288_H44441003_PIP  I187
  U2D1   AB63  DDR2_CKE<3>  SKX_EXT_B_BGA1  I172

M_J_CLK_DN<0>   @BASEBOARD_FAB2_LIB.BASEBOARD_FAB2(SCH_1):M_J_CLK_DN<0>
  J1G3    75   CK0N  SCONN288_H44441004_PIP  I186
  U2D1   AA54  DDR2_CLK_DN<0>  SKX_EXT_B_BGA1  I172

M_J_CLK_DN<1>   @BASEBOARD_FAB2_LIB.BASEBOARD_FAB2(SCH_1):M_J_CLK_DN<1>
  J1G3   219   CK1N  SCONN288_H44441004_PIP  I186
  U2D1   W54  DDR2_CLK_DN<1>  SKX_EXT_B_BGA1  I172

M_J_CLK_DN<2>   @BASEBOARD_FAB2_LIB.BASEBOARD_FAB2(SCH_1):M_J_CLK_DN<2>
  J9U2    75   CK0N  SCONN288_H44441003_PIP  I187
  U2D1   AA56  DDR2_CLK_DN<2>  SKX_EXT_B_BGA1  I172

M_J_CLK_DN<3>   @BASEBOARD_FAB2_LIB.BASEBOARD_FAB2(SCH_1):M_J_CLK_DN<3>
  J9U2   219   CK1N  SCONN288_H44441003_PIP  I187
  U2D1   W56  DDR2_CLK_DN<3>  SKX_EXT_B_BGA1  I172

M_J_CLK_DP<0>   @BASEBOARD_FAB2_LIB.BASEBOARD_FAB2(SCH_1):M_J_CLK_DP<0>
  J1G3    74   CK0P  SCONN288_H44441004_PIP  I186
  U2D1   AB55  DDR2_CLK_DP<0>  SKX_EXT_B_BGA1  I172

M_J_CLK_DP<1>   @BASEBOARD_FAB2_LIB.BASEBOARD_FAB2(SCH_1):M_J_CLK_DP<1>
  J1G3   218   CK1P  SCONN288_H44441004_PIP  I186
  U2D1   V55  DDR2_CLK_DP<1>  SKX_EXT_B_BGA1  I172

M_J_CLK_DP<2>   @BASEBOARD_FAB2_LIB.BASEBOARD_FAB2(SCH_1):M_J_CLK_DP<2>
  J9U2    74   CK0P  SCONN288_H44441003_PIP  I187
  U2D1   AB57  DDR2_CLK_DP<2>  SKX_EXT_B_BGA1  I172

M_J_CLK_DP<3>   @BASEBOARD_FAB2_LIB.BASEBOARD_FAB2(SCH_1):M_J_CLK_DP<3>
  J9U2   218   CK1P  SCONN288_H44441003_PIP  I187
  U2D1   V57  DDR2_CLK_DP<3>  SKX_EXT_B_BGA1  I172

M_J_CPU_VREF    @BASEBOARD_FAB2_LIB.BASEBOARD_FAB2(SCH_1):M_J_CPU_VREF
  C1G18    1      A  CAP_A       I42
  R1G14    1      A  RES         I41
  U2D1   AH63  DDR2_CAVREF  SKX_EXT_B_BGA1  I172

M_J_CS_N<0>     @BASEBOARD_FAB2_LIB.BASEBOARD_FAB2(SCH_1):M_J_CS_N<0>
  J1G3    84   S0_N  SCONN288_H44441004_PIP  I186
  U2D1   V51  DDR2_CS_N<0>  SKX_EXT_B_BGA1  I172

M_J_CS_N<1>     @BASEBOARD_FAB2_LIB.BASEBOARD_FAB2(SCH_1):M_J_CS_N<1>
  J1G3    89   S1_N  SCONN288_H44441004_PIP  I186
  U2D1   AB49  DDR2_CS_N<1>  SKX_EXT_B_BGA1  I172

M_J_CS_N<2>     @BASEBOARD_FAB2_LIB.BASEBOARD_FAB2(SCH_1):M_J_CS_N<2>
  J1G3    93  S2_N_C<0>  SCONN288_H44441004_PIP  I186
  U2D1   W46  DDR2_CS_N<2>  SKX_EXT_B_BGA1  I172

M_J_CS_N<3>     @BASEBOARD_FAB2_LIB.BASEBOARD_FAB2(SCH_1):M_J_CS_N<3>
  J1G3   237  S3_N_C<1>  SCONN288_H44441004_PIP  I186
  U2D1   AA46  DDR2_CS_N<3>  SKX_EXT_B_BGA1  I172

M_J_CS_N<4>     @BASEBOARD_FAB2_LIB.BASEBOARD_FAB2(SCH_1):M_J_CS_N<4>
  J9U2    84   S0_N  SCONN288_H44441003_PIP  I187
  U2D1   AB51  DDR2_CS_N<4>  SKX_EXT_B_BGA1  I172

M_J_CS_N<5>     @BASEBOARD_FAB2_LIB.BASEBOARD_FAB2(SCH_1):M_J_CS_N<5>
  J9U2    89   S1_N  SCONN288_H44441003_PIP  I187
  U2D1   W48  DDR2_CS_N<5>  SKX_EXT_B_BGA1  I172

M_J_CS_N<6>     @BASEBOARD_FAB2_LIB.BASEBOARD_FAB2(SCH_1):M_J_CS_N<6>
  J9U2    93  S2_N_C<0>  SCONN288_H44441003_PIP  I187
  U2D1   T45  DDR2_CS_N<6>  SKX_EXT_B_BGA1  I172

M_J_CS_N<7>     @BASEBOARD_FAB2_LIB.BASEBOARD_FAB2(SCH_1):M_J_CS_N<7>
  J9U2   237  S3_N_C<1>  SCONN288_H44441003_PIP  I187
  U2D1   V45  DDR2_CS_N<7>  SKX_EXT_B_BGA1  I172

M_J_DQ<0>       @BASEBOARD_FAB2_LIB.BASEBOARD_FAB2(SCH_1):M_J_DQ<0>
  J1G3   150  DQ<1>  SCONN288_H44441004_PIP  I186
  J9U2     5  DQ<0>  SCONN288_H44441003_PIP  I187
  U2D1   AR76  DDR2_DQ<0>  SKX_EXT_B_BGA1  I172

M_J_DQ<1>       @BASEBOARD_FAB2_LIB.BASEBOARD_FAB2(SCH_1):M_J_DQ<1>
  J1G3     5  DQ<0>  SCONN288_H44441004_PIP  I186
  J9U2   150  DQ<1>  SCONN288_H44441003_PIP  I187
  U2D1   AN74  DDR2_DQ<1>  SKX_EXT_B_BGA1  I172

M_J_DQ<2>       @BASEBOARD_FAB2_LIB.BASEBOARD_FAB2(SCH_1):M_J_DQ<2>
  J1G3   157  DQ<3>  SCONN288_H44441004_PIP  I186
  J9U2    12  DQ<2>  SCONN288_H44441003_PIP  I187
  U2D1   AK77  DDR2_DQ<2>  SKX_EXT_B_BGA1  I172

M_J_DQ<3>       @BASEBOARD_FAB2_LIB.BASEBOARD_FAB2(SCH_1):M_J_DQ<3>
  J1G3    12  DQ<2>  SCONN288_H44441004_PIP  I186
  J9U2   157  DQ<3>  SCONN288_H44441003_PIP  I187
  U2D1   AJ76  DDR2_DQ<3>  SKX_EXT_B_BGA1  I172

M_J_DQ<4>       @BASEBOARD_FAB2_LIB.BASEBOARD_FAB2(SCH_1):M_J_DQ<4>
  J1G3   148  DQ<5>  SCONN288_H44441004_PIP  I186
  J9U2     3  DQ<4>  SCONN288_H44441003_PIP  I187
  U2D1   AT75  DDR2_DQ<4>  SKX_EXT_B_BGA1  I172

M_J_DQ<5>       @BASEBOARD_FAB2_LIB.BASEBOARD_FAB2(SCH_1):M_J_DQ<5>
  J1G3     3  DQ<4>  SCONN288_H44441004_PIP  I186
  J9U2   148  DQ<5>  SCONN288_H44441003_PIP  I187
  U2D1   AR74  DDR2_DQ<5>  SKX_EXT_B_BGA1  I172

M_J_DQ<6>       @BASEBOARD_FAB2_LIB.BASEBOARD_FAB2(SCH_1):M_J_DQ<6>
  J1G3   155  DQ<7>  SCONN288_H44441004_PIP  I186
  J9U2    10  DQ<6>  SCONN288_H44441003_PIP  I187
  U2D1   AM77  DDR2_DQ<6>  SKX_EXT_B_BGA1  I172

M_J_DQ<7>       @BASEBOARD_FAB2_LIB.BASEBOARD_FAB2(SCH_1):M_J_DQ<7>
  J1G3    10  DQ<6>  SCONN288_H44441004_PIP  I186
  J9U2   155  DQ<7>  SCONN288_H44441003_PIP  I187
  U2D1   AK75  DDR2_DQ<7>  SKX_EXT_B_BGA1  I172

M_J_DQ<8>       @BASEBOARD_FAB2_LIB.BASEBOARD_FAB2(SCH_1):M_J_DQ<8>
  J1G3   161  DQ<9>  SCONN288_H44441004_PIP  I186
  J9U2    16  DQ<8>  SCONN288_H44441003_PIP  I187
  U2D1   AE76  DDR2_DQ<8>  SKX_EXT_B_BGA1  I172

M_J_DQ<9>       @BASEBOARD_FAB2_LIB.BASEBOARD_FAB2(SCH_1):M_J_DQ<9>
  J1G3    16  DQ<8>  SCONN288_H44441004_PIP  I186
  J9U2   161  DQ<9>  SCONN288_H44441003_PIP  I187
  U2D1   AC74  DDR2_DQ<9>  SKX_EXT_B_BGA1  I172

M_J_DQ<10>      @BASEBOARD_FAB2_LIB.BASEBOARD_FAB2(SCH_1):M_J_DQ<10>
  J1G3   168  DQ<11>  SCONN288_H44441004_PIP  I186
  J9U2    23  DQ<10>  SCONN288_H44441003_PIP  I187
  U2D1   Y77  DDR2_DQ<10>  SKX_EXT_B_BGA1  I172

M_J_DQ<11>      @BASEBOARD_FAB2_LIB.BASEBOARD_FAB2(SCH_1):M_J_DQ<11>
  J1G3    23  DQ<10>  SCONN288_H44441004_PIP  I186
  J9U2   168  DQ<11>  SCONN288_H44441003_PIP  I187
  U2D1   W76  DDR2_DQ<11>  SKX_EXT_B_BGA1  I172

M_J_DQ<12>      @BASEBOARD_FAB2_LIB.BASEBOARD_FAB2(SCH_1):M_J_DQ<12>
  J1G3   159  DQ<13>  SCONN288_H44441004_PIP  I186
  J9U2    14  DQ<12>  SCONN288_H44441003_PIP  I187
  U2D1   AF75  DDR2_DQ<12>  SKX_EXT_B_BGA1  I172

M_J_DQ<13>      @BASEBOARD_FAB2_LIB.BASEBOARD_FAB2(SCH_1):M_J_DQ<13>
  J1G3    14  DQ<12>  SCONN288_H44441004_PIP  I186
  J9U2   159  DQ<13>  SCONN288_H44441003_PIP  I187
  U2D1   AE74  DDR2_DQ<13>  SKX_EXT_B_BGA1  I172

M_J_DQ<14>      @BASEBOARD_FAB2_LIB.BASEBOARD_FAB2(SCH_1):M_J_DQ<14>
  J1G3   166  DQ<15>  SCONN288_H44441004_PIP  I186
  J9U2    21  DQ<14>  SCONN288_H44441003_PIP  I187
  U2D1   AB77  DDR2_DQ<14>  SKX_EXT_B_BGA1  I172

M_J_DQ<15>      @BASEBOARD_FAB2_LIB.BASEBOARD_FAB2(SCH_1):M_J_DQ<15>
  J1G3    21  DQ<14>  SCONN288_H44441004_PIP  I186
  J9U2   166  DQ<15>  SCONN288_H44441003_PIP  I187
  U2D1   Y75  DDR2_DQ<15>  SKX_EXT_B_BGA1  I172

M_J_DQ<16>      @BASEBOARD_FAB2_LIB.BASEBOARD_FAB2(SCH_1):M_J_DQ<16>
  J1G3   172  DQ<17>  SCONN288_H44441004_PIP  I186
  J9U2    27  DQ<16>  SCONN288_H44441003_PIP  I187
  U2D1   W72  DDR2_DQ<16>  SKX_EXT_B_BGA1  I172

M_J_DQ<17>      @BASEBOARD_FAB2_LIB.BASEBOARD_FAB2(SCH_1):M_J_DQ<17>
  J1G3    27  DQ<16>  SCONN288_H44441004_PIP  I186
  J9U2   172  DQ<17>  SCONN288_H44441003_PIP  I187
  U2D1   AA70  DDR2_DQ<17>  SKX_EXT_B_BGA1  I172

M_J_DQ<18>      @BASEBOARD_FAB2_LIB.BASEBOARD_FAB2(SCH_1):M_J_DQ<18>
  J1G3   179  DQ<19>  SCONN288_H44441004_PIP  I186
  J9U2    34  DQ<18>  SCONN288_H44441003_PIP  I187
  U2D1   R70  DDR2_DQ<18>  SKX_EXT_B_BGA1  I172

M_J_DQ<19>      @BASEBOARD_FAB2_LIB.BASEBOARD_FAB2(SCH_1):M_J_DQ<19>
  J1G3    34  DQ<18>  SCONN288_H44441004_PIP  I186
  J9U2   179  DQ<19>  SCONN288_H44441003_PIP  I187
  U2D1   T69  DDR2_DQ<19>  SKX_EXT_B_BGA1  I172

M_J_DQ<20>      @BASEBOARD_FAB2_LIB.BASEBOARD_FAB2(SCH_1):M_J_DQ<20>
  J1G3   170  DQ<21>  SCONN288_H44441004_PIP  I186
  J9U2    25  DQ<20>  SCONN288_H44441003_PIP  I187
  U2D1   AA72  DDR2_DQ<20>  SKX_EXT_B_BGA1  I172

M_J_DQ<21>      @BASEBOARD_FAB2_LIB.BASEBOARD_FAB2(SCH_1):M_J_DQ<21>
  J1G3    25  DQ<20>  SCONN288_H44441004_PIP  I186
  J9U2   170  DQ<21>  SCONN288_H44441003_PIP  I187
  U2D1   AB71  DDR2_DQ<21>  SKX_EXT_B_BGA1  I172

M_J_DQ<22>      @BASEBOARD_FAB2_LIB.BASEBOARD_FAB2(SCH_1):M_J_DQ<22>
  J1G3   177  DQ<23>  SCONN288_H44441004_PIP  I186
  J9U2    32  DQ<22>  SCONN288_H44441003_PIP  I187
  U2D1   T71  DDR2_DQ<22>  SKX_EXT_B_BGA1  I172

M_J_DQ<23>      @BASEBOARD_FAB2_LIB.BASEBOARD_FAB2(SCH_1):M_J_DQ<23>
  J1G3    32  DQ<22>  SCONN288_H44441004_PIP  I186
  J9U2   177  DQ<23>  SCONN288_H44441003_PIP  I187
  U2D1   V69  DDR2_DQ<23>  SKX_EXT_B_BGA1  I172

M_J_DQ<24>      @BASEBOARD_FAB2_LIB.BASEBOARD_FAB2(SCH_1):M_J_DQ<24>
  J1G3   183  DQ<25>  SCONN288_H44441004_PIP  I186
  J9U2    38  DQ<24>  SCONN288_H44441003_PIP  I187
  U2D1   AM67  DDR2_DQ<24>  SKX_EXT_B_BGA1  I172

M_J_DQ<25>      @BASEBOARD_FAB2_LIB.BASEBOARD_FAB2(SCH_1):M_J_DQ<25>
  J1G3    38  DQ<24>  SCONN288_H44441004_PIP  I186
  J9U2   183  DQ<25>  SCONN288_H44441003_PIP  I187
  U2D1   AT67  DDR2_DQ<25>  SKX_EXT_B_BGA1  I172

M_J_DQ<26>      @BASEBOARD_FAB2_LIB.BASEBOARD_FAB2(SCH_1):M_J_DQ<26>
  J1G3   190  DQ<27>  SCONN288_H44441004_PIP  I186
  J9U2    45  DQ<26>  SCONN288_H44441003_PIP  I187
  U2D1   AN64  DDR2_DQ<26>  SKX_EXT_B_BGA1  I172

M_J_DQ<27>      @BASEBOARD_FAB2_LIB.BASEBOARD_FAB2(SCH_1):M_J_DQ<27>
  J1G3    45  DQ<26>  SCONN288_H44441004_PIP  I186
  J9U2   190  DQ<27>  SCONN288_H44441003_PIP  I187
  U2D1   AR64  DDR2_DQ<27>  SKX_EXT_B_BGA1  I172

M_J_DQ<28>      @BASEBOARD_FAB2_LIB.BASEBOARD_FAB2(SCH_1):M_J_DQ<28>
  J1G3   181  DQ<29>  SCONN288_H44441004_PIP  I186
  J9U2    36  DQ<28>  SCONN288_H44441003_PIP  I187
  U2D1   AN68  DDR2_DQ<28>  SKX_EXT_B_BGA1  I172

M_J_DQ<29>      @BASEBOARD_FAB2_LIB.BASEBOARD_FAB2(SCH_1):M_J_DQ<29>
  J1G3    36  DQ<28>  SCONN288_H44441004_PIP  I186
  J9U2   181  DQ<29>  SCONN288_H44441003_PIP  I187
  U2D1   AR68  DDR2_DQ<29>  SKX_EXT_B_BGA1  I172

M_J_DQ<30>      @BASEBOARD_FAB2_LIB.BASEBOARD_FAB2(SCH_1):M_J_DQ<30>
  J1G3   188  DQ<31>  SCONN288_H44441004_PIP  I186
  J9U2    43  DQ<30>  SCONN288_H44441003_PIP  I187
  U2D1   AM65  DDR2_DQ<30>  SKX_EXT_B_BGA1  I172

M_J_DQ<31>      @BASEBOARD_FAB2_LIB.BASEBOARD_FAB2(SCH_1):M_J_DQ<31>
  J1G3    43  DQ<30>  SCONN288_H44441004_PIP  I186
  J9U2   188  DQ<31>  SCONN288_H44441003_PIP  I187
  U2D1   AT65  DDR2_DQ<31>  SKX_EXT_B_BGA1  I172

M_J_DQ<32>      @BASEBOARD_FAB2_LIB.BASEBOARD_FAB2(SCH_1):M_J_DQ<32>
  J1G3   242  DQ<33>  SCONN288_H44441004_PIP  I186
  J9U2    97  DQ<32>  SCONN288_H44441003_PIP  I187
  U2D1   U40  DDR2_DQ<32>  SKX_EXT_B_BGA1  I172

M_J_DQ<33>      @BASEBOARD_FAB2_LIB.BASEBOARD_FAB2(SCH_1):M_J_DQ<33>
  J1G3    97  DQ<32>  SCONN288_H44441004_PIP  I186
  J9U2   242  DQ<33>  SCONN288_H44441003_PIP  I187
  U2D1   AA40  DDR2_DQ<33>  SKX_EXT_B_BGA1  I172

M_J_DQ<34>      @BASEBOARD_FAB2_LIB.BASEBOARD_FAB2(SCH_1):M_J_DQ<34>
  J1G3   249  DQ<35>  SCONN288_H44441004_PIP  I186
  J9U2   104  DQ<34>  SCONN288_H44441003_PIP  I187
  U2D1   V37  DDR2_DQ<34>  SKX_EXT_B_BGA1  I172

M_J_DQ<35>      @BASEBOARD_FAB2_LIB.BASEBOARD_FAB2(SCH_1):M_J_DQ<35>
  J1G3   104  DQ<34>  SCONN288_H44441004_PIP  I186
  J9U2   249  DQ<35>  SCONN288_H44441003_PIP  I187
  U2D1   Y37  DDR2_DQ<35>  SKX_EXT_B_BGA1  I172

M_J_DQ<36>      @BASEBOARD_FAB2_LIB.BASEBOARD_FAB2(SCH_1):M_J_DQ<36>
  J1G3   240  DQ<37>  SCONN288_H44441004_PIP  I186
  J9U2    95  DQ<36>  SCONN288_H44441003_PIP  I187
  U2D1   V41  DDR2_DQ<36>  SKX_EXT_B_BGA1  I172

M_J_DQ<37>      @BASEBOARD_FAB2_LIB.BASEBOARD_FAB2(SCH_1):M_J_DQ<37>
  J1G3    95  DQ<36>  SCONN288_H44441004_PIP  I186
  J9U2   240  DQ<37>  SCONN288_H44441003_PIP  I187
  U2D1   Y41  DDR2_DQ<37>  SKX_EXT_B_BGA1  I172

M_J_DQ<38>      @BASEBOARD_FAB2_LIB.BASEBOARD_FAB2(SCH_1):M_J_DQ<38>
  J1G3   247  DQ<39>  SCONN288_H44441004_PIP  I186
  J9U2   102  DQ<38>  SCONN288_H44441003_PIP  I187
  U2D1   U38  DDR2_DQ<38>  SKX_EXT_B_BGA1  I172

M_J_DQ<39>      @BASEBOARD_FAB2_LIB.BASEBOARD_FAB2(SCH_1):M_J_DQ<39>
  J1G3   102  DQ<38>  SCONN288_H44441004_PIP  I186
  J9U2   247  DQ<39>  SCONN288_H44441003_PIP  I187
  U2D1   AA38  DDR2_DQ<39>  SKX_EXT_B_BGA1  I172

M_J_DQ<40>      @BASEBOARD_FAB2_LIB.BASEBOARD_FAB2(SCH_1):M_J_DQ<40>
  J1G3   253  DQ<41>  SCONN288_H44441004_PIP  I186
  J9U2   108  DQ<40>  SCONN288_H44441003_PIP  I187
  U2D1   U34  DDR2_DQ<40>  SKX_EXT_B_BGA1  I172

M_J_DQ<41>      @BASEBOARD_FAB2_LIB.BASEBOARD_FAB2(SCH_1):M_J_DQ<41>
  J1G3   108  DQ<40>  SCONN288_H44441004_PIP  I186
  J9U2   253  DQ<41>  SCONN288_H44441003_PIP  I187
  U2D1   AA34  DDR2_DQ<41>  SKX_EXT_B_BGA1  I172

M_J_DQ<42>      @BASEBOARD_FAB2_LIB.BASEBOARD_FAB2(SCH_1):M_J_DQ<42>
  J1G3   260  DQ<43>  SCONN288_H44441004_PIP  I186
  J9U2   115  DQ<42>  SCONN288_H44441003_PIP  I187
  U2D1   V31  DDR2_DQ<42>  SKX_EXT_B_BGA1  I172

M_J_DQ<43>      @BASEBOARD_FAB2_LIB.BASEBOARD_FAB2(SCH_1):M_J_DQ<43>
  J1G3   115  DQ<42>  SCONN288_H44441004_PIP  I186
  J9U2   260  DQ<43>  SCONN288_H44441003_PIP  I187
  U2D1   Y31  DDR2_DQ<43>  SKX_EXT_B_BGA1  I172

M_J_DQ<44>      @BASEBOARD_FAB2_LIB.BASEBOARD_FAB2(SCH_1):M_J_DQ<44>
  J1G3   251  DQ<45>  SCONN288_H44441004_PIP  I186
  J9U2   106  DQ<44>  SCONN288_H44441003_PIP  I187
  U2D1   V35  DDR2_DQ<44>  SKX_EXT_B_BGA1  I172

M_J_DQ<45>      @BASEBOARD_FAB2_LIB.BASEBOARD_FAB2(SCH_1):M_J_DQ<45>
  J1G3   106  DQ<44>  SCONN288_H44441004_PIP  I186
  J9U2   251  DQ<45>  SCONN288_H44441003_PIP  I187
  U2D1   Y35  DDR2_DQ<45>  SKX_EXT_B_BGA1  I172

M_J_DQ<46>      @BASEBOARD_FAB2_LIB.BASEBOARD_FAB2(SCH_1):M_J_DQ<46>
  J1G3   258  DQ<47>  SCONN288_H44441004_PIP  I186
  J9U2   113  DQ<46>  SCONN288_H44441003_PIP  I187
  U2D1   U32  DDR2_DQ<46>  SKX_EXT_B_BGA1  I172

M_J_DQ<47>      @BASEBOARD_FAB2_LIB.BASEBOARD_FAB2(SCH_1):M_J_DQ<47>
  J1G3   113  DQ<46>  SCONN288_H44441004_PIP  I186
  J9U2   258  DQ<47>  SCONN288_H44441003_PIP  I187
  U2D1   AA32  DDR2_DQ<47>  SKX_EXT_B_BGA1  I172

M_J_DQ<48>      @BASEBOARD_FAB2_LIB.BASEBOARD_FAB2(SCH_1):M_J_DQ<48>
  J1G3   264  DQ<49>  SCONN288_H44441004_PIP  I186
  J9U2   119  DQ<48>  SCONN288_H44441003_PIP  I187
  U2D1   AD31  DDR2_DQ<48>  SKX_EXT_B_BGA1  I172

M_J_DQ<49>      @BASEBOARD_FAB2_LIB.BASEBOARD_FAB2(SCH_1):M_J_DQ<49>
  J1G3   119  DQ<48>  SCONN288_H44441004_PIP  I186
  J9U2   264  DQ<49>  SCONN288_H44441003_PIP  I187
  U2D1   AH31  DDR2_DQ<49>  SKX_EXT_B_BGA1  I172

M_J_DQ<50>      @BASEBOARD_FAB2_LIB.BASEBOARD_FAB2(SCH_1):M_J_DQ<50>
  J1G3   271  DQ<51>  SCONN288_H44441004_PIP  I186
  J9U2   126  DQ<50>  SCONN288_H44441003_PIP  I187
  U2D1   AE28  DDR2_DQ<50>  SKX_EXT_B_BGA1  I172

M_J_DQ<51>      @BASEBOARD_FAB2_LIB.BASEBOARD_FAB2(SCH_1):M_J_DQ<51>
  J1G3   126  DQ<50>  SCONN288_H44441004_PIP  I186
  J9U2   271  DQ<51>  SCONN288_H44441003_PIP  I187
  U2D1   AG28  DDR2_DQ<51>  SKX_EXT_B_BGA1  I172

M_J_DQ<52>      @BASEBOARD_FAB2_LIB.BASEBOARD_FAB2(SCH_1):M_J_DQ<52>
  J1G3   262  DQ<53>  SCONN288_H44441004_PIP  I186
  J9U2   117  DQ<52>  SCONN288_H44441003_PIP  I187
  U2D1   AE32  DDR2_DQ<52>  SKX_EXT_B_BGA1  I172

M_J_DQ<53>      @BASEBOARD_FAB2_LIB.BASEBOARD_FAB2(SCH_1):M_J_DQ<53>
  J1G3   117  DQ<52>  SCONN288_H44441004_PIP  I186
  J9U2   262  DQ<53>  SCONN288_H44441003_PIP  I187
  U2D1   AG32  DDR2_DQ<53>  SKX_EXT_B_BGA1  I172

M_J_DQ<54>      @BASEBOARD_FAB2_LIB.BASEBOARD_FAB2(SCH_1):M_J_DQ<54>
  J1G3   269  DQ<55>  SCONN288_H44441004_PIP  I186
  J9U2   124  DQ<54>  SCONN288_H44441003_PIP  I187
  U2D1   AD29  DDR2_DQ<54>  SKX_EXT_B_BGA1  I172

M_J_DQ<55>      @BASEBOARD_FAB2_LIB.BASEBOARD_FAB2(SCH_1):M_J_DQ<55>
  J1G3   124  DQ<54>  SCONN288_H44441004_PIP  I186
  J9U2   269  DQ<55>  SCONN288_H44441003_PIP  I187
  U2D1   AH29  DDR2_DQ<55>  SKX_EXT_B_BGA1  I172

M_J_DQ<56>      @BASEBOARD_FAB2_LIB.BASEBOARD_FAB2(SCH_1):M_J_DQ<56>
  J1G3   275  DQ<57>  SCONN288_H44441004_PIP  I186
  J9U2   130  DQ<56>  SCONN288_H44441003_PIP  I187
  U2D1   AD25  DDR2_DQ<56>  SKX_EXT_B_BGA1  I172

M_J_DQ<57>      @BASEBOARD_FAB2_LIB.BASEBOARD_FAB2(SCH_1):M_J_DQ<57>
  J1G3   130  DQ<56>  SCONN288_H44441004_PIP  I186
  J9U2   275  DQ<57>  SCONN288_H44441003_PIP  I187
  U2D1   AH25  DDR2_DQ<57>  SKX_EXT_B_BGA1  I172

M_J_DQ<58>      @BASEBOARD_FAB2_LIB.BASEBOARD_FAB2(SCH_1):M_J_DQ<58>
  J1G3   282  DQ<59>  SCONN288_H44441004_PIP  I186
  J9U2   137  DQ<58>  SCONN288_H44441003_PIP  I187
  U2D1   AE22  DDR2_DQ<58>  SKX_EXT_B_BGA1  I172

M_J_DQ<59>      @BASEBOARD_FAB2_LIB.BASEBOARD_FAB2(SCH_1):M_J_DQ<59>
  J1G3   137  DQ<58>  SCONN288_H44441004_PIP  I186
  J9U2   282  DQ<59>  SCONN288_H44441003_PIP  I187
  U2D1   AG22  DDR2_DQ<59>  SKX_EXT_B_BGA1  I172

M_J_DQ<60>      @BASEBOARD_FAB2_LIB.BASEBOARD_FAB2(SCH_1):M_J_DQ<60>
  J1G3   273  DQ<61>  SCONN288_H44441004_PIP  I186
  J9U2   128  DQ<60>  SCONN288_H44441003_PIP  I187
  U2D1   AE26  DDR2_DQ<60>  SKX_EXT_B_BGA1  I172

M_J_DQ<61>      @BASEBOARD_FAB2_LIB.BASEBOARD_FAB2(SCH_1):M_J_DQ<61>
  J1G3   128  DQ<60>  SCONN288_H44441004_PIP  I186
  J9U2   273  DQ<61>  SCONN288_H44441003_PIP  I187
  U2D1   AG26  DDR2_DQ<61>  SKX_EXT_B_BGA1  I172

M_J_DQ<62>      @BASEBOARD_FAB2_LIB.BASEBOARD_FAB2(SCH_1):M_J_DQ<62>
  J1G3   280  DQ<63>  SCONN288_H44441004_PIP  I186
  J9U2   135  DQ<62>  SCONN288_H44441003_PIP  I187
  U2D1   AD23  DDR2_DQ<62>  SKX_EXT_B_BGA1  I172

M_J_DQ<63>      @BASEBOARD_FAB2_LIB.BASEBOARD_FAB2(SCH_1):M_J_DQ<63>
  J1G3   135  DQ<62>  SCONN288_H44441004_PIP  I186
  J9U2   280  DQ<63>  SCONN288_H44441003_PIP  I187
  U2D1   AH23  DDR2_DQ<63>  SKX_EXT_B_BGA1  I172

M_J_DQS_DN<0>   @BASEBOARD_FAB2_LIB.BASEBOARD_FAB2(SCH_1):M_J_DQS_DN<0>
  J1G3   152  DQS0N  SCONN288_H44441004_PIP  I67
  J9U2   152  DQS0N  SCONN288_H44441003_PIP  I64
  U2D1   AL74  DDR2_DQS_DN<0>  SKX_EXT_B_BGA1  I172

M_J_DQS_DN<1>   @BASEBOARD_FAB2_LIB.BASEBOARD_FAB2(SCH_1):M_J_DQS_DN<1>
  J1G3   163  DQS1N  SCONN288_H44441004_PIP  I67
  J9U2   163  DQS1N  SCONN288_H44441003_PIP  I64
  U2D1   AA74  DDR2_DQS_DN<1>  SKX_EXT_B_BGA1  I172

M_J_DQS_DN<2>   @BASEBOARD_FAB2_LIB.BASEBOARD_FAB2(SCH_1):M_J_DQS_DN<2>
  J1G3   174  DQS2N  SCONN288_H44441004_PIP  I67
  J9U2   174  DQS2N  SCONN288_H44441003_PIP  I64
  U2D1   Y69  DDR2_DQS_DN<2>  SKX_EXT_B_BGA1  I172

M_J_DQS_DN<3>   @BASEBOARD_FAB2_LIB.BASEBOARD_FAB2(SCH_1):M_J_DQS_DN<3>
  J1G3   185  DQS3N  SCONN288_H44441004_PIP  I67
  J9U2   185  DQS3N  SCONN288_H44441003_PIP  I64
  U2D1   AU66  DDR2_DQS_DN<3>  SKX_EXT_B_BGA1  I172

M_J_DQS_DN<4>   @BASEBOARD_FAB2_LIB.BASEBOARD_FAB2(SCH_1):M_J_DQS_DN<4>
  J1G3   244  DQS4N  SCONN288_H44441004_PIP  I67
  J9U2   244  DQS4N  SCONN288_H44441003_PIP  I64
  U2D1   AB39  DDR2_DQS_DN<4>  SKX_EXT_B_BGA1  I172

M_J_DQS_DN<5>   @BASEBOARD_FAB2_LIB.BASEBOARD_FAB2(SCH_1):M_J_DQS_DN<5>
  J1G3   255  DQS5N  SCONN288_H44441004_PIP  I67
  J9U2   255  DQS5N  SCONN288_H44441003_PIP  I64
  U2D1   AB33  DDR2_DQS_DN<5>  SKX_EXT_B_BGA1  I172

M_J_DQS_DN<6>   @BASEBOARD_FAB2_LIB.BASEBOARD_FAB2(SCH_1):M_J_DQS_DN<6>
  J1G3   266  DQS6N  SCONN288_H44441004_PIP  I67
  J9U2   266  DQS6N  SCONN288_H44441003_PIP  I64
  U2D1   AJ30  DDR2_DQS_DN<6>  SKX_EXT_B_BGA1  I172

M_J_DQS_DN<7>   @BASEBOARD_FAB2_LIB.BASEBOARD_FAB2(SCH_1):M_J_DQS_DN<7>
  J1G3   277  DQS7N  SCONN288_H44441004_PIP  I67
  J9U2   277  DQS7N  SCONN288_H44441003_PIP  I64
  U2D1   AJ24  DDR2_DQS_DN<7>  SKX_EXT_B_BGA1  I172

M_J_DQS_DN<8>   @BASEBOARD_FAB2_LIB.BASEBOARD_FAB2(SCH_1):M_J_DQS_DN<8>
  J1G3   196  DQS8N  SCONN288_H44441004_PIP  I67
  J9U2   196  DQS8N  SCONN288_H44441003_PIP  I64
  U2D1   BB71  DDR2_DQS_DN<8>  SKX_EXT_B_BGA1  I172

M_J_DQS_DN<9>   @BASEBOARD_FAB2_LIB.BASEBOARD_FAB2(SCH_1):M_J_DQS_DN<9>
  J1G3     8  DQS9N  SCONN288_H44441004_PIP  I67
  J9U2     8  DQS9N  SCONN288_H44441003_PIP  I64
  U2D1   AP77  DDR2_DQS_DN<9>  SKX_EXT_B_BGA1  I172

M_J_DQS_DN<10>   @BASEBOARD_FAB2_LIB.BASEBOARD_FAB2(SCH_1):M_J_DQS_DN<10>
  J1G3    19  DQS10N  SCONN288_H44441004_PIP  I67
  J9U2    19  DQS10N  SCONN288_H44441003_PIP  I64
  U2D1   AD77  DDR2_DQS_DN<10>  SKX_EXT_B_BGA1  I172

M_J_DQS_DN<11>   @BASEBOARD_FAB2_LIB.BASEBOARD_FAB2(SCH_1):M_J_DQS_DN<11>
  J1G3    30  DQS11N  SCONN288_H44441004_PIP  I67
  J9U2    30  DQS11N  SCONN288_H44441003_PIP  I64
  U2D1   U72  DDR2_DQS_DN<11>  SKX_EXT_B_BGA1  I172

M_J_DQS_DN<12>   @BASEBOARD_FAB2_LIB.BASEBOARD_FAB2(SCH_1):M_J_DQS_DN<12>
  J1G3    41  DQS12N  SCONN288_H44441004_PIP  I67
  J9U2    41  DQS12N  SCONN288_H44441003_PIP  I64
  U2D1   AL66  DDR2_DQS_DN<12>  SKX_EXT_B_BGA1  I172

M_J_DQS_DN<13>   @BASEBOARD_FAB2_LIB.BASEBOARD_FAB2(SCH_1):M_J_DQS_DN<13>
  J1G3   100  DQS13N  SCONN288_H44441004_PIP  I67
  J9U2   100  DQS13N  SCONN288_H44441003_PIP  I64
  U2D1   T39  DDR2_DQS_DN<13>  SKX_EXT_B_BGA1  I172

M_J_DQS_DN<14>   @BASEBOARD_FAB2_LIB.BASEBOARD_FAB2(SCH_1):M_J_DQS_DN<14>
  J1G3   111  DQS14N  SCONN288_H44441004_PIP  I67
  J9U2   111  DQS14N  SCONN288_H44441003_PIP  I64
  U2D1   T33  DDR2_DQS_DN<14>  SKX_EXT_B_BGA1  I172

M_J_DQS_DN<15>   @BASEBOARD_FAB2_LIB.BASEBOARD_FAB2(SCH_1):M_J_DQS_DN<15>
  J1G3   122  DQS15N  SCONN288_H44441004_PIP  I67
  J9U2   122  DQS15N  SCONN288_H44441003_PIP  I64
  U2D1   AC30  DDR2_DQS_DN<15>  SKX_EXT_B_BGA1  I172

M_J_DQS_DN<16>   @BASEBOARD_FAB2_LIB.BASEBOARD_FAB2(SCH_1):M_J_DQS_DN<16>
  J1G3   133  DQS16N  SCONN288_H44441004_PIP  I67
  J9U2   133  DQS16N  SCONN288_H44441003_PIP  I64
  U2D1   AC24  DDR2_DQS_DN<16>  SKX_EXT_B_BGA1  I172

M_J_DQS_DN<17>   @BASEBOARD_FAB2_LIB.BASEBOARD_FAB2(SCH_1):M_J_DQS_DN<17>
  J1G3    52  DQS17N  SCONN288_H44441004_PIP  I67
  J9U2    52  DQS17N  SCONN288_H44441003_PIP  I64
  U2D1   AT71  DDR2_DQS_DN<17>  SKX_EXT_B_BGA1  I172

M_J_DQS_DP<0>   @BASEBOARD_FAB2_LIB.BASEBOARD_FAB2(SCH_1):M_J_DQS_DP<0>
  J1G3   153  DQS0P  SCONN288_H44441004_PIP  I67
  J9U2   153  DQS0P  SCONN288_H44441003_PIP  I64
  U2D1   AM75  DDR2_DQS_DP<0>  SKX_EXT_B_BGA1  I172

M_J_DQS_DP<1>   @BASEBOARD_FAB2_LIB.BASEBOARD_FAB2(SCH_1):M_J_DQS_DP<1>
  J1G3   164  DQS1P  SCONN288_H44441004_PIP  I67
  J9U2   164  DQS1P  SCONN288_H44441003_PIP  I64
  U2D1   AB75  DDR2_DQS_DP<1>  SKX_EXT_B_BGA1  I172

M_J_DQS_DP<2>   @BASEBOARD_FAB2_LIB.BASEBOARD_FAB2(SCH_1):M_J_DQS_DP<2>
  J1G3   175  DQS2P  SCONN288_H44441004_PIP  I67
  J9U2   175  DQS2P  SCONN288_H44441003_PIP  I64
  U2D1   W70  DDR2_DQS_DP<2>  SKX_EXT_B_BGA1  I172

M_J_DQS_DP<3>   @BASEBOARD_FAB2_LIB.BASEBOARD_FAB2(SCH_1):M_J_DQS_DP<3>
  J1G3   186  DQS3P  SCONN288_H44441004_PIP  I67
  J9U2   186  DQS3P  SCONN288_H44441003_PIP  I64
  U2D1   AR66  DDR2_DQS_DP<3>  SKX_EXT_B_BGA1  I172

M_J_DQS_DP<4>   @BASEBOARD_FAB2_LIB.BASEBOARD_FAB2(SCH_1):M_J_DQS_DP<4>
  J1G3   245  DQS4P  SCONN288_H44441004_PIP  I67
  J9U2   245  DQS4P  SCONN288_H44441003_PIP  I64
  U2D1   Y39  DDR2_DQS_DP<4>  SKX_EXT_B_BGA1  I172

M_J_DQS_DP<5>   @BASEBOARD_FAB2_LIB.BASEBOARD_FAB2(SCH_1):M_J_DQS_DP<5>
  J1G3   256  DQS5P  SCONN288_H44441004_PIP  I67
  J9U2   256  DQS5P  SCONN288_H44441003_PIP  I64
  U2D1   Y33  DDR2_DQS_DP<5>  SKX_EXT_B_BGA1  I172

M_J_DQS_DP<6>   @BASEBOARD_FAB2_LIB.BASEBOARD_FAB2(SCH_1):M_J_DQS_DP<6>
  J1G3   267  DQS6P  SCONN288_H44441004_PIP  I67
  J9U2   267  DQS6P  SCONN288_H44441003_PIP  I64
  U2D1   AG30  DDR2_DQS_DP<6>  SKX_EXT_B_BGA1  I172

M_J_DQS_DP<7>   @BASEBOARD_FAB2_LIB.BASEBOARD_FAB2(SCH_1):M_J_DQS_DP<7>
  J1G3   278  DQS7P  SCONN288_H44441004_PIP  I67
  J9U2   278  DQS7P  SCONN288_H44441003_PIP  I64
  U2D1   AG24  DDR2_DQS_DP<7>  SKX_EXT_B_BGA1  I172

M_J_DQS_DP<8>   @BASEBOARD_FAB2_LIB.BASEBOARD_FAB2(SCH_1):M_J_DQS_DP<8>
  J1G3   197  DQS8P  SCONN288_H44441004_PIP  I67
  J9U2   197  DQS8P  SCONN288_H44441003_PIP  I64
  U2D1   AY71  DDR2_DQS_DP<8>  SKX_EXT_B_BGA1  I172

M_J_DQS_DP<9>   @BASEBOARD_FAB2_LIB.BASEBOARD_FAB2(SCH_1):M_J_DQS_DP<9>
  J1G3     7  DQS9P  SCONN288_H44441004_PIP  I67
  J9U2     7  DQS9P  SCONN288_H44441003_PIP  I64
  U2D1   AN76  DDR2_DQS_DP<9>  SKX_EXT_B_BGA1  I172

M_J_DQS_DP<10>   @BASEBOARD_FAB2_LIB.BASEBOARD_FAB2(SCH_1):M_J_DQS_DP<10>
  J1G3    18  DQS10P  SCONN288_H44441004_PIP  I67
  J9U2    18  DQS10P  SCONN288_H44441003_PIP  I64
  U2D1   AC76  DDR2_DQS_DP<10>  SKX_EXT_B_BGA1  I172

M_J_DQS_DP<11>   @BASEBOARD_FAB2_LIB.BASEBOARD_FAB2(SCH_1):M_J_DQS_DP<11>
  J1G3    29  DQS11P  SCONN288_H44441004_PIP  I67
  J9U2    29  DQS11P  SCONN288_H44441003_PIP  I64
  U2D1   V71  DDR2_DQS_DP<11>  SKX_EXT_B_BGA1  I172

M_J_DQS_DP<12>   @BASEBOARD_FAB2_LIB.BASEBOARD_FAB2(SCH_1):M_J_DQS_DP<12>
  J1G3    40  DQS12P  SCONN288_H44441004_PIP  I67
  J9U2    40  DQS12P  SCONN288_H44441003_PIP  I64
  U2D1   AN66  DDR2_DQS_DP<12>  SKX_EXT_B_BGA1  I172

M_J_DQS_DP<13>   @BASEBOARD_FAB2_LIB.BASEBOARD_FAB2(SCH_1):M_J_DQS_DP<13>
  J1G3    99  DQS13P  SCONN288_H44441004_PIP  I67
  J9U2    99  DQS13P  SCONN288_H44441003_PIP  I64
  U2D1   V39  DDR2_DQS_DP<13>  SKX_EXT_B_BGA1  I172

M_J_DQS_DP<14>   @BASEBOARD_FAB2_LIB.BASEBOARD_FAB2(SCH_1):M_J_DQS_DP<14>
  J1G3   110  DQS14P  SCONN288_H44441004_PIP  I67
  J9U2   110  DQS14P  SCONN288_H44441003_PIP  I64
  U2D1   V33  DDR2_DQS_DP<14>  SKX_EXT_B_BGA1  I172

M_J_DQS_DP<15>   @BASEBOARD_FAB2_LIB.BASEBOARD_FAB2(SCH_1):M_J_DQS_DP<15>
  J1G3   121  DQS15P  SCONN288_H44441004_PIP  I67
  J9U2   121  DQS15P  SCONN288_H44441003_PIP  I64
  U2D1   AE30  DDR2_DQS_DP<15>  SKX_EXT_B_BGA1  I172

M_J_DQS_DP<16>   @BASEBOARD_FAB2_LIB.BASEBOARD_FAB2(SCH_1):M_J_DQS_DP<16>
  J1G3   132  DQS16P  SCONN288_H44441004_PIP  I67
  J9U2   132  DQS16P  SCONN288_H44441003_PIP  I64
  U2D1   AE24  DDR2_DQS_DP<16>  SKX_EXT_B_BGA1  I172

M_J_DQS_DP<17>   @BASEBOARD_FAB2_LIB.BASEBOARD_FAB2(SCH_1):M_J_DQS_DP<17>
  J1G3    51  DQS17P  SCONN288_H44441004_PIP  I67
  J9U2    51  DQS17P  SCONN288_H44441003_PIP  I64
  U2D1   AV71  DDR2_DQS_DP<17>  SKX_EXT_B_BGA1  I172

M_J_ECC<0>      @BASEBOARD_FAB2_LIB.BASEBOARD_FAB2(SCH_1):M_J_ECC<0>
  J1G3   194  CB<1>  SCONN288_H44441004_PIP  I186
  J9U2    49  CB<0>  SCONN288_H44441003_PIP  I187
  U2D1   AU72  DDR2_ECC<0>  SKX_EXT_B_BGA1  I172

M_J_ECC<1>      @BASEBOARD_FAB2_LIB.BASEBOARD_FAB2(SCH_1):M_J_ECC<1>
  J1G3    49  CB<0>  SCONN288_H44441004_PIP  I186
  J9U2   194  CB<1>  SCONN288_H44441003_PIP  I187
  U2D1   BA72  DDR2_ECC<1>  SKX_EXT_B_BGA1  I172

M_J_ECC<2>      @BASEBOARD_FAB2_LIB.BASEBOARD_FAB2(SCH_1):M_J_ECC<2>
  J1G3   201  CB<3>  SCONN288_H44441004_PIP  I186
  J9U2    56  CB<2>  SCONN288_H44441003_PIP  I187
  U2D1   AV69  DDR2_ECC<2>  SKX_EXT_B_BGA1  I172

M_J_ECC<3>      @BASEBOARD_FAB2_LIB.BASEBOARD_FAB2(SCH_1):M_J_ECC<3>
  J1G3    56  CB<2>  SCONN288_H44441004_PIP  I186
  J9U2   201  CB<3>  SCONN288_H44441003_PIP  I187
  U2D1   AY69  DDR2_ECC<3>  SKX_EXT_B_BGA1  I172

M_J_ECC<4>      @BASEBOARD_FAB2_LIB.BASEBOARD_FAB2(SCH_1):M_J_ECC<4>
  J1G3   192  CB<5>  SCONN288_H44441004_PIP  I186
  J9U2    47  CB<4>  SCONN288_H44441003_PIP  I187
  U2D1   AV73  DDR2_ECC<4>  SKX_EXT_B_BGA1  I172

M_J_ECC<5>      @BASEBOARD_FAB2_LIB.BASEBOARD_FAB2(SCH_1):M_J_ECC<5>
  J1G3    47  CB<4>  SCONN288_H44441004_PIP  I186
  J9U2   192  CB<5>  SCONN288_H44441003_PIP  I187
  U2D1   AY73  DDR2_ECC<5>  SKX_EXT_B_BGA1  I172

M_J_ECC<6>      @BASEBOARD_FAB2_LIB.BASEBOARD_FAB2(SCH_1):M_J_ECC<6>
  J1G3   199  CB<7>  SCONN288_H44441004_PIP  I186
  J9U2    54  CB<6>  SCONN288_H44441003_PIP  I187
  U2D1   AU70  DDR2_ECC<6>  SKX_EXT_B_BGA1  I172

M_J_ECC<7>      @BASEBOARD_FAB2_LIB.BASEBOARD_FAB2(SCH_1):M_J_ECC<7>
  J1G3    54  CB<6>  SCONN288_H44441004_PIP  I186
  J9U2   199  CB<7>  SCONN288_H44441003_PIP  I187
  U2D1   BA70  DDR2_ECC<7>  SKX_EXT_B_BGA1  I172

M_J_MA<0>       @BASEBOARD_FAB2_LIB.BASEBOARD_FAB2(SCH_1):M_J_MA<0>
  J1G3    79     A0  SCONN288_H44441004_PIP  I186
  J9U2    79     A0  SCONN288_H44441003_PIP  I187
  U2D1   AB53  DDR2_MA<0>  SKX_EXT_B_BGA1  I172

M_J_MA<1>       @BASEBOARD_FAB2_LIB.BASEBOARD_FAB2(SCH_1):M_J_MA<1>
  J1G3    72     A1  SCONN288_H44441004_PIP  I186
  J9U2    72     A1  SCONN288_H44441003_PIP  I187
  U2D1   AE58  DDR2_MA<1>  SKX_EXT_B_BGA1  I172

M_J_MA<2>       @BASEBOARD_FAB2_LIB.BASEBOARD_FAB2(SCH_1):M_J_MA<2>
  J1G3   216     A2  SCONN288_H44441004_PIP  I186
  J9U2   216     A2  SCONN288_H44441003_PIP  I187
  U2D1   AD57  DDR2_MA<2>  SKX_EXT_B_BGA1  I172

M_J_MA<3>       @BASEBOARD_FAB2_LIB.BASEBOARD_FAB2(SCH_1):M_J_MA<3>
  J1G3    71     A3  SCONN288_H44441004_PIP  I186
  J9U2    71     A3  SCONN288_H44441003_PIP  I187
  U2D1   W58  DDR2_MA<3>  SKX_EXT_B_BGA1  I172

M_J_MA<4>       @BASEBOARD_FAB2_LIB.BASEBOARD_FAB2(SCH_1):M_J_MA<4>
  J1G3   214     A4  SCONN288_H44441004_PIP  I186
  J9U2   214     A4  SCONN288_H44441003_PIP  I187
  U2D1   AA58  DDR2_MA<4>  SKX_EXT_B_BGA1  I172

M_J_MA<5>       @BASEBOARD_FAB2_LIB.BASEBOARD_FAB2(SCH_1):M_J_MA<5>
  J1G3   213     A5  SCONN288_H44441004_PIP  I186
  J9U2   213     A5  SCONN288_H44441003_PIP  I187
  U2D1   V59  DDR2_MA<5>  SKX_EXT_B_BGA1  I172

M_J_MA<6>       @BASEBOARD_FAB2_LIB.BASEBOARD_FAB2(SCH_1):M_J_MA<6>
  J1G3    69     A6  SCONN288_H44441004_PIP  I186
  J9U2    69     A6  SCONN288_H44441003_PIP  I187
  U2D1   AB59  DDR2_MA<6>  SKX_EXT_B_BGA1  I172

M_J_MA<7>       @BASEBOARD_FAB2_LIB.BASEBOARD_FAB2(SCH_1):M_J_MA<7>
  J1G3   211     A7  SCONN288_H44441004_PIP  I186
  J9U2   211     A7  SCONN288_H44441003_PIP  I187
  U2D1   AE60  DDR2_MA<7>  SKX_EXT_B_BGA1  I172

M_J_MA<8>       @BASEBOARD_FAB2_LIB.BASEBOARD_FAB2(SCH_1):M_J_MA<8>
  J1G3    68     A8  SCONN288_H44441004_PIP  I186
  J9U2    68     A8  SCONN288_H44441003_PIP  I187
  U2D1   AD59  DDR2_MA<8>  SKX_EXT_B_BGA1  I172

M_J_MA<9>       @BASEBOARD_FAB2_LIB.BASEBOARD_FAB2(SCH_1):M_J_MA<9>
  J1G3    66     A9  SCONN288_H44441004_PIP  I186
  J9U2    66     A9  SCONN288_H44441003_PIP  I187
  U2D1   AG58  DDR2_MA<9>  SKX_EXT_B_BGA1  I172

M_J_MA<10>      @BASEBOARD_FAB2_LIB.BASEBOARD_FAB2(SCH_1):M_J_MA<10>
  J1G3   225    A10  SCONN288_H44441004_PIP  I186
  J9U2   225    A10  SCONN288_H44441003_PIP  I187
  U2D1   AD55  DDR2_MA<10>  SKX_EXT_B_BGA1  I172

M_J_MA<11>      @BASEBOARD_FAB2_LIB.BASEBOARD_FAB2(SCH_1):M_J_MA<11>
  J1G3   210    A11  SCONN288_H44441004_PIP  I186
  J9U2   210    A11  SCONN288_H44441003_PIP  I187
  U2D1   AG60  DDR2_MA<11>  SKX_EXT_B_BGA1  I172

M_J_MA<12>      @BASEBOARD_FAB2_LIB.BASEBOARD_FAB2(SCH_1):M_J_MA<12>
  J1G3    65    A12  SCONN288_H44441004_PIP  I186
  J9U2    65    A12  SCONN288_H44441003_PIP  I187
  U2D1   AG62  DDR2_MA<12>  SKX_EXT_B_BGA1  I172

M_J_MA<13>      @BASEBOARD_FAB2_LIB.BASEBOARD_FAB2(SCH_1):M_J_MA<13>
  J1G3   232    A13  SCONN288_H44441004_PIP  I186
  J9U2   232    A13  SCONN288_H44441003_PIP  I187
  U2D1   AD53  DDR2_MA<13>  SKX_EXT_B_BGA1  I172

M_J_MA<14>      @BASEBOARD_FAB2_LIB.BASEBOARD_FAB2(SCH_1):M_J_MA<14>
  J1G3   228  A14_WE_N  SCONN288_H44441004_PIP  I186
  J9U2   228  A14_WE_N  SCONN288_H44441003_PIP  I187
  U2D1   W50  DDR2_MA<14>  SKX_EXT_B_BGA1  I172

M_J_MA<15>      @BASEBOARD_FAB2_LIB.BASEBOARD_FAB2(SCH_1):M_J_MA<15>
  J1G3    86  A15_CAS_N  SCONN288_H44441004_PIP  I186
  J9U2    86  A15_CAS_N  SCONN288_H44441003_PIP  I187
  U2D1   AE54  DDR2_MA<15>  SKX_EXT_B_BGA1  I172

M_J_MA<16>      @BASEBOARD_FAB2_LIB.BASEBOARD_FAB2(SCH_1):M_J_MA<16>
  J1G3    82  A16_RAS_N  SCONN288_H44441004_PIP  I186
  J9U2    82  A16_RAS_N  SCONN288_H44441003_PIP  I187
  U2D1   AA52  DDR2_MA<16>  SKX_EXT_B_BGA1  I172

M_J_MA<17>      @BASEBOARD_FAB2_LIB.BASEBOARD_FAB2(SCH_1):M_J_MA<17>
  J1G3   234    A17  SCONN288_H44441004_PIP  I186
  J9U2   234    A17  SCONN288_H44441003_PIP  I187
  U2D1   AC46  DDR2_MA<17>  SKX_EXT_B_BGA1  I172

M_J_ODT<0>      @BASEBOARD_FAB2_LIB.BASEBOARD_FAB2(SCH_1):M_J_ODT<0>
  J1G3    87  ODT<0>  SCONN288_H44441004_PIP  I186
  U2D1   AA50  DDR2_ODT<0>  SKX_EXT_B_BGA1  I172

M_J_ODT<1>      @BASEBOARD_FAB2_LIB.BASEBOARD_FAB2(SCH_1):M_J_ODT<1>
  J1G3    91  ODT<1>  SCONN288_H44441004_PIP  I186
  U2D1   AA48  DDR2_ODT<1>  SKX_EXT_B_BGA1  I172

M_J_ODT<2>      @BASEBOARD_FAB2_LIB.BASEBOARD_FAB2(SCH_1):M_J_ODT<2>
  J9U2    87  ODT<0>  SCONN288_H44441003_PIP  I187
  U2D1   V49  DDR2_ODT<2>  SKX_EXT_B_BGA1  I172

M_J_ODT<3>      @BASEBOARD_FAB2_LIB.BASEBOARD_FAB2(SCH_1):M_J_ODT<3>
  J9U2    91  ODT<1>  SCONN288_H44441003_PIP  I187
  U2D1   AB47  DDR2_ODT<3>  SKX_EXT_B_BGA1  I172

M_J_PAR         @BASEBOARD_FAB2_LIB.BASEBOARD_FAB2(SCH_1):M_J_PAR
  J1G3   222    PAR  SCONN288_H44441004_PIP  I186
  J9U2   222    PAR  SCONN288_H44441003_PIP  I187
  U2D1   V53  DDR2_PAR  SKX_EXT_B_BGA1  I172

M_J_VREF        @BASEBOARD_FAB2_LIB.BASEBOARD_FAB2(SCH_1):M_J_VREF
  C1G19    1      A  CAP_A       I180
  C9U10    1      A  CAP_A       I178
  J1G3   146  VREFCA  SCONN288_H44441004_PIP  I186
  J9U2   146  VREFCA  SCONN288_H44441003_PIP  I187
  R1G14    2      B  RES         I41
  R1G15    2      B  RES         I35
  R1G17    1      A  RES         I36

M_KLM_RST_N     @BASEBOARD_FAB2_LIB.BASEBOARD_FAB2(SCH_1):M_KLM_RST_N
  J1A1    58  RESET_N  SCONN288_H44441004_PIP  I186
  J1A2    58  RESET_N  SCONN288_H44441004_PIP  I111
  J1B1    58  RESET_N  SCONN288_H44441004_PIP  I111
  J9L1    58  RESET_N  SCONN288_H44441003_PIP  I111
  J9L2    58  RESET_N  SCONN288_H44441003_PIP  I12
  J9M1    58  RESET_N  SCONN288_H44441003_PIP  I14
  U2D1   DV63  DDR345_RESET_N  SKX_EXT_B_BGA1  I172

M_K_ACT_N       @BASEBOARD_FAB2_LIB.BASEBOARD_FAB2(SCH_1):M_K_ACT_N
  J1B1    62  ACT_N  SCONN288_H44441004_PIP  I111
  J9M1    62  ACT_N  SCONN288_H44441003_PIP  I14
  U2D1   DW60  DDR3_ACT_N  SKX_EXT_B_BGA1  I172

M_K_ALERT_N     @BASEBOARD_FAB2_LIB.BASEBOARD_FAB2(SCH_1):M_K_ALERT_N
  J1B1   208  ALERT_N  SCONN288_H44441004_PIP  I111
  J9M1   208  ALERT_N  SCONN288_H44441003_PIP  I14
  U2D1   ED63  DDR3_ALERT_N  SKX_EXT_B_BGA1  I172

M_K_BA<0>       @BASEBOARD_FAB2_LIB.BASEBOARD_FAB2(SCH_1):M_K_BA<0>
  J1B1    81  BA<0>  SCONN288_H44441004_PIP  I111
  J9M1    81  BA<0>  SCONN288_H44441003_PIP  I14
  U2D1   EE52  DDR3_BA<0>  SKX_EXT_B_BGA1  I172

M_K_BA<1>       @BASEBOARD_FAB2_LIB.BASEBOARD_FAB2(SCH_1):M_K_BA<1>
  J1B1   224  BA<1>  SCONN288_H44441004_PIP  I111
  J9M1   224  BA<1>  SCONN288_H44441003_PIP  I14
  U2D1   EA54  DDR3_BA<1>  SKX_EXT_B_BGA1  I172

M_K_BG<0>       @BASEBOARD_FAB2_LIB.BASEBOARD_FAB2(SCH_1):M_K_BG<0>
  J1B1    63  BG<0>  SCONN288_H44441004_PIP  I111
  J9M1    63  BG<0>  SCONN288_H44441003_PIP  I14
  U2D1   ED61  DDR3_BG<0>  SKX_EXT_B_BGA1  I172

M_K_BG<1>       @BASEBOARD_FAB2_LIB.BASEBOARD_FAB2(SCH_1):M_K_BG<1>
  J1B1   207  BG<1>  SCONN288_H44441004_PIP  I111
  J9M1   207  BG<1>  SCONN288_H44441003_PIP  I14
  U2D1   DW62  DDR3_BG<1>  SKX_EXT_B_BGA1  I172

M_K_C<2>        @BASEBOARD_FAB2_LIB.BASEBOARD_FAB2(SCH_1):M_K_C<2>
  J1B1   235   C<2>  SCONN288_H44441004_PIP  I111
  J9M1   235   C<2>  SCONN288_H44441003_PIP  I14
  U2D1   DV47  DDR3_CID<2>  SKX_EXT_B_BGA1  I172

M_K_CKE<0>      @BASEBOARD_FAB2_LIB.BASEBOARD_FAB2(SCH_1):M_K_CKE<0>
  J1B1    60  CKE<0>  SCONN288_H44441004_PIP  I111
  U2D1   EE62  DDR3_CKE<0>  SKX_EXT_B_BGA1  I172

M_K_CKE<1>      @BASEBOARD_FAB2_LIB.BASEBOARD_FAB2(SCH_1):M_K_CKE<1>
  J1B1   203  CKE<1>  SCONN288_H44441004_PIP  I111
  U2D1   EF63  DDR3_CKE<1>  SKX_EXT_B_BGA1  I172

M_K_CKE<2>      @BASEBOARD_FAB2_LIB.BASEBOARD_FAB2(SCH_1):M_K_CKE<2>
  J9M1    60  CKE<0>  SCONN288_H44441003_PIP  I14
  U2D1   EA62  DDR3_CKE<2>  SKX_EXT_B_BGA1  I172

M_K_CKE<3>      @BASEBOARD_FAB2_LIB.BASEBOARD_FAB2(SCH_1):M_K_CKE<3>
  J9M1   203  CKE<1>  SCONN288_H44441003_PIP  I14
  U2D1   EB63  DDR3_CKE<3>  SKX_EXT_B_BGA1  I172

M_K_CLK_DN<0>   @BASEBOARD_FAB2_LIB.BASEBOARD_FAB2(SCH_1):M_K_CLK_DN<0>
  J1B1    75   CK0N  SCONN288_H44441004_PIP  I111
  U2D1   ED55  DDR3_CLK_DN<0>  SKX_EXT_B_BGA1  I172

M_K_CLK_DN<1>   @BASEBOARD_FAB2_LIB.BASEBOARD_FAB2(SCH_1):M_K_CLK_DN<1>
  J1B1   219   CK1N  SCONN288_H44441004_PIP  I111
  U2D1   EF55  DDR3_CLK_DN<1>  SKX_EXT_B_BGA1  I172

M_K_CLK_DN<2>   @BASEBOARD_FAB2_LIB.BASEBOARD_FAB2(SCH_1):M_K_CLK_DN<2>
  J9M1    75   CK0N  SCONN288_H44441003_PIP  I14
  U2D1   DW56  DDR3_CLK_DN<2>  SKX_EXT_B_BGA1  I172

M_K_CLK_DN<3>   @BASEBOARD_FAB2_LIB.BASEBOARD_FAB2(SCH_1):M_K_CLK_DN<3>
  J9M1   219   CK1N  SCONN288_H44441003_PIP  I14
  U2D1   EF57  DDR3_CLK_DN<3>  SKX_EXT_B_BGA1  I172

M_K_CLK_DP<0>   @BASEBOARD_FAB2_LIB.BASEBOARD_FAB2(SCH_1):M_K_CLK_DP<0>
  J1B1    74   CK0P  SCONN288_H44441004_PIP  I111
  U2D1   EB55  DDR3_CLK_DP<0>  SKX_EXT_B_BGA1  I172

M_K_CLK_DP<1>   @BASEBOARD_FAB2_LIB.BASEBOARD_FAB2(SCH_1):M_K_CLK_DP<1>
  J1B1   218   CK1P  SCONN288_H44441004_PIP  I111
  U2D1   EE54  DDR3_CLK_DP<1>  SKX_EXT_B_BGA1  I172

M_K_CLK_DP<2>   @BASEBOARD_FAB2_LIB.BASEBOARD_FAB2(SCH_1):M_K_CLK_DP<2>
  J9M1    74   CK0P  SCONN288_H44441003_PIP  I14
  U2D1   EA56  DDR3_CLK_DP<2>  SKX_EXT_B_BGA1  I172

M_K_CLK_DP<3>   @BASEBOARD_FAB2_LIB.BASEBOARD_FAB2(SCH_1):M_K_CLK_DP<3>
  J9M1   218   CK1P  SCONN288_H44441003_PIP  I14
  U2D1   EE56  DDR3_CLK_DP<3>  SKX_EXT_B_BGA1  I172

M_K_CPU_VREF    @BASEBOARD_FAB2_LIB.BASEBOARD_FAB2(SCH_1):M_K_CPU_VREF
  C9M2     1      A  CAP_A       I15
  R9M2     1      A  RES         I13
  U2D1   CP61  DDR3_CAVREF  SKX_EXT_B_BGA1  I172

M_K_CS_N<0>     @BASEBOARD_FAB2_LIB.BASEBOARD_FAB2(SCH_1):M_K_CS_N<0>
  J1B1    84   S0_N  SCONN288_H44441004_PIP  I111
  U2D1   EF51  DDR3_CS_N<0>  SKX_EXT_B_BGA1  I172

M_K_CS_N<1>     @BASEBOARD_FAB2_LIB.BASEBOARD_FAB2(SCH_1):M_K_CS_N<1>
  J1B1    89   S1_N  SCONN288_H44441004_PIP  I111
  U2D1   ED49  DDR3_CS_N<1>  SKX_EXT_B_BGA1  I172

M_K_CS_N<2>     @BASEBOARD_FAB2_LIB.BASEBOARD_FAB2(SCH_1):M_K_CS_N<2>
  J1B1    93  S2_N_C<0>  SCONN288_H44441004_PIP  I111
  U2D1   ED47  DDR3_CS_N<2>  SKX_EXT_B_BGA1  I172

M_K_CS_N<3>     @BASEBOARD_FAB2_LIB.BASEBOARD_FAB2(SCH_1):M_K_CS_N<3>
  J1B1   237  S3_N_C<1>  SCONN288_H44441004_PIP  I111
  U2D1   EB47  DDR3_CS_N<3>  SKX_EXT_B_BGA1  I172

M_K_CS_N<4>     @BASEBOARD_FAB2_LIB.BASEBOARD_FAB2(SCH_1):M_K_CS_N<4>
  J9M1    84   S0_N  SCONN288_H44441003_PIP  I14
  U2D1   EB51  DDR3_CS_N<4>  SKX_EXT_B_BGA1  I172

M_K_CS_N<5>     @BASEBOARD_FAB2_LIB.BASEBOARD_FAB2(SCH_1):M_K_CS_N<5>
  J9M1    89   S1_N  SCONN288_H44441003_PIP  I14
  U2D1   EB49  DDR3_CS_N<5>  SKX_EXT_B_BGA1  I172

M_K_CS_N<6>     @BASEBOARD_FAB2_LIB.BASEBOARD_FAB2(SCH_1):M_K_CS_N<6>
  J9M1    93  S2_N_C<0>  SCONN288_H44441003_PIP  I14
  U2D1   DV45  DDR3_CS_N<6>  SKX_EXT_B_BGA1  I172

M_K_CS_N<7>     @BASEBOARD_FAB2_LIB.BASEBOARD_FAB2(SCH_1):M_K_CS_N<7>
  J9M1   237  S3_N_C<1>  SCONN288_H44441003_PIP  I14
  U2D1   EB45  DDR3_CS_N<7>  SKX_EXT_B_BGA1  I172

M_K_DQ<0>       @BASEBOARD_FAB2_LIB.BASEBOARD_FAB2(SCH_1):M_K_DQ<0>
  J1B1   150  DQ<1>  SCONN288_H44441004_PIP  I111
  J9M1     5  DQ<0>  SCONN288_H44441003_PIP  I14
  U2D1   CN84  DDR3_DQ<0>  SKX_EXT_B_BGA1  I172

M_K_DQ<1>       @BASEBOARD_FAB2_LIB.BASEBOARD_FAB2(SCH_1):M_K_DQ<1>
  J1B1     5  DQ<0>  SCONN288_H44441004_PIP  I111
  J9M1   150  DQ<1>  SCONN288_H44441003_PIP  I14
  U2D1   CN86  DDR3_DQ<1>  SKX_EXT_B_BGA1  I172

M_K_DQ<2>       @BASEBOARD_FAB2_LIB.BASEBOARD_FAB2(SCH_1):M_K_DQ<2>
  J1B1   157  DQ<3>  SCONN288_H44441004_PIP  I111
  J9M1    12  DQ<2>  SCONN288_H44441003_PIP  I14
  U2D1   DA86  DDR3_DQ<2>  SKX_EXT_B_BGA1  I172

M_K_DQ<3>       @BASEBOARD_FAB2_LIB.BASEBOARD_FAB2(SCH_1):M_K_DQ<3>
  J1B1    12  DQ<2>  SCONN288_H44441004_PIP  I111
  J9M1   157  DQ<3>  SCONN288_H44441003_PIP  I14
  U2D1   DA84  DDR3_DQ<3>  SKX_EXT_B_BGA1  I172

M_K_DQ<4>       @BASEBOARD_FAB2_LIB.BASEBOARD_FAB2(SCH_1):M_K_DQ<4>
  J1B1   148  DQ<5>  SCONN288_H44441004_PIP  I111
  J9M1     3  DQ<4>  SCONN288_H44441003_PIP  I14
  U2D1   CL84  DDR3_DQ<4>  SKX_EXT_B_BGA1  I172

M_K_DQ<5>       @BASEBOARD_FAB2_LIB.BASEBOARD_FAB2(SCH_1):M_K_DQ<5>
  J1B1     3  DQ<4>  SCONN288_H44441004_PIP  I111
  J9M1   148  DQ<5>  SCONN288_H44441003_PIP  I14
  U2D1   CL86  DDR3_DQ<5>  SKX_EXT_B_BGA1  I172

M_K_DQ<6>       @BASEBOARD_FAB2_LIB.BASEBOARD_FAB2(SCH_1):M_K_DQ<6>
  J1B1   155  DQ<7>  SCONN288_H44441004_PIP  I111
  J9M1    10  DQ<6>  SCONN288_H44441003_PIP  I14
  U2D1   CW86  DDR3_DQ<6>  SKX_EXT_B_BGA1  I172

M_K_DQ<7>       @BASEBOARD_FAB2_LIB.BASEBOARD_FAB2(SCH_1):M_K_DQ<7>
  J1B1    10  DQ<6>  SCONN288_H44441004_PIP  I111
  J9M1   155  DQ<7>  SCONN288_H44441003_PIP  I14
  U2D1   CW84  DDR3_DQ<7>  SKX_EXT_B_BGA1  I172

M_K_DQ<8>       @BASEBOARD_FAB2_LIB.BASEBOARD_FAB2(SCH_1):M_K_DQ<8>
  J1B1   161  DQ<9>  SCONN288_H44441004_PIP  I111
  J9M1    16  DQ<8>  SCONN288_H44441003_PIP  I14
  U2D1   DG84  DDR3_DQ<8>  SKX_EXT_B_BGA1  I172

M_K_DQ<9>       @BASEBOARD_FAB2_LIB.BASEBOARD_FAB2(SCH_1):M_K_DQ<9>
  J1B1    16  DQ<8>  SCONN288_H44441004_PIP  I111
  J9M1   161  DQ<9>  SCONN288_H44441003_PIP  I14
  U2D1   DH85  DDR3_DQ<9>  SKX_EXT_B_BGA1  I172

M_K_DQ<10>      @BASEBOARD_FAB2_LIB.BASEBOARD_FAB2(SCH_1):M_K_DQ<10>
  J1B1   168  DQ<11>  SCONN288_H44441004_PIP  I111
  J9M1    23  DQ<10>  SCONN288_H44441003_PIP  I14
  U2D1   DV83  DDR3_DQ<10>  SKX_EXT_B_BGA1  I172

M_K_DQ<11>      @BASEBOARD_FAB2_LIB.BASEBOARD_FAB2(SCH_1):M_K_DQ<11>
  J1B1    23  DQ<10>  SCONN288_H44441004_PIP  I111
  J9M1   168  DQ<11>  SCONN288_H44441003_PIP  I14
  U2D1   DY83  DDR3_DQ<11>  SKX_EXT_B_BGA1  I172

M_K_DQ<12>      @BASEBOARD_FAB2_LIB.BASEBOARD_FAB2(SCH_1):M_K_DQ<12>
  J1B1   159  DQ<13>  SCONN288_H44441004_PIP  I111
  J9M1    14  DQ<12>  SCONN288_H44441003_PIP  I14
  U2D1   DD85  DDR3_DQ<12>  SKX_EXT_B_BGA1  I172

M_K_DQ<13>      @BASEBOARD_FAB2_LIB.BASEBOARD_FAB2(SCH_1):M_K_DQ<13>
  J1B1    14  DQ<12>  SCONN288_H44441004_PIP  I111
  J9M1   159  DQ<13>  SCONN288_H44441003_PIP  I14
  U2D1   DE84  DDR3_DQ<13>  SKX_EXT_B_BGA1  I172

M_K_DQ<14>      @BASEBOARD_FAB2_LIB.BASEBOARD_FAB2(SCH_1):M_K_DQ<14>
  J1B1   166  DQ<15>  SCONN288_H44441004_PIP  I111
  J9M1    21  DQ<14>  SCONN288_H44441003_PIP  I14
  U2D1   DR84  DDR3_DQ<14>  SKX_EXT_B_BGA1  I172

M_K_DQ<15>      @BASEBOARD_FAB2_LIB.BASEBOARD_FAB2(SCH_1):M_K_DQ<15>
  J1B1    21  DQ<14>  SCONN288_H44441004_PIP  I111
  J9M1   166  DQ<15>  SCONN288_H44441003_PIP  I14
  U2D1   DV85  DDR3_DQ<15>  SKX_EXT_B_BGA1  I172

M_K_DQ<16>      @BASEBOARD_FAB2_LIB.BASEBOARD_FAB2(SCH_1):M_K_DQ<16>
  J1B1   172  DQ<17>  SCONN288_H44441004_PIP  I111
  J9M1    27  DQ<16>  SCONN288_H44441003_PIP  I14
  U2D1   DM79  DDR3_DQ<16>  SKX_EXT_B_BGA1  I172

M_K_DQ<17>      @BASEBOARD_FAB2_LIB.BASEBOARD_FAB2(SCH_1):M_K_DQ<17>
  J1B1    27  DQ<16>  SCONN288_H44441004_PIP  I111
  J9M1   172  DQ<17>  SCONN288_H44441003_PIP  I14
  U2D1   DK81  DDR3_DQ<17>  SKX_EXT_B_BGA1  I172

M_K_DQ<18>      @BASEBOARD_FAB2_LIB.BASEBOARD_FAB2(SCH_1):M_K_DQ<18>
  J1B1   179  DQ<19>  SCONN288_H44441004_PIP  I111
  J9M1    34  DQ<18>  SCONN288_H44441003_PIP  I14
  U2D1   DT81  DDR3_DQ<18>  SKX_EXT_B_BGA1  I172

M_K_DQ<19>      @BASEBOARD_FAB2_LIB.BASEBOARD_FAB2(SCH_1):M_K_DQ<19>
  J1B1    34  DQ<18>  SCONN288_H44441004_PIP  I111
  J9M1   179  DQ<19>  SCONN288_H44441003_PIP  I14
  U2D1   DR82  DDR3_DQ<19>  SKX_EXT_B_BGA1  I172

M_K_DQ<20>      @BASEBOARD_FAB2_LIB.BASEBOARD_FAB2(SCH_1):M_K_DQ<20>
  J1B1   170  DQ<21>  SCONN288_H44441004_PIP  I111
  J9M1    25  DQ<20>  SCONN288_H44441003_PIP  I14
  U2D1   DK79  DDR3_DQ<20>  SKX_EXT_B_BGA1  I172

M_K_DQ<21>      @BASEBOARD_FAB2_LIB.BASEBOARD_FAB2(SCH_1):M_K_DQ<21>
  J1B1    25  DQ<20>  SCONN288_H44441004_PIP  I111
  J9M1   170  DQ<21>  SCONN288_H44441003_PIP  I14
  U2D1   DJ80  DDR3_DQ<21>  SKX_EXT_B_BGA1  I172

M_K_DQ<22>      @BASEBOARD_FAB2_LIB.BASEBOARD_FAB2(SCH_1):M_K_DQ<22>
  J1B1   177  DQ<23>  SCONN288_H44441004_PIP  I111
  J9M1    32  DQ<22>  SCONN288_H44441003_PIP  I14
  U2D1   DR80  DDR3_DQ<22>  SKX_EXT_B_BGA1  I172

M_K_DQ<23>      @BASEBOARD_FAB2_LIB.BASEBOARD_FAB2(SCH_1):M_K_DQ<23>
  J1B1    32  DQ<22>  SCONN288_H44441004_PIP  I111
  J9M1   177  DQ<23>  SCONN288_H44441003_PIP  I14
  U2D1   DN82  DDR3_DQ<23>  SKX_EXT_B_BGA1  I172

M_K_DQ<24>      @BASEBOARD_FAB2_LIB.BASEBOARD_FAB2(SCH_1):M_K_DQ<24>
  J1B1   183  DQ<25>  SCONN288_H44441004_PIP  I111
  J9M1    38  DQ<24>  SCONN288_H44441003_PIP  I14
  U2D1   DN76  DDR3_DQ<24>  SKX_EXT_B_BGA1  I172

M_K_DQ<25>      @BASEBOARD_FAB2_LIB.BASEBOARD_FAB2(SCH_1):M_K_DQ<25>
  J1B1    38  DQ<24>  SCONN288_H44441004_PIP  I111
  J9M1   183  DQ<25>  SCONN288_H44441003_PIP  I14
  U2D1   DU76  DDR3_DQ<25>  SKX_EXT_B_BGA1  I172

M_K_DQ<26>      @BASEBOARD_FAB2_LIB.BASEBOARD_FAB2(SCH_1):M_K_DQ<26>
  J1B1   190  DQ<27>  SCONN288_H44441004_PIP  I111
  J9M1    45  DQ<26>  SCONN288_H44441003_PIP  I14
  U2D1   DP73  DDR3_DQ<26>  SKX_EXT_B_BGA1  I172

M_K_DQ<27>      @BASEBOARD_FAB2_LIB.BASEBOARD_FAB2(SCH_1):M_K_DQ<27>
  J1B1    45  DQ<26>  SCONN288_H44441004_PIP  I111
  J9M1   190  DQ<27>  SCONN288_H44441003_PIP  I14
  U2D1   DT73  DDR3_DQ<27>  SKX_EXT_B_BGA1  I172

M_K_DQ<28>      @BASEBOARD_FAB2_LIB.BASEBOARD_FAB2(SCH_1):M_K_DQ<28>
  J1B1   181  DQ<29>  SCONN288_H44441004_PIP  I111
  J9M1    36  DQ<28>  SCONN288_H44441003_PIP  I14
  U2D1   DP77  DDR3_DQ<28>  SKX_EXT_B_BGA1  I172

M_K_DQ<29>      @BASEBOARD_FAB2_LIB.BASEBOARD_FAB2(SCH_1):M_K_DQ<29>
  J1B1    36  DQ<28>  SCONN288_H44441004_PIP  I111
  J9M1   181  DQ<29>  SCONN288_H44441003_PIP  I14
  U2D1   DT77  DDR3_DQ<29>  SKX_EXT_B_BGA1  I172

M_K_DQ<30>      @BASEBOARD_FAB2_LIB.BASEBOARD_FAB2(SCH_1):M_K_DQ<30>
  J1B1   188  DQ<31>  SCONN288_H44441004_PIP  I111
  J9M1    43  DQ<30>  SCONN288_H44441003_PIP  I14
  U2D1   DN74  DDR3_DQ<30>  SKX_EXT_B_BGA1  I172

M_K_DQ<31>      @BASEBOARD_FAB2_LIB.BASEBOARD_FAB2(SCH_1):M_K_DQ<31>
  J1B1    43  DQ<30>  SCONN288_H44441004_PIP  I111
  J9M1   188  DQ<31>  SCONN288_H44441003_PIP  I14
  U2D1   DU74  DDR3_DQ<31>  SKX_EXT_B_BGA1  I172

M_K_DQ<32>      @BASEBOARD_FAB2_LIB.BASEBOARD_FAB2(SCH_1):M_K_DQ<32>
  J1B1   242  DQ<33>  SCONN288_H44441004_PIP  I111
  J9M1    97  DQ<32>  SCONN288_H44441003_PIP  I14
  U2D1   EC40  DDR3_DQ<32>  SKX_EXT_B_BGA1  I172

M_K_DQ<33>      @BASEBOARD_FAB2_LIB.BASEBOARD_FAB2(SCH_1):M_K_DQ<33>
  J1B1    97  DQ<32>  SCONN288_H44441004_PIP  I111
  J9M1   242  DQ<33>  SCONN288_H44441003_PIP  I14
  U2D1   ED39  DDR3_DQ<33>  SKX_EXT_B_BGA1  I172

M_K_DQ<34>      @BASEBOARD_FAB2_LIB.BASEBOARD_FAB2(SCH_1):M_K_DQ<34>
  J1B1   249  DQ<35>  SCONN288_H44441004_PIP  I111
  J9M1   104  DQ<34>  SCONN288_H44441003_PIP  I14
  U2D1   EA36  DDR3_DQ<34>  SKX_EXT_B_BGA1  I172

M_K_DQ<35>      @BASEBOARD_FAB2_LIB.BASEBOARD_FAB2(SCH_1):M_K_DQ<35>
  J1B1   104  DQ<34>  SCONN288_H44441004_PIP  I111
  J9M1   249  DQ<35>  SCONN288_H44441003_PIP  I14
  U2D1   EC36  DDR3_DQ<35>  SKX_EXT_B_BGA1  I172

M_K_DQ<36>      @BASEBOARD_FAB2_LIB.BASEBOARD_FAB2(SCH_1):M_K_DQ<36>
  J1B1   240  DQ<37>  SCONN288_H44441004_PIP  I111
  J9M1    95  DQ<36>  SCONN288_H44441003_PIP  I14
  U2D1   DY39  DDR3_DQ<36>  SKX_EXT_B_BGA1  I172

M_K_DQ<37>      @BASEBOARD_FAB2_LIB.BASEBOARD_FAB2(SCH_1):M_K_DQ<37>
  J1B1    95  DQ<36>  SCONN288_H44441004_PIP  I111
  J9M1   240  DQ<37>  SCONN288_H44441003_PIP  I14
  U2D1   EA40  DDR3_DQ<37>  SKX_EXT_B_BGA1  I172

M_K_DQ<38>      @BASEBOARD_FAB2_LIB.BASEBOARD_FAB2(SCH_1):M_K_DQ<38>
  J1B1   247  DQ<39>  SCONN288_H44441004_PIP  I111
  J9M1   102  DQ<38>  SCONN288_H44441003_PIP  I14
  U2D1   DY37  DDR3_DQ<38>  SKX_EXT_B_BGA1  I172

M_K_DQ<39>      @BASEBOARD_FAB2_LIB.BASEBOARD_FAB2(SCH_1):M_K_DQ<39>
  J1B1   102  DQ<38>  SCONN288_H44441004_PIP  I111
  J9M1   247  DQ<39>  SCONN288_H44441003_PIP  I14
  U2D1   ED37  DDR3_DQ<39>  SKX_EXT_B_BGA1  I172

M_K_DQ<40>      @BASEBOARD_FAB2_LIB.BASEBOARD_FAB2(SCH_1):M_K_DQ<40>
  J1B1   253  DQ<41>  SCONN288_H44441004_PIP  I111
  J9M1   108  DQ<40>  SCONN288_H44441003_PIP  I14
  U2D1   DN36  DDR3_DQ<40>  SKX_EXT_B_BGA1  I172

M_K_DQ<41>      @BASEBOARD_FAB2_LIB.BASEBOARD_FAB2(SCH_1):M_K_DQ<41>
  J1B1   108  DQ<40>  SCONN288_H44441004_PIP  I111
  J9M1   253  DQ<41>  SCONN288_H44441003_PIP  I14
  U2D1   DU36  DDR3_DQ<41>  SKX_EXT_B_BGA1  I172

M_K_DQ<42>      @BASEBOARD_FAB2_LIB.BASEBOARD_FAB2(SCH_1):M_K_DQ<42>
  J1B1   260  DQ<43>  SCONN288_H44441004_PIP  I111
  J9M1   115  DQ<42>  SCONN288_H44441003_PIP  I14
  U2D1   DP33  DDR3_DQ<42>  SKX_EXT_B_BGA1  I172

M_K_DQ<43>      @BASEBOARD_FAB2_LIB.BASEBOARD_FAB2(SCH_1):M_K_DQ<43>
  J1B1   115  DQ<42>  SCONN288_H44441004_PIP  I111
  J9M1   260  DQ<43>  SCONN288_H44441003_PIP  I14
  U2D1   DT33  DDR3_DQ<43>  SKX_EXT_B_BGA1  I172

M_K_DQ<44>      @BASEBOARD_FAB2_LIB.BASEBOARD_FAB2(SCH_1):M_K_DQ<44>
  J1B1   251  DQ<45>  SCONN288_H44441004_PIP  I111
  J9M1   106  DQ<44>  SCONN288_H44441003_PIP  I14
  U2D1   DP37  DDR3_DQ<44>  SKX_EXT_B_BGA1  I172

M_K_DQ<45>      @BASEBOARD_FAB2_LIB.BASEBOARD_FAB2(SCH_1):M_K_DQ<45>
  J1B1   106  DQ<44>  SCONN288_H44441004_PIP  I111
  J9M1   251  DQ<45>  SCONN288_H44441003_PIP  I14
  U2D1   DT37  DDR3_DQ<45>  SKX_EXT_B_BGA1  I172

M_K_DQ<46>      @BASEBOARD_FAB2_LIB.BASEBOARD_FAB2(SCH_1):M_K_DQ<46>
  J1B1   258  DQ<47>  SCONN288_H44441004_PIP  I111
  J9M1   113  DQ<46>  SCONN288_H44441003_PIP  I14
  U2D1   DN34  DDR3_DQ<46>  SKX_EXT_B_BGA1  I172

M_K_DQ<47>      @BASEBOARD_FAB2_LIB.BASEBOARD_FAB2(SCH_1):M_K_DQ<47>
  J1B1   113  DQ<46>  SCONN288_H44441004_PIP  I111
  J9M1   258  DQ<47>  SCONN288_H44441003_PIP  I14
  U2D1   DU34  DDR3_DQ<47>  SKX_EXT_B_BGA1  I172

M_K_DQ<48>      @BASEBOARD_FAB2_LIB.BASEBOARD_FAB2(SCH_1):M_K_DQ<48>
  J1B1   264  DQ<49>  SCONN288_H44441004_PIP  I111
  J9M1   119  DQ<48>  SCONN288_H44441003_PIP  I14
  U2D1   DN30  DDR3_DQ<48>  SKX_EXT_B_BGA1  I172

M_K_DQ<49>      @BASEBOARD_FAB2_LIB.BASEBOARD_FAB2(SCH_1):M_K_DQ<49>
  J1B1   119  DQ<48>  SCONN288_H44441004_PIP  I111
  J9M1   264  DQ<49>  SCONN288_H44441003_PIP  I14
  U2D1   DU30  DDR3_DQ<49>  SKX_EXT_B_BGA1  I172

M_K_DQ<50>      @BASEBOARD_FAB2_LIB.BASEBOARD_FAB2(SCH_1):M_K_DQ<50>
  J1B1   271  DQ<51>  SCONN288_H44441004_PIP  I111
  J9M1   126  DQ<50>  SCONN288_H44441003_PIP  I14
  U2D1   DP27  DDR3_DQ<50>  SKX_EXT_B_BGA1  I172

M_K_DQ<51>      @BASEBOARD_FAB2_LIB.BASEBOARD_FAB2(SCH_1):M_K_DQ<51>
  J1B1   126  DQ<50>  SCONN288_H44441004_PIP  I111
  J9M1   271  DQ<51>  SCONN288_H44441003_PIP  I14
  U2D1   DT27  DDR3_DQ<51>  SKX_EXT_B_BGA1  I172

M_K_DQ<52>      @BASEBOARD_FAB2_LIB.BASEBOARD_FAB2(SCH_1):M_K_DQ<52>
  J1B1   262  DQ<53>  SCONN288_H44441004_PIP  I111
  J9M1   117  DQ<52>  SCONN288_H44441003_PIP  I14
  U2D1   DP31  DDR3_DQ<52>  SKX_EXT_B_BGA1  I172

M_K_DQ<53>      @BASEBOARD_FAB2_LIB.BASEBOARD_FAB2(SCH_1):M_K_DQ<53>
  J1B1   117  DQ<52>  SCONN288_H44441004_PIP  I111
  J9M1   262  DQ<53>  SCONN288_H44441003_PIP  I14
  U2D1   DT31  DDR3_DQ<53>  SKX_EXT_B_BGA1  I172

M_K_DQ<54>      @BASEBOARD_FAB2_LIB.BASEBOARD_FAB2(SCH_1):M_K_DQ<54>
  J1B1   269  DQ<55>  SCONN288_H44441004_PIP  I111
  J9M1   124  DQ<54>  SCONN288_H44441003_PIP  I14
  U2D1   DN28  DDR3_DQ<54>  SKX_EXT_B_BGA1  I172

M_K_DQ<55>      @BASEBOARD_FAB2_LIB.BASEBOARD_FAB2(SCH_1):M_K_DQ<55>
  J1B1   124  DQ<54>  SCONN288_H44441004_PIP  I111
  J9M1   269  DQ<55>  SCONN288_H44441003_PIP  I14
  U2D1   DU28  DDR3_DQ<55>  SKX_EXT_B_BGA1  I172

M_K_DQ<56>      @BASEBOARD_FAB2_LIB.BASEBOARD_FAB2(SCH_1):M_K_DQ<56>
  J1B1   275  DQ<57>  SCONN288_H44441004_PIP  I111
  J9M1   130  DQ<56>  SCONN288_H44441003_PIP  I14
  U2D1   DN24  DDR3_DQ<56>  SKX_EXT_B_BGA1  I172

M_K_DQ<57>      @BASEBOARD_FAB2_LIB.BASEBOARD_FAB2(SCH_1):M_K_DQ<57>
  J1B1   130  DQ<56>  SCONN288_H44441004_PIP  I111
  J9M1   275  DQ<57>  SCONN288_H44441003_PIP  I14
  U2D1   DU24  DDR3_DQ<57>  SKX_EXT_B_BGA1  I172

M_K_DQ<58>      @BASEBOARD_FAB2_LIB.BASEBOARD_FAB2(SCH_1):M_K_DQ<58>
  J1B1   282  DQ<59>  SCONN288_H44441004_PIP  I111
  J9M1   137  DQ<58>  SCONN288_H44441003_PIP  I14
  U2D1   DY21  DDR3_DQ<58>  SKX_EXT_B_BGA1  I172

M_K_DQ<59>      @BASEBOARD_FAB2_LIB.BASEBOARD_FAB2(SCH_1):M_K_DQ<59>
  J1B1   137  DQ<58>  SCONN288_H44441004_PIP  I111
  J9M1   282  DQ<59>  SCONN288_H44441003_PIP  I14
  U2D1   EB21  DDR3_DQ<59>  SKX_EXT_B_BGA1  I172

M_K_DQ<60>      @BASEBOARD_FAB2_LIB.BASEBOARD_FAB2(SCH_1):M_K_DQ<60>
  J1B1   273  DQ<61>  SCONN288_H44441004_PIP  I111
  J9M1   128  DQ<60>  SCONN288_H44441003_PIP  I14
  U2D1   DP25  DDR3_DQ<60>  SKX_EXT_B_BGA1  I172

M_K_DQ<61>      @BASEBOARD_FAB2_LIB.BASEBOARD_FAB2(SCH_1):M_K_DQ<61>
  J1B1   128  DQ<60>  SCONN288_H44441004_PIP  I111
  J9M1   273  DQ<61>  SCONN288_H44441003_PIP  I14
  U2D1   DT25  DDR3_DQ<61>  SKX_EXT_B_BGA1  I172

M_K_DQ<62>      @BASEBOARD_FAB2_LIB.BASEBOARD_FAB2(SCH_1):M_K_DQ<62>
  J1B1   280  DQ<63>  SCONN288_H44441004_PIP  I111
  J9M1   135  DQ<62>  SCONN288_H44441003_PIP  I14
  U2D1   EC22  DDR3_DQ<62>  SKX_EXT_B_BGA1  I172

M_K_DQ<63>      @BASEBOARD_FAB2_LIB.BASEBOARD_FAB2(SCH_1):M_K_DQ<63>
  J1B1   135  DQ<62>  SCONN288_H44441004_PIP  I111
  J9M1   280  DQ<63>  SCONN288_H44441003_PIP  I14
  U2D1   DW22  DDR3_DQ<63>  SKX_EXT_B_BGA1  I172

M_K_DQS_DN<0>   @BASEBOARD_FAB2_LIB.BASEBOARD_FAB2(SCH_1):M_K_DQS_DN<0>
  J1B1   152  DQS0N  SCONN288_H44441004_PIP  I66
  J9M1   152  DQS0N  SCONN288_H44441003_PIP  I102
  U2D1   CU84  DDR3_DQS_DN<0>  SKX_EXT_B_BGA1  I172

M_K_DQS_DN<1>   @BASEBOARD_FAB2_LIB.BASEBOARD_FAB2(SCH_1):M_K_DQS_DN<1>
  J1B1   163  DQS1N  SCONN288_H44441004_PIP  I66
  J9M1   163  DQS1N  SCONN288_H44441003_PIP  I102
  U2D1   DN84  DDR3_DQS_DN<1>  SKX_EXT_B_BGA1  I172

M_K_DQS_DN<2>   @BASEBOARD_FAB2_LIB.BASEBOARD_FAB2(SCH_1):M_K_DQS_DN<2>
  J1B1   174  DQS2N  SCONN288_H44441004_PIP  I66
  J9M1   174  DQS2N  SCONN288_H44441003_PIP  I102
  U2D1   DL82  DDR3_DQS_DN<2>  SKX_EXT_B_BGA1  I172

M_K_DQS_DN<3>   @BASEBOARD_FAB2_LIB.BASEBOARD_FAB2(SCH_1):M_K_DQS_DN<3>
  J1B1   185  DQS3N  SCONN288_H44441004_PIP  I66
  J9M1   185  DQS3N  SCONN288_H44441003_PIP  I102
  U2D1   DV75  DDR3_DQS_DN<3>  SKX_EXT_B_BGA1  I172

M_K_DQS_DN<4>   @BASEBOARD_FAB2_LIB.BASEBOARD_FAB2(SCH_1):M_K_DQS_DN<4>
  J1B1   244  DQS4N  SCONN288_H44441004_PIP  I66
  J9M1   244  DQS4N  SCONN288_H44441003_PIP  I102
  U2D1   EE38  DDR3_DQS_DN<4>  SKX_EXT_B_BGA1  I172

M_K_DQS_DN<5>   @BASEBOARD_FAB2_LIB.BASEBOARD_FAB2(SCH_1):M_K_DQS_DN<5>
  J1B1   255  DQS5N  SCONN288_H44441004_PIP  I66
  J9M1   255  DQS5N  SCONN288_H44441003_PIP  I102
  U2D1   DV35  DDR3_DQS_DN<5>  SKX_EXT_B_BGA1  I172

M_K_DQS_DN<6>   @BASEBOARD_FAB2_LIB.BASEBOARD_FAB2(SCH_1):M_K_DQS_DN<6>
  J1B1   266  DQS6N  SCONN288_H44441004_PIP  I66
  J9M1   266  DQS6N  SCONN288_H44441003_PIP  I102
  U2D1   DV29  DDR3_DQS_DN<6>  SKX_EXT_B_BGA1  I172

M_K_DQS_DN<7>   @BASEBOARD_FAB2_LIB.BASEBOARD_FAB2(SCH_1):M_K_DQS_DN<7>
  J1B1   277  DQS7N  SCONN288_H44441004_PIP  I66
  J9M1   277  DQS7N  SCONN288_H44441003_PIP  I102
  U2D1   DV23  DDR3_DQS_DN<7>  SKX_EXT_B_BGA1  I172

M_K_DQS_DN<8>   @BASEBOARD_FAB2_LIB.BASEBOARD_FAB2(SCH_1):M_K_DQS_DN<8>
  J1B1   196  DQS8N  SCONN288_H44441004_PIP  I66
  J9M1   196  DQS8N  SCONN288_H44441003_PIP  I102
  U2D1   DF67  DDR3_DQS_DN<8>  SKX_EXT_B_BGA1  I172

M_K_DQS_DN<9>   @BASEBOARD_FAB2_LIB.BASEBOARD_FAB2(SCH_1):M_K_DQS_DN<9>
  J1B1     8  DQS9N  SCONN288_H44441004_PIP  I66
  J9M1     8  DQS9N  SCONN288_H44441003_PIP  I102
  U2D1   CR84  DDR3_DQS_DN<9>  SKX_EXT_B_BGA1  I172

M_K_DQS_DN<10>   @BASEBOARD_FAB2_LIB.BASEBOARD_FAB2(SCH_1):M_K_DQS_DN<10>
  J1B1    19  DQS10N  SCONN288_H44441004_PIP  I66
  J9M1    19  DQS10N  SCONN288_H44441003_PIP  I102
  U2D1   DM85  DDR3_DQS_DN<10>  SKX_EXT_B_BGA1  I172

M_K_DQS_DN<11>   @BASEBOARD_FAB2_LIB.BASEBOARD_FAB2(SCH_1):M_K_DQS_DN<11>
  J1B1    30  DQS11N  SCONN288_H44441004_PIP  I66
  J9M1    30  DQS11N  SCONN288_H44441003_PIP  I102
  U2D1   DN80  DDR3_DQS_DN<11>  SKX_EXT_B_BGA1  I172

M_K_DQS_DN<12>   @BASEBOARD_FAB2_LIB.BASEBOARD_FAB2(SCH_1):M_K_DQS_DN<12>
  J1B1    41  DQS12N  SCONN288_H44441004_PIP  I66
  J9M1    41  DQS12N  SCONN288_H44441003_PIP  I102
  U2D1   DP75  DDR3_DQS_DN<12>  SKX_EXT_B_BGA1  I172

M_K_DQS_DN<13>   @BASEBOARD_FAB2_LIB.BASEBOARD_FAB2(SCH_1):M_K_DQS_DN<13>
  J1B1   100  DQS13N  SCONN288_H44441004_PIP  I66
  J9M1   100  DQS13N  SCONN288_H44441003_PIP  I102
  U2D1   EA38  DDR3_DQS_DN<13>  SKX_EXT_B_BGA1  I172

M_K_DQS_DN<14>   @BASEBOARD_FAB2_LIB.BASEBOARD_FAB2(SCH_1):M_K_DQS_DN<14>
  J1B1   111  DQS14N  SCONN288_H44441004_PIP  I66
  J9M1   111  DQS14N  SCONN288_H44441003_PIP  I102
  U2D1   DP35  DDR3_DQS_DN<14>  SKX_EXT_B_BGA1  I172

M_K_DQS_DN<15>   @BASEBOARD_FAB2_LIB.BASEBOARD_FAB2(SCH_1):M_K_DQS_DN<15>
  J1B1   122  DQS15N  SCONN288_H44441004_PIP  I66
  J9M1   122  DQS15N  SCONN288_H44441003_PIP  I102
  U2D1   DM29  DDR3_DQS_DN<15>  SKX_EXT_B_BGA1  I172

M_K_DQS_DN<16>   @BASEBOARD_FAB2_LIB.BASEBOARD_FAB2(SCH_1):M_K_DQS_DN<16>
  J1B1   133  DQS16N  SCONN288_H44441004_PIP  I66
  J9M1   133  DQS16N  SCONN288_H44441003_PIP  I102
  U2D1   DM23  DDR3_DQS_DN<16>  SKX_EXT_B_BGA1  I172

M_K_DQS_DN<17>   @BASEBOARD_FAB2_LIB.BASEBOARD_FAB2(SCH_1):M_K_DQS_DN<17>
  J1B1    52  DQS17N  SCONN288_H44441004_PIP  I66
  J9M1    52  DQS17N  SCONN288_H44441003_PIP  I102
  U2D1   DB67  DDR3_DQS_DN<17>  SKX_EXT_B_BGA1  I172

M_K_DQS_DP<0>   @BASEBOARD_FAB2_LIB.BASEBOARD_FAB2(SCH_1):M_K_DQS_DP<0>
  J1B1   153  DQS0P  SCONN288_H44441004_PIP  I66
  J9M1   153  DQS0P  SCONN288_H44441003_PIP  I102
  U2D1   CV85  DDR3_DQS_DP<0>  SKX_EXT_B_BGA1  I172

M_K_DQS_DP<1>   @BASEBOARD_FAB2_LIB.BASEBOARD_FAB2(SCH_1):M_K_DQS_DP<1>
  J1B1   164  DQS1P  SCONN288_H44441004_PIP  I66
  J9M1   164  DQS1P  SCONN288_H44441003_PIP  I102
  U2D1   DP85  DDR3_DQS_DP<1>  SKX_EXT_B_BGA1  I172

M_K_DQS_DP<2>   @BASEBOARD_FAB2_LIB.BASEBOARD_FAB2(SCH_1):M_K_DQS_DP<2>
  J1B1   175  DQS2P  SCONN288_H44441004_PIP  I66
  J9M1   175  DQS2P  SCONN288_H44441003_PIP  I102
  U2D1   DM81  DDR3_DQS_DP<2>  SKX_EXT_B_BGA1  I172

M_K_DQS_DP<3>   @BASEBOARD_FAB2_LIB.BASEBOARD_FAB2(SCH_1):M_K_DQS_DP<3>
  J1B1   186  DQS3P  SCONN288_H44441004_PIP  I66
  J9M1   186  DQS3P  SCONN288_H44441003_PIP  I102
  U2D1   DT75  DDR3_DQS_DP<3>  SKX_EXT_B_BGA1  I172

M_K_DQS_DP<4>   @BASEBOARD_FAB2_LIB.BASEBOARD_FAB2(SCH_1):M_K_DQS_DP<4>
  J1B1   245  DQS4P  SCONN288_H44441004_PIP  I66
  J9M1   245  DQS4P  SCONN288_H44441003_PIP  I102
  U2D1   EC38  DDR3_DQS_DP<4>  SKX_EXT_B_BGA1  I172

M_K_DQS_DP<5>   @BASEBOARD_FAB2_LIB.BASEBOARD_FAB2(SCH_1):M_K_DQS_DP<5>
  J1B1   256  DQS5P  SCONN288_H44441004_PIP  I66
  J9M1   256  DQS5P  SCONN288_H44441003_PIP  I102
  U2D1   DT35  DDR3_DQS_DP<5>  SKX_EXT_B_BGA1  I172

M_K_DQS_DP<6>   @BASEBOARD_FAB2_LIB.BASEBOARD_FAB2(SCH_1):M_K_DQS_DP<6>
  J1B1   267  DQS6P  SCONN288_H44441004_PIP  I66
  J9M1   267  DQS6P  SCONN288_H44441003_PIP  I102
  U2D1   DT29  DDR3_DQS_DP<6>  SKX_EXT_B_BGA1  I172

M_K_DQS_DP<7>   @BASEBOARD_FAB2_LIB.BASEBOARD_FAB2(SCH_1):M_K_DQS_DP<7>
  J1B1   278  DQS7P  SCONN288_H44441004_PIP  I66
  J9M1   278  DQS7P  SCONN288_H44441003_PIP  I102
  U2D1   DT23  DDR3_DQS_DP<7>  SKX_EXT_B_BGA1  I172

M_K_DQS_DP<8>   @BASEBOARD_FAB2_LIB.BASEBOARD_FAB2(SCH_1):M_K_DQS_DP<8>
  J1B1   197  DQS8P  SCONN288_H44441004_PIP  I66
  J9M1   197  DQS8P  SCONN288_H44441003_PIP  I102
  U2D1   DD67  DDR3_DQS_DP<8>  SKX_EXT_B_BGA1  I172

M_K_DQS_DP<9>   @BASEBOARD_FAB2_LIB.BASEBOARD_FAB2(SCH_1):M_K_DQS_DP<9>
  J1B1     7  DQS9P  SCONN288_H44441004_PIP  I66
  J9M1     7  DQS9P  SCONN288_H44441003_PIP  I102
  U2D1   CP85  DDR3_DQS_DP<9>  SKX_EXT_B_BGA1  I172

M_K_DQS_DP<10>   @BASEBOARD_FAB2_LIB.BASEBOARD_FAB2(SCH_1):M_K_DQS_DP<10>
  J1B1    18  DQS10P  SCONN288_H44441004_PIP  I66
  J9M1    18  DQS10P  SCONN288_H44441003_PIP  I102
  U2D1   DL84  DDR3_DQS_DP<10>  SKX_EXT_B_BGA1  I172

M_K_DQS_DP<11>   @BASEBOARD_FAB2_LIB.BASEBOARD_FAB2(SCH_1):M_K_DQS_DP<11>
  J1B1    29  DQS11P  SCONN288_H44441004_PIP  I66
  J9M1    29  DQS11P  SCONN288_H44441003_PIP  I102
  U2D1   DP79  DDR3_DQS_DP<11>  SKX_EXT_B_BGA1  I172

M_K_DQS_DP<12>   @BASEBOARD_FAB2_LIB.BASEBOARD_FAB2(SCH_1):M_K_DQS_DP<12>
  J1B1    40  DQS12P  SCONN288_H44441004_PIP  I66
  J9M1    40  DQS12P  SCONN288_H44441003_PIP  I102
  U2D1   DM75  DDR3_DQS_DP<12>  SKX_EXT_B_BGA1  I172

M_K_DQS_DP<13>   @BASEBOARD_FAB2_LIB.BASEBOARD_FAB2(SCH_1):M_K_DQS_DP<13>
  J1B1    99  DQS13P  SCONN288_H44441004_PIP  I66
  J9M1    99  DQS13P  SCONN288_H44441003_PIP  I102
  U2D1   DW38  DDR3_DQS_DP<13>  SKX_EXT_B_BGA1  I172

M_K_DQS_DP<14>   @BASEBOARD_FAB2_LIB.BASEBOARD_FAB2(SCH_1):M_K_DQS_DP<14>
  J1B1   110  DQS14P  SCONN288_H44441004_PIP  I66
  J9M1   110  DQS14P  SCONN288_H44441003_PIP  I102
  U2D1   DM35  DDR3_DQS_DP<14>  SKX_EXT_B_BGA1  I172

M_K_DQS_DP<15>   @BASEBOARD_FAB2_LIB.BASEBOARD_FAB2(SCH_1):M_K_DQS_DP<15>
  J1B1   121  DQS15P  SCONN288_H44441004_PIP  I66
  J9M1   121  DQS15P  SCONN288_H44441003_PIP  I102
  U2D1   DP29  DDR3_DQS_DP<15>  SKX_EXT_B_BGA1  I172

M_K_DQS_DP<16>   @BASEBOARD_FAB2_LIB.BASEBOARD_FAB2(SCH_1):M_K_DQS_DP<16>
  J1B1   132  DQS16P  SCONN288_H44441004_PIP  I66
  J9M1   132  DQS16P  SCONN288_H44441003_PIP  I102
  U2D1   DP23  DDR3_DQS_DP<16>  SKX_EXT_B_BGA1  I172

M_K_DQS_DP<17>   @BASEBOARD_FAB2_LIB.BASEBOARD_FAB2(SCH_1):M_K_DQS_DP<17>
  J1B1    51  DQS17P  SCONN288_H44441004_PIP  I66
  J9M1    51  DQS17P  SCONN288_H44441003_PIP  I102
  U2D1   CY67  DDR3_DQS_DP<17>  SKX_EXT_B_BGA1  I172

M_K_ECC<0>      @BASEBOARD_FAB2_LIB.BASEBOARD_FAB2(SCH_1):M_K_ECC<0>
  J1B1   194  CB<1>  SCONN288_H44441004_PIP  I111
  J9M1    49  CB<0>  SCONN288_H44441003_PIP  I14
  U2D1   DA68  DDR3_ECC<0>  SKX_EXT_B_BGA1  I172

M_K_ECC<1>      @BASEBOARD_FAB2_LIB.BASEBOARD_FAB2(SCH_1):M_K_ECC<1>
  J1B1    49  CB<0>  SCONN288_H44441004_PIP  I111
  J9M1   194  CB<1>  SCONN288_H44441003_PIP  I14
  U2D1   DE68  DDR3_ECC<1>  SKX_EXT_B_BGA1  I172

M_K_ECC<2>      @BASEBOARD_FAB2_LIB.BASEBOARD_FAB2(SCH_1):M_K_ECC<2>
  J1B1   201  CB<3>  SCONN288_H44441004_PIP  I111
  J9M1    56  CB<2>  SCONN288_H44441003_PIP  I14
  U2D1   DB65  DDR3_ECC<2>  SKX_EXT_B_BGA1  I172

M_K_ECC<3>      @BASEBOARD_FAB2_LIB.BASEBOARD_FAB2(SCH_1):M_K_ECC<3>
  J1B1    56  CB<2>  SCONN288_H44441004_PIP  I111
  J9M1   201  CB<3>  SCONN288_H44441003_PIP  I14
  U2D1   DD65  DDR3_ECC<3>  SKX_EXT_B_BGA1  I172

M_K_ECC<4>      @BASEBOARD_FAB2_LIB.BASEBOARD_FAB2(SCH_1):M_K_ECC<4>
  J1B1   192  CB<5>  SCONN288_H44441004_PIP  I111
  J9M1    47  CB<4>  SCONN288_H44441003_PIP  I14
  U2D1   DB69  DDR3_ECC<4>  SKX_EXT_B_BGA1  I172

M_K_ECC<5>      @BASEBOARD_FAB2_LIB.BASEBOARD_FAB2(SCH_1):M_K_ECC<5>
  J1B1    47  CB<4>  SCONN288_H44441004_PIP  I111
  J9M1   192  CB<5>  SCONN288_H44441003_PIP  I14
  U2D1   DD69  DDR3_ECC<5>  SKX_EXT_B_BGA1  I172

M_K_ECC<6>      @BASEBOARD_FAB2_LIB.BASEBOARD_FAB2(SCH_1):M_K_ECC<6>
  J1B1   199  CB<7>  SCONN288_H44441004_PIP  I111
  J9M1    54  CB<6>  SCONN288_H44441003_PIP  I14
  U2D1   DA66  DDR3_ECC<6>  SKX_EXT_B_BGA1  I172

M_K_ECC<7>      @BASEBOARD_FAB2_LIB.BASEBOARD_FAB2(SCH_1):M_K_ECC<7>
  J1B1    54  CB<6>  SCONN288_H44441004_PIP  I111
  J9M1   199  CB<7>  SCONN288_H44441003_PIP  I14
  U2D1   DE66  DDR3_ECC<7>  SKX_EXT_B_BGA1  I172

M_K_MA<0>       @BASEBOARD_FAB2_LIB.BASEBOARD_FAB2(SCH_1):M_K_MA<0>
  J1B1    79     A0  SCONN288_H44441004_PIP  I111
  J9M1    79     A0  SCONN288_H44441003_PIP  I14
  U2D1   EB53  DDR3_MA<0>  SKX_EXT_B_BGA1  I172

M_K_MA<1>       @BASEBOARD_FAB2_LIB.BASEBOARD_FAB2(SCH_1):M_K_MA<1>
  J1B1    72     A1  SCONN288_H44441004_PIP  I111
  J9M1    72     A1  SCONN288_H44441003_PIP  I14
  U2D1   ED57  DDR3_MA<1>  SKX_EXT_B_BGA1  I172

M_K_MA<2>       @BASEBOARD_FAB2_LIB.BASEBOARD_FAB2(SCH_1):M_K_MA<2>
  J1B1   216     A2  SCONN288_H44441004_PIP  I111
  J9M1   216     A2  SCONN288_H44441003_PIP  I14
  U2D1   EE58  DDR3_MA<2>  SKX_EXT_B_BGA1  I172

M_K_MA<3>       @BASEBOARD_FAB2_LIB.BASEBOARD_FAB2(SCH_1):M_K_MA<3>
  J1B1    71     A3  SCONN288_H44441004_PIP  I111
  J9M1    71     A3  SCONN288_H44441003_PIP  I14
  U2D1   EB57  DDR3_MA<3>  SKX_EXT_B_BGA1  I172

M_K_MA<4>       @BASEBOARD_FAB2_LIB.BASEBOARD_FAB2(SCH_1):M_K_MA<4>
  J1B1   214     A4  SCONN288_H44441004_PIP  I111
  J9M1   214     A4  SCONN288_H44441003_PIP  I14
  U2D1   ED59  DDR3_MA<4>  SKX_EXT_B_BGA1  I172

M_K_MA<5>       @BASEBOARD_FAB2_LIB.BASEBOARD_FAB2(SCH_1):M_K_MA<5>
  J1B1   213     A5  SCONN288_H44441004_PIP  I111
  J9M1   213     A5  SCONN288_H44441003_PIP  I14
  U2D1   EA58  DDR3_MA<5>  SKX_EXT_B_BGA1  I172

M_K_MA<6>       @BASEBOARD_FAB2_LIB.BASEBOARD_FAB2(SCH_1):M_K_MA<6>
  J1B1    69     A6  SCONN288_H44441004_PIP  I111
  J9M1    69     A6  SCONN288_H44441003_PIP  I14
  U2D1   EE60  DDR3_MA<6>  SKX_EXT_B_BGA1  I172

M_K_MA<7>       @BASEBOARD_FAB2_LIB.BASEBOARD_FAB2(SCH_1):M_K_MA<7>
  J1B1   211     A7  SCONN288_H44441004_PIP  I111
  J9M1   211     A7  SCONN288_H44441003_PIP  I14
  U2D1   EA60  DDR3_MA<7>  SKX_EXT_B_BGA1  I172

M_K_MA<8>       @BASEBOARD_FAB2_LIB.BASEBOARD_FAB2(SCH_1):M_K_MA<8>
  J1B1    68     A8  SCONN288_H44441004_PIP  I111
  J9M1    68     A8  SCONN288_H44441003_PIP  I14
  U2D1   EB59  DDR3_MA<8>  SKX_EXT_B_BGA1  I172

M_K_MA<9>       @BASEBOARD_FAB2_LIB.BASEBOARD_FAB2(SCH_1):M_K_MA<9>
  J1B1    66     A9  SCONN288_H44441004_PIP  I111
  J9M1    66     A9  SCONN288_H44441003_PIP  I14
  U2D1   EF61  DDR3_MA<9>  SKX_EXT_B_BGA1  I172

M_K_MA<10>      @BASEBOARD_FAB2_LIB.BASEBOARD_FAB2(SCH_1):M_K_MA<10>
  J1B1   225    A10  SCONN288_H44441004_PIP  I111
  J9M1   225    A10  SCONN288_H44441003_PIP  I14
  U2D1   DW54  DDR3_MA<10>  SKX_EXT_B_BGA1  I172

M_K_MA<11>      @BASEBOARD_FAB2_LIB.BASEBOARD_FAB2(SCH_1):M_K_MA<11>
  J1B1   210    A11  SCONN288_H44441004_PIP  I111
  J9M1   210    A11  SCONN288_H44441003_PIP  I14
  U2D1   EB61  DDR3_MA<11>  SKX_EXT_B_BGA1  I172

M_K_MA<12>      @BASEBOARD_FAB2_LIB.BASEBOARD_FAB2(SCH_1):M_K_MA<12>
  J1B1    65    A12  SCONN288_H44441004_PIP  I111
  J9M1    65    A12  SCONN288_H44441003_PIP  I14
  U2D1   DT63  DDR3_MA<12>  SKX_EXT_B_BGA1  I172

M_K_MA<13>      @BASEBOARD_FAB2_LIB.BASEBOARD_FAB2(SCH_1):M_K_MA<13>
  J1B1   232    A13  SCONN288_H44441004_PIP  I111
  J9M1   232    A13  SCONN288_H44441003_PIP  I14
  U2D1   DW48  DDR3_MA<13>  SKX_EXT_B_BGA1  I172

M_K_MA<14>      @BASEBOARD_FAB2_LIB.BASEBOARD_FAB2(SCH_1):M_K_MA<14>
  J1B1   228  A14_WE_N  SCONN288_H44441004_PIP  I111
  J9M1   228  A14_WE_N  SCONN288_H44441003_PIP  I14
  U2D1   ED51  DDR3_MA<14>  SKX_EXT_B_BGA1  I172

M_K_MA<15>      @BASEBOARD_FAB2_LIB.BASEBOARD_FAB2(SCH_1):M_K_MA<15>
  J1B1    86  A15_CAS_N  SCONN288_H44441004_PIP  I111
  J9M1    86  A15_CAS_N  SCONN288_H44441003_PIP  I14
  U2D1   DV49  DDR3_MA<15>  SKX_EXT_B_BGA1  I172

M_K_MA<16>      @BASEBOARD_FAB2_LIB.BASEBOARD_FAB2(SCH_1):M_K_MA<16>
  J1B1    82  A16_RAS_N  SCONN288_H44441004_PIP  I111
  J9M1    82  A16_RAS_N  SCONN288_H44441003_PIP  I14
  U2D1   EA52  DDR3_MA<16>  SKX_EXT_B_BGA1  I172

M_K_MA<17>      @BASEBOARD_FAB2_LIB.BASEBOARD_FAB2(SCH_1):M_K_MA<17>
  J1B1   234    A17  SCONN288_H44441004_PIP  I111
  J9M1   234    A17  SCONN288_H44441003_PIP  I14
  U2D1   EA46  DDR3_MA<17>  SKX_EXT_B_BGA1  I172

M_K_ODT<0>      @BASEBOARD_FAB2_LIB.BASEBOARD_FAB2(SCH_1):M_K_ODT<0>
  J1B1    87  ODT<0>  SCONN288_H44441004_PIP  I111
  U2D1   EE50  DDR3_ODT<0>  SKX_EXT_B_BGA1  I172

M_K_ODT<1>      @BASEBOARD_FAB2_LIB.BASEBOARD_FAB2(SCH_1):M_K_ODT<1>
  J1B1    91  ODT<1>  SCONN288_H44441004_PIP  I111
  U2D1   EE48  DDR3_ODT<1>  SKX_EXT_B_BGA1  I172

M_K_ODT<2>      @BASEBOARD_FAB2_LIB.BASEBOARD_FAB2(SCH_1):M_K_ODT<2>
  J9M1    87  ODT<0>  SCONN288_H44441003_PIP  I14
  U2D1   EA50  DDR3_ODT<2>  SKX_EXT_B_BGA1  I172

M_K_ODT<3>      @BASEBOARD_FAB2_LIB.BASEBOARD_FAB2(SCH_1):M_K_ODT<3>
  J9M1    91  ODT<1>  SCONN288_H44441003_PIP  I14
  U2D1   EA48  DDR3_ODT<3>  SKX_EXT_B_BGA1  I172

M_K_PAR         @BASEBOARD_FAB2_LIB.BASEBOARD_FAB2(SCH_1):M_K_PAR
  J1B1   222    PAR  SCONN288_H44441004_PIP  I111
  J9M1   222    PAR  SCONN288_H44441003_PIP  I14
  U2D1   ED53  DDR3_PAR  SKX_EXT_B_BGA1  I172

M_K_VREF        @BASEBOARD_FAB2_LIB.BASEBOARD_FAB2(SCH_1):M_K_VREF
  C1B9     1      A  CAP_A       I176
  C9M1     1      A  CAP_A        I4
  J1B1   146  VREFCA  SCONN288_H44441004_PIP  I111
  J9M1   146  VREFCA  SCONN288_H44441003_PIP  I14
  R9L11    1      A  RES          I4
  R9M1     2      B  RES         I11
  R9M2     2      B  RES         I13

M_L_ACT_N       @BASEBOARD_FAB2_LIB.BASEBOARD_FAB2(SCH_1):M_L_ACT_N
  J1A2    62  ACT_N  SCONN288_H44441004_PIP  I111
  J9L2    62  ACT_N  SCONN288_H44441003_PIP  I12
  U2D1   DR62  DDR4_ACT_N  SKX_EXT_B_BGA1  I172

M_L_ALERT_N     @BASEBOARD_FAB2_LIB.BASEBOARD_FAB2(SCH_1):M_L_ALERT_N
  J1A2   208  ALERT_N  SCONN288_H44441004_PIP  I111
  J9L2   208  ALERT_N  SCONN288_H44441003_PIP  I12
  U2D1   DT61  DDR4_ALERT_N  SKX_EXT_B_BGA1  I172

M_L_BA<0>       @BASEBOARD_FAB2_LIB.BASEBOARD_FAB2(SCH_1):M_L_BA<0>
  J1A2    81  BA<0>  SCONN288_H44441004_PIP  I111
  J9L2    81  BA<0>  SCONN288_H44441003_PIP  I12
  U2D1   DM53  DDR4_BA<0>  SKX_EXT_B_BGA1  I172

M_L_BA<1>       @BASEBOARD_FAB2_LIB.BASEBOARD_FAB2(SCH_1):M_L_BA<1>
  J1A2   224  BA<1>  SCONN288_H44441004_PIP  I111
  J9L2   224  BA<1>  SCONN288_H44441003_PIP  I12
  U2D1   DV55  DDR4_BA<1>  SKX_EXT_B_BGA1  I172

M_L_BG<0>       @BASEBOARD_FAB2_LIB.BASEBOARD_FAB2(SCH_1):M_L_BG<0>
  J1A2    63  BG<0>  SCONN288_H44441004_PIP  I111
  J9L2    63  BG<0>  SCONN288_H44441003_PIP  I12
  U2D1   DJ62  DDR4_BG<0>  SKX_EXT_B_BGA1  I172

M_L_BG<1>       @BASEBOARD_FAB2_LIB.BASEBOARD_FAB2(SCH_1):M_L_BG<1>
  J1A2   207  BG<1>  SCONN288_H44441004_PIP  I111
  J9L2   207  BG<1>  SCONN288_H44441003_PIP  I12
  U2D1   DM61  DDR4_BG<1>  SKX_EXT_B_BGA1  I172

M_L_C<2>        @BASEBOARD_FAB2_LIB.BASEBOARD_FAB2(SCH_1):M_L_C<2>
  J1A2   235   C<2>  SCONN288_H44441004_PIP  I111
  J9L2   235   C<2>  SCONN288_H44441003_PIP  I12
  U2D1   DT47  DDR4_CID<2>  SKX_EXT_B_BGA1  I172

M_L_CKE<0>      @BASEBOARD_FAB2_LIB.BASEBOARD_FAB2(SCH_1):M_L_CKE<0>
  J1A2    60  CKE<0>  SCONN288_H44441004_PIP  I111
  U2D1   DM63  DDR4_CKE<0>  SKX_EXT_B_BGA1  I172

M_L_CKE<1>      @BASEBOARD_FAB2_LIB.BASEBOARD_FAB2(SCH_1):M_L_CKE<1>
  J1A2   203  CKE<1>  SCONN288_H44441004_PIP  I111
  U2D1   DN64  DDR4_CKE<1>  SKX_EXT_B_BGA1  I172

M_L_CKE<2>      @BASEBOARD_FAB2_LIB.BASEBOARD_FAB2(SCH_1):M_L_CKE<2>
  J9L2    60  CKE<0>  SCONN288_H44441003_PIP  I12
  U2D1   DL64  DDR4_CKE<2>  SKX_EXT_B_BGA1  I172

M_L_CKE<3>      @BASEBOARD_FAB2_LIB.BASEBOARD_FAB2(SCH_1):M_L_CKE<3>
  J9L2   203  CKE<1>  SCONN288_H44441003_PIP  I12
  U2D1   DR64  DDR4_CKE<3>  SKX_EXT_B_BGA1  I172

M_L_CLK_DN<0>   @BASEBOARD_FAB2_LIB.BASEBOARD_FAB2(SCH_1):M_L_CLK_DN<0>
  J1A2    75   CK0N  SCONN288_H44441004_PIP  I111
  U2D1   DM55  DDR4_CLK_DN<0>  SKX_EXT_B_BGA1  I172

M_L_CLK_DN<1>   @BASEBOARD_FAB2_LIB.BASEBOARD_FAB2(SCH_1):M_L_CLK_DN<1>
  J1A2   219   CK1N  SCONN288_H44441004_PIP  I111
  U2D1   DR54  DDR4_CLK_DN<1>  SKX_EXT_B_BGA1  I172

M_L_CLK_DN<2>   @BASEBOARD_FAB2_LIB.BASEBOARD_FAB2(SCH_1):M_L_CLK_DN<2>
  J9L2    75   CK0N  SCONN288_H44441003_PIP  I12
  U2D1   DM57  DDR4_CLK_DN<2>  SKX_EXT_B_BGA1  I172

M_L_CLK_DN<3>   @BASEBOARD_FAB2_LIB.BASEBOARD_FAB2(SCH_1):M_L_CLK_DN<3>
  J9L2   219   CK1N  SCONN288_H44441003_PIP  I12
  U2D1   DT57  DDR4_CLK_DN<3>  SKX_EXT_B_BGA1  I172

M_L_CLK_DP<0>   @BASEBOARD_FAB2_LIB.BASEBOARD_FAB2(SCH_1):M_L_CLK_DP<0>
  J1A2    74   CK0P  SCONN288_H44441004_PIP  I111
  U2D1   DN54  DDR4_CLK_DP<0>  SKX_EXT_B_BGA1  I172

M_L_CLK_DP<1>   @BASEBOARD_FAB2_LIB.BASEBOARD_FAB2(SCH_1):M_L_CLK_DP<1>
  J1A2   218   CK1P  SCONN288_H44441004_PIP  I111
  U2D1   DT53  DDR4_CLK_DP<1>  SKX_EXT_B_BGA1  I172

M_L_CLK_DP<2>   @BASEBOARD_FAB2_LIB.BASEBOARD_FAB2(SCH_1):M_L_CLK_DP<2>
  J9L2    74   CK0P  SCONN288_H44441003_PIP  I12
  U2D1   DN56  DDR4_CLK_DP<2>  SKX_EXT_B_BGA1  I172

M_L_CLK_DP<3>   @BASEBOARD_FAB2_LIB.BASEBOARD_FAB2(SCH_1):M_L_CLK_DP<3>
  J9L2   218   CK1P  SCONN288_H44441003_PIP  I12
  U2D1   DR56  DDR4_CLK_DP<3>  SKX_EXT_B_BGA1  I172

M_L_CPU_VREF    @BASEBOARD_FAB2_LIB.BASEBOARD_FAB2(SCH_1):M_L_CPU_VREF
  C9L8     1      A  CAP_A       I30
  R9L8     1      A  RES         I29
  U2D1   CT61  DDR4_CAVREF  SKX_EXT_B_BGA1  I172

M_L_CS_N<0>     @BASEBOARD_FAB2_LIB.BASEBOARD_FAB2(SCH_1):M_L_CS_N<0>
  J1A2    84   S0_N  SCONN288_H44441004_PIP  I111
  U2D1   DV51  DDR4_CS_N<0>  SKX_EXT_B_BGA1  I172

M_L_CS_N<1>     @BASEBOARD_FAB2_LIB.BASEBOARD_FAB2(SCH_1):M_L_CS_N<1>
  J1A2    89   S1_N  SCONN288_H44441004_PIP  I111
  U2D1   DN50  DDR4_CS_N<1>  SKX_EXT_B_BGA1  I172

M_L_CS_N<2>     @BASEBOARD_FAB2_LIB.BASEBOARD_FAB2(SCH_1):M_L_CS_N<2>
  J1A2    93  S2_N_C<0>  SCONN288_H44441004_PIP  I111
  U2D1   DR46  DDR4_CS_N<2>  SKX_EXT_B_BGA1  I172

M_L_CS_N<3>     @BASEBOARD_FAB2_LIB.BASEBOARD_FAB2(SCH_1):M_L_CS_N<3>
  J1A2   237  S3_N_C<1>  SCONN288_H44441004_PIP  I111
  U2D1   DK47  DDR4_CS_N<3>  SKX_EXT_B_BGA1  I172

M_L_CS_N<4>     @BASEBOARD_FAB2_LIB.BASEBOARD_FAB2(SCH_1):M_L_CS_N<4>
  J9L2    84   S0_N  SCONN288_H44441003_PIP  I12
  U2D1   DW50  DDR4_CS_N<4>  SKX_EXT_B_BGA1  I172

M_L_CS_N<5>     @BASEBOARD_FAB2_LIB.BASEBOARD_FAB2(SCH_1):M_L_CS_N<5>
  J9L2    89   S1_N  SCONN288_H44441003_PIP  I12
  U2D1   DM49  DDR4_CS_N<5>  SKX_EXT_B_BGA1  I172

M_L_CS_N<6>     @BASEBOARD_FAB2_LIB.BASEBOARD_FAB2(SCH_1):M_L_CS_N<6>
  J9L2    93  S2_N_C<0>  SCONN288_H44441003_PIP  I12
  U2D1   DT45  DDR4_CS_N<6>  SKX_EXT_B_BGA1  I172

M_L_CS_N<7>     @BASEBOARD_FAB2_LIB.BASEBOARD_FAB2(SCH_1):M_L_CS_N<7>
  J9L2   237  S3_N_C<1>  SCONN288_H44441003_PIP  I12
  U2D1   DN46  DDR4_CS_N<7>  SKX_EXT_B_BGA1  I172

M_L_DQ<0>       @BASEBOARD_FAB2_LIB.BASEBOARD_FAB2(SCH_1):M_L_DQ<0>
  J1A2   150  DQ<1>  SCONN288_H44441004_PIP  I111
  J9L2     5  DQ<0>  SCONN288_H44441003_PIP  I12
  U2D1   CM79  DDR4_DQ<0>  SKX_EXT_B_BGA1  I172

M_L_DQ<1>       @BASEBOARD_FAB2_LIB.BASEBOARD_FAB2(SCH_1):M_L_DQ<1>
  J1A2     5  DQ<0>  SCONN288_H44441004_PIP  I111
  J9L2   150  DQ<1>  SCONN288_H44441003_PIP  I12
  U2D1   CK81  DDR4_DQ<1>  SKX_EXT_B_BGA1  I172

M_L_DQ<2>       @BASEBOARD_FAB2_LIB.BASEBOARD_FAB2(SCH_1):M_L_DQ<2>
  J1A2   157  DQ<3>  SCONN288_H44441004_PIP  I111
  J9L2    12  DQ<2>  SCONN288_H44441003_PIP  I12
  U2D1   CT81  DDR4_DQ<2>  SKX_EXT_B_BGA1  I172

M_L_DQ<3>       @BASEBOARD_FAB2_LIB.BASEBOARD_FAB2(SCH_1):M_L_DQ<3>
  J1A2    12  DQ<2>  SCONN288_H44441004_PIP  I111
  J9L2   157  DQ<3>  SCONN288_H44441003_PIP  I12
  U2D1   CR82  DDR4_DQ<3>  SKX_EXT_B_BGA1  I172

M_L_DQ<4>       @BASEBOARD_FAB2_LIB.BASEBOARD_FAB2(SCH_1):M_L_DQ<4>
  J1A2   148  DQ<5>  SCONN288_H44441004_PIP  I111
  J9L2     3  DQ<4>  SCONN288_H44441003_PIP  I12
  U2D1   CK79  DDR4_DQ<4>  SKX_EXT_B_BGA1  I172

M_L_DQ<5>       @BASEBOARD_FAB2_LIB.BASEBOARD_FAB2(SCH_1):M_L_DQ<5>
  J1A2     3  DQ<4>  SCONN288_H44441004_PIP  I111
  J9L2   148  DQ<5>  SCONN288_H44441003_PIP  I12
  U2D1   CJ80  DDR4_DQ<5>  SKX_EXT_B_BGA1  I172

M_L_DQ<6>       @BASEBOARD_FAB2_LIB.BASEBOARD_FAB2(SCH_1):M_L_DQ<6>
  J1A2   155  DQ<7>  SCONN288_H44441004_PIP  I111
  J9L2    10  DQ<6>  SCONN288_H44441003_PIP  I12
  U2D1   CR80  DDR4_DQ<6>  SKX_EXT_B_BGA1  I172

M_L_DQ<7>       @BASEBOARD_FAB2_LIB.BASEBOARD_FAB2(SCH_1):M_L_DQ<7>
  J1A2    10  DQ<6>  SCONN288_H44441004_PIP  I111
  J9L2   155  DQ<7>  SCONN288_H44441003_PIP  I12
  U2D1   CN82  DDR4_DQ<7>  SKX_EXT_B_BGA1  I172

M_L_DQ<8>       @BASEBOARD_FAB2_LIB.BASEBOARD_FAB2(SCH_1):M_L_DQ<8>
  J1A2   161  DQ<9>  SCONN288_H44441004_PIP  I111
  J9L2    16  DQ<8>  SCONN288_H44441003_PIP  I12
  U2D1   DB79  DDR4_DQ<8>  SKX_EXT_B_BGA1  I172

M_L_DQ<9>       @BASEBOARD_FAB2_LIB.BASEBOARD_FAB2(SCH_1):M_L_DQ<9>
  J1A2    16  DQ<8>  SCONN288_H44441004_PIP  I111
  J9L2   161  DQ<9>  SCONN288_H44441003_PIP  I12
  U2D1   CY81  DDR4_DQ<9>  SKX_EXT_B_BGA1  I172

M_L_DQ<10>      @BASEBOARD_FAB2_LIB.BASEBOARD_FAB2(SCH_1):M_L_DQ<10>
  J1A2   168  DQ<11>  SCONN288_H44441004_PIP  I111
  J9L2    23  DQ<10>  SCONN288_H44441003_PIP  I12
  U2D1   DE80  DDR4_DQ<10>  SKX_EXT_B_BGA1  I172

M_L_DQ<11>      @BASEBOARD_FAB2_LIB.BASEBOARD_FAB2(SCH_1):M_L_DQ<11>
  J1A2    23  DQ<10>  SCONN288_H44441004_PIP  I111
  J9L2   168  DQ<11>  SCONN288_H44441003_PIP  I12
  U2D1   DF81  DDR4_DQ<11>  SKX_EXT_B_BGA1  I172

M_L_DQ<12>      @BASEBOARD_FAB2_LIB.BASEBOARD_FAB2(SCH_1):M_L_DQ<12>
  J1A2   159  DQ<13>  SCONN288_H44441004_PIP  I111
  J9L2    14  DQ<12>  SCONN288_H44441003_PIP  I12
  U2D1   CY79  DDR4_DQ<12>  SKX_EXT_B_BGA1  I172

M_L_DQ<13>      @BASEBOARD_FAB2_LIB.BASEBOARD_FAB2(SCH_1):M_L_DQ<13>
  J1A2    14  DQ<12>  SCONN288_H44441004_PIP  I111
  J9L2   159  DQ<13>  SCONN288_H44441003_PIP  I12
  U2D1   CW80  DDR4_DQ<13>  SKX_EXT_B_BGA1  I172

M_L_DQ<14>      @BASEBOARD_FAB2_LIB.BASEBOARD_FAB2(SCH_1):M_L_DQ<14>
  J1A2   166  DQ<15>  SCONN288_H44441004_PIP  I111
  J9L2    21  DQ<14>  SCONN288_H44441003_PIP  I12
  U2D1   DC82  DDR4_DQ<14>  SKX_EXT_B_BGA1  I172

M_L_DQ<15>      @BASEBOARD_FAB2_LIB.BASEBOARD_FAB2(SCH_1):M_L_DQ<15>
  J1A2    21  DQ<14>  SCONN288_H44441004_PIP  I111
  J9L2   166  DQ<15>  SCONN288_H44441003_PIP  I12
  U2D1   DE82  DDR4_DQ<15>  SKX_EXT_B_BGA1  I172

M_L_DQ<16>      @BASEBOARD_FAB2_LIB.BASEBOARD_FAB2(SCH_1):M_L_DQ<16>
  J1A2   172  DQ<17>  SCONN288_H44441004_PIP  I111
  J9L2    27  DQ<16>  SCONN288_H44441003_PIP  I12
  U2D1   DW80  DDR4_DQ<16>  SKX_EXT_B_BGA1  I172

M_L_DQ<17>      @BASEBOARD_FAB2_LIB.BASEBOARD_FAB2(SCH_1):M_L_DQ<17>
  J1A2    27  DQ<16>  SCONN288_H44441004_PIP  I111
  J9L2   172  DQ<17>  SCONN288_H44441003_PIP  I12
  U2D1   EC80  DDR4_DQ<17>  SKX_EXT_B_BGA1  I172

M_L_DQ<18>      @BASEBOARD_FAB2_LIB.BASEBOARD_FAB2(SCH_1):M_L_DQ<18>
  J1A2   179  DQ<19>  SCONN288_H44441004_PIP  I111
  J9L2    34  DQ<18>  SCONN288_H44441003_PIP  I12
  U2D1   DY77  DDR4_DQ<18>  SKX_EXT_B_BGA1  I172

M_L_DQ<19>      @BASEBOARD_FAB2_LIB.BASEBOARD_FAB2(SCH_1):M_L_DQ<19>
  J1A2    34  DQ<18>  SCONN288_H44441004_PIP  I111
  J9L2   179  DQ<19>  SCONN288_H44441003_PIP  I12
  U2D1   EB77  DDR4_DQ<19>  SKX_EXT_B_BGA1  I172

M_L_DQ<20>      @BASEBOARD_FAB2_LIB.BASEBOARD_FAB2(SCH_1):M_L_DQ<20>
  J1A2   170  DQ<21>  SCONN288_H44441004_PIP  I111
  J9L2    25  DQ<20>  SCONN288_H44441003_PIP  I12
  U2D1   DY81  DDR4_DQ<20>  SKX_EXT_B_BGA1  I172

M_L_DQ<21>      @BASEBOARD_FAB2_LIB.BASEBOARD_FAB2(SCH_1):M_L_DQ<21>
  J1A2    25  DQ<20>  SCONN288_H44441004_PIP  I111
  J9L2   170  DQ<21>  SCONN288_H44441003_PIP  I12
  U2D1   EB81  DDR4_DQ<21>  SKX_EXT_B_BGA1  I172

M_L_DQ<22>      @BASEBOARD_FAB2_LIB.BASEBOARD_FAB2(SCH_1):M_L_DQ<22>
  J1A2   177  DQ<23>  SCONN288_H44441004_PIP  I111
  J9L2    32  DQ<22>  SCONN288_H44441003_PIP  I12
  U2D1   DW78  DDR4_DQ<22>  SKX_EXT_B_BGA1  I172

M_L_DQ<23>      @BASEBOARD_FAB2_LIB.BASEBOARD_FAB2(SCH_1):M_L_DQ<23>
  J1A2    32  DQ<22>  SCONN288_H44441004_PIP  I111
  J9L2   177  DQ<23>  SCONN288_H44441003_PIP  I12
  U2D1   EC78  DDR4_DQ<23>  SKX_EXT_B_BGA1  I172

M_L_DQ<24>      @BASEBOARD_FAB2_LIB.BASEBOARD_FAB2(SCH_1):M_L_DQ<24>
  J1A2   183  DQ<25>  SCONN288_H44441004_PIP  I111
  J9L2    38  DQ<24>  SCONN288_H44441003_PIP  I12
  U2D1   ED75  DDR4_DQ<24>  SKX_EXT_B_BGA1  I172

M_L_DQ<25>      @BASEBOARD_FAB2_LIB.BASEBOARD_FAB2(SCH_1):M_L_DQ<25>
  J1A2    38  DQ<24>  SCONN288_H44441004_PIP  I111
  J9L2   183  DQ<25>  SCONN288_H44441003_PIP  I12
  U2D1   EE74  DDR4_DQ<25>  SKX_EXT_B_BGA1  I172

M_L_DQ<26>      @BASEBOARD_FAB2_LIB.BASEBOARD_FAB2(SCH_1):M_L_DQ<26>
  J1A2   190  DQ<27>  SCONN288_H44441004_PIP  I111
  J9L2    45  DQ<26>  SCONN288_H44441003_PIP  I12
  U2D1   EB71  DDR4_DQ<26>  SKX_EXT_B_BGA1  I172

M_L_DQ<27>      @BASEBOARD_FAB2_LIB.BASEBOARD_FAB2(SCH_1):M_L_DQ<27>
  J1A2    45  DQ<26>  SCONN288_H44441004_PIP  I111
  J9L2   190  DQ<27>  SCONN288_H44441003_PIP  I12
  U2D1   ED71  DDR4_DQ<27>  SKX_EXT_B_BGA1  I172

M_L_DQ<28>      @BASEBOARD_FAB2_LIB.BASEBOARD_FAB2(SCH_1):M_L_DQ<28>
  J1A2   181  DQ<29>  SCONN288_H44441004_PIP  I111
  J9L2    36  DQ<28>  SCONN288_H44441003_PIP  I12
  U2D1   EA74  DDR4_DQ<28>  SKX_EXT_B_BGA1  I172

M_L_DQ<29>      @BASEBOARD_FAB2_LIB.BASEBOARD_FAB2(SCH_1):M_L_DQ<29>
  J1A2    36  DQ<28>  SCONN288_H44441004_PIP  I111
  J9L2   181  DQ<29>  SCONN288_H44441003_PIP  I12
  U2D1   EB75  DDR4_DQ<29>  SKX_EXT_B_BGA1  I172

M_L_DQ<30>      @BASEBOARD_FAB2_LIB.BASEBOARD_FAB2(SCH_1):M_L_DQ<30>
  J1A2   188  DQ<31>  SCONN288_H44441004_PIP  I111
  J9L2    43  DQ<30>  SCONN288_H44441003_PIP  I12
  U2D1   EA72  DDR4_DQ<30>  SKX_EXT_B_BGA1  I172

M_L_DQ<31>      @BASEBOARD_FAB2_LIB.BASEBOARD_FAB2(SCH_1):M_L_DQ<31>
  J1A2    43  DQ<30>  SCONN288_H44441004_PIP  I111
  J9L2   188  DQ<31>  SCONN288_H44441003_PIP  I12
  U2D1   EE72  DDR4_DQ<31>  SKX_EXT_B_BGA1  I172

M_L_DQ<32>      @BASEBOARD_FAB2_LIB.BASEBOARD_FAB2(SCH_1):M_L_DQ<32>
  J1A2   242  DQ<33>  SCONN288_H44441004_PIP  I111
  J9L2    97  DQ<32>  SCONN288_H44441003_PIP  I12
  U2D1   DU42  DDR4_DQ<32>  SKX_EXT_B_BGA1  I172

M_L_DQ<33>      @BASEBOARD_FAB2_LIB.BASEBOARD_FAB2(SCH_1):M_L_DQ<33>
  J1A2    97  DQ<32>  SCONN288_H44441004_PIP  I111
  J9L2   242  DQ<33>  SCONN288_H44441003_PIP  I12
  U2D1   DW42  DDR4_DQ<33>  SKX_EXT_B_BGA1  I172

M_L_DQ<34>      @BASEBOARD_FAB2_LIB.BASEBOARD_FAB2(SCH_1):M_L_DQ<34>
  J1A2   249  DQ<35>  SCONN288_H44441004_PIP  I111
  J9L2   104  DQ<34>  SCONN288_H44441003_PIP  I12
  U2D1   DP39  DDR4_DQ<34>  SKX_EXT_B_BGA1  I172

M_L_DQ<35>      @BASEBOARD_FAB2_LIB.BASEBOARD_FAB2(SCH_1):M_L_DQ<35>
  J1A2   104  DQ<34>  SCONN288_H44441004_PIP  I111
  J9L2   249  DQ<35>  SCONN288_H44441003_PIP  I12
  U2D1   DT39  DDR4_DQ<35>  SKX_EXT_B_BGA1  I172

M_L_DQ<36>      @BASEBOARD_FAB2_LIB.BASEBOARD_FAB2(SCH_1):M_L_DQ<36>
  J1A2   240  DQ<37>  SCONN288_H44441004_PIP  I111
  J9L2    95  DQ<36>  SCONN288_H44441003_PIP  I12
  U2D1   DL42  DDR4_DQ<36>  SKX_EXT_B_BGA1  I172

M_L_DQ<37>      @BASEBOARD_FAB2_LIB.BASEBOARD_FAB2(SCH_1):M_L_DQ<37>
  J1A2    95  DQ<36>  SCONN288_H44441004_PIP  I111
  J9L2   240  DQ<37>  SCONN288_H44441003_PIP  I12
  U2D1   DN42  DDR4_DQ<37>  SKX_EXT_B_BGA1  I172

M_L_DQ<38>      @BASEBOARD_FAB2_LIB.BASEBOARD_FAB2(SCH_1):M_L_DQ<38>
  J1A2   247  DQ<39>  SCONN288_H44441004_PIP  I111
  J9L2   102  DQ<38>  SCONN288_H44441003_PIP  I12
  U2D1   DN40  DDR4_DQ<38>  SKX_EXT_B_BGA1  I172

M_L_DQ<39>      @BASEBOARD_FAB2_LIB.BASEBOARD_FAB2(SCH_1):M_L_DQ<39>
  J1A2   102  DQ<38>  SCONN288_H44441004_PIP  I111
  J9L2   247  DQ<39>  SCONN288_H44441003_PIP  I12
  U2D1   DU40  DDR4_DQ<39>  SKX_EXT_B_BGA1  I172

M_L_DQ<40>      @BASEBOARD_FAB2_LIB.BASEBOARD_FAB2(SCH_1):M_L_DQ<40>
  J1A2   253  DQ<41>  SCONN288_H44441004_PIP  I111
  J9L2   108  DQ<40>  SCONN288_H44441003_PIP  I12
  U2D1   EC34  DDR4_DQ<40>  SKX_EXT_B_BGA1  I172

M_L_DQ<41>      @BASEBOARD_FAB2_LIB.BASEBOARD_FAB2(SCH_1):M_L_DQ<41>
  J1A2   108  DQ<40>  SCONN288_H44441004_PIP  I111
  J9L2   253  DQ<41>  SCONN288_H44441003_PIP  I12
  U2D1   ED33  DDR4_DQ<41>  SKX_EXT_B_BGA1  I172

M_L_DQ<42>      @BASEBOARD_FAB2_LIB.BASEBOARD_FAB2(SCH_1):M_L_DQ<42>
  J1A2   260  DQ<43>  SCONN288_H44441004_PIP  I111
  J9L2   115  DQ<42>  SCONN288_H44441003_PIP  I12
  U2D1   EA30  DDR4_DQ<42>  SKX_EXT_B_BGA1  I172

M_L_DQ<43>      @BASEBOARD_FAB2_LIB.BASEBOARD_FAB2(SCH_1):M_L_DQ<43>
  J1A2   115  DQ<42>  SCONN288_H44441004_PIP  I111
  J9L2   260  DQ<43>  SCONN288_H44441003_PIP  I12
  U2D1   EC30  DDR4_DQ<43>  SKX_EXT_B_BGA1  I172

M_L_DQ<44>      @BASEBOARD_FAB2_LIB.BASEBOARD_FAB2(SCH_1):M_L_DQ<44>
  J1A2   251  DQ<45>  SCONN288_H44441004_PIP  I111
  J9L2   106  DQ<44>  SCONN288_H44441003_PIP  I12
  U2D1   DY33  DDR4_DQ<44>  SKX_EXT_B_BGA1  I172

M_L_DQ<45>      @BASEBOARD_FAB2_LIB.BASEBOARD_FAB2(SCH_1):M_L_DQ<45>
  J1A2   106  DQ<44>  SCONN288_H44441004_PIP  I111
  J9L2   251  DQ<45>  SCONN288_H44441003_PIP  I12
  U2D1   EA34  DDR4_DQ<45>  SKX_EXT_B_BGA1  I172

M_L_DQ<46>      @BASEBOARD_FAB2_LIB.BASEBOARD_FAB2(SCH_1):M_L_DQ<46>
  J1A2   258  DQ<47>  SCONN288_H44441004_PIP  I111
  J9L2   113  DQ<46>  SCONN288_H44441003_PIP  I12
  U2D1   DY31  DDR4_DQ<46>  SKX_EXT_B_BGA1  I172

M_L_DQ<47>      @BASEBOARD_FAB2_LIB.BASEBOARD_FAB2(SCH_1):M_L_DQ<47>
  J1A2   113  DQ<46>  SCONN288_H44441004_PIP  I111
  J9L2   258  DQ<47>  SCONN288_H44441003_PIP  I12
  U2D1   ED31  DDR4_DQ<47>  SKX_EXT_B_BGA1  I172

M_L_DQ<48>      @BASEBOARD_FAB2_LIB.BASEBOARD_FAB2(SCH_1):M_L_DQ<48>
  J1A2   264  DQ<49>  SCONN288_H44441004_PIP  I111
  J9L2   119  DQ<48>  SCONN288_H44441003_PIP  I12
  U2D1   EC28  DDR4_DQ<48>  SKX_EXT_B_BGA1  I172

M_L_DQ<49>      @BASEBOARD_FAB2_LIB.BASEBOARD_FAB2(SCH_1):M_L_DQ<49>
  J1A2   119  DQ<48>  SCONN288_H44441004_PIP  I111
  J9L2   264  DQ<49>  SCONN288_H44441003_PIP  I12
  U2D1   ED27  DDR4_DQ<49>  SKX_EXT_B_BGA1  I172

M_L_DQ<50>      @BASEBOARD_FAB2_LIB.BASEBOARD_FAB2(SCH_1):M_L_DQ<50>
  J1A2   271  DQ<51>  SCONN288_H44441004_PIP  I111
  J9L2   126  DQ<50>  SCONN288_H44441003_PIP  I12
  U2D1   EA24  DDR4_DQ<50>  SKX_EXT_B_BGA1  I172

M_L_DQ<51>      @BASEBOARD_FAB2_LIB.BASEBOARD_FAB2(SCH_1):M_L_DQ<51>
  J1A2   126  DQ<50>  SCONN288_H44441004_PIP  I111
  J9L2   271  DQ<51>  SCONN288_H44441003_PIP  I12
  U2D1   EC24  DDR4_DQ<51>  SKX_EXT_B_BGA1  I172

M_L_DQ<52>      @BASEBOARD_FAB2_LIB.BASEBOARD_FAB2(SCH_1):M_L_DQ<52>
  J1A2   262  DQ<53>  SCONN288_H44441004_PIP  I111
  J9L2   117  DQ<52>  SCONN288_H44441003_PIP  I12
  U2D1   DY27  DDR4_DQ<52>  SKX_EXT_B_BGA1  I172

M_L_DQ<53>      @BASEBOARD_FAB2_LIB.BASEBOARD_FAB2(SCH_1):M_L_DQ<53>
  J1A2   117  DQ<52>  SCONN288_H44441004_PIP  I111
  J9L2   262  DQ<53>  SCONN288_H44441003_PIP  I12
  U2D1   EA28  DDR4_DQ<53>  SKX_EXT_B_BGA1  I172

M_L_DQ<54>      @BASEBOARD_FAB2_LIB.BASEBOARD_FAB2(SCH_1):M_L_DQ<54>
  J1A2   269  DQ<55>  SCONN288_H44441004_PIP  I111
  J9L2   124  DQ<54>  SCONN288_H44441003_PIP  I12
  U2D1   DY25  DDR4_DQ<54>  SKX_EXT_B_BGA1  I172

M_L_DQ<55>      @BASEBOARD_FAB2_LIB.BASEBOARD_FAB2(SCH_1):M_L_DQ<55>
  J1A2   124  DQ<54>  SCONN288_H44441004_PIP  I111
  J9L2   269  DQ<55>  SCONN288_H44441003_PIP  I12
  U2D1   ED25  DDR4_DQ<55>  SKX_EXT_B_BGA1  I172

M_L_DQ<56>      @BASEBOARD_FAB2_LIB.BASEBOARD_FAB2(SCH_1):M_L_DQ<56>
  J1A2   275  DQ<57>  SCONN288_H44441004_PIP  I111
  J9L2   130  DQ<56>  SCONN288_H44441003_PIP  I12
  U2D1   DF27  DDR4_DQ<56>  SKX_EXT_B_BGA1  I172

M_L_DQ<57>      @BASEBOARD_FAB2_LIB.BASEBOARD_FAB2(SCH_1):M_L_DQ<57>
  J1A2   130  DQ<56>  SCONN288_H44441004_PIP  I111
  J9L2   275  DQ<57>  SCONN288_H44441003_PIP  I12
  U2D1   DK27  DDR4_DQ<57>  SKX_EXT_B_BGA1  I172

M_L_DQ<58>      @BASEBOARD_FAB2_LIB.BASEBOARD_FAB2(SCH_1):M_L_DQ<58>
  J1A2   282  DQ<59>  SCONN288_H44441004_PIP  I111
  J9L2   137  DQ<58>  SCONN288_H44441003_PIP  I12
  U2D1   DD25  DDR4_DQ<58>  SKX_EXT_B_BGA1  I172

M_L_DQ<59>      @BASEBOARD_FAB2_LIB.BASEBOARD_FAB2(SCH_1):M_L_DQ<59>
  J1A2   137  DQ<58>  SCONN288_H44441004_PIP  I111
  J9L2   282  DQ<59>  SCONN288_H44441003_PIP  I12
  U2D1   DJ24  DDR4_DQ<59>  SKX_EXT_B_BGA1  I172

M_L_DQ<60>      @BASEBOARD_FAB2_LIB.BASEBOARD_FAB2(SCH_1):M_L_DQ<60>
  J1A2   273  DQ<61>  SCONN288_H44441004_PIP  I111
  J9L2   128  DQ<60>  SCONN288_H44441003_PIP  I12
  U2D1   DG28  DDR4_DQ<60>  SKX_EXT_B_BGA1  I172

M_L_DQ<61>      @BASEBOARD_FAB2_LIB.BASEBOARD_FAB2(SCH_1):M_L_DQ<61>
  J1A2   128  DQ<60>  SCONN288_H44441004_PIP  I111
  J9L2   273  DQ<61>  SCONN288_H44441003_PIP  I12
  U2D1   DJ28  DDR4_DQ<61>  SKX_EXT_B_BGA1  I172

M_L_DQ<62>      @BASEBOARD_FAB2_LIB.BASEBOARD_FAB2(SCH_1):M_L_DQ<62>
  J1A2   280  DQ<63>  SCONN288_H44441004_PIP  I111
  J9L2   135  DQ<62>  SCONN288_H44441003_PIP  I12
  U2D1   DF25  DDR4_DQ<62>  SKX_EXT_B_BGA1  I172

M_L_DQ<63>      @BASEBOARD_FAB2_LIB.BASEBOARD_FAB2(SCH_1):M_L_DQ<63>
  J1A2   135  DQ<62>  SCONN288_H44441004_PIP  I111
  J9L2   280  DQ<63>  SCONN288_H44441003_PIP  I12
  U2D1   DK25  DDR4_DQ<63>  SKX_EXT_B_BGA1  I172

M_L_DQS_DN<0>   @BASEBOARD_FAB2_LIB.BASEBOARD_FAB2(SCH_1):M_L_DQS_DN<0>
  J1A2   152  DQS0N  SCONN288_H44441004_PIP  I66
  J9L2   152  DQS0N  SCONN288_H44441003_PIP  I100
  U2D1   CL82  DDR4_DQS_DN<0>  SKX_EXT_B_BGA1  I172

M_L_DQS_DN<1>   @BASEBOARD_FAB2_LIB.BASEBOARD_FAB2(SCH_1):M_L_DQS_DN<1>
  J1A2   163  DQS1N  SCONN288_H44441004_PIP  I66
  J9L2   163  DQS1N  SCONN288_H44441003_PIP  I100
  U2D1   DA82  DDR4_DQS_DN<1>  SKX_EXT_B_BGA1  I172

M_L_DQS_DN<2>   @BASEBOARD_FAB2_LIB.BASEBOARD_FAB2(SCH_1):M_L_DQS_DN<2>
  J1A2   174  DQS2N  SCONN288_H44441004_PIP  I66
  J9L2   174  DQS2N  SCONN288_H44441003_PIP  I100
  U2D1   ED79  DDR4_DQS_DN<2>  SKX_EXT_B_BGA1  I172

M_L_DQS_DN<3>   @BASEBOARD_FAB2_LIB.BASEBOARD_FAB2(SCH_1):M_L_DQS_DN<3>
  J1A2   185  DQS3N  SCONN288_H44441004_PIP  I66
  J9L2   185  DQS3N  SCONN288_H44441003_PIP  I100
  U2D1   EF73  DDR4_DQS_DN<3>  SKX_EXT_B_BGA1  I172

M_L_DQS_DN<4>   @BASEBOARD_FAB2_LIB.BASEBOARD_FAB2(SCH_1):M_L_DQS_DN<4>
  J1A2   244  DQS4N  SCONN288_H44441004_PIP  I66
  J9L2   244  DQS4N  SCONN288_H44441003_PIP  I100
  U2D1   DV41  DDR4_DQS_DN<4>  SKX_EXT_B_BGA1  I172

M_L_DQS_DN<5>   @BASEBOARD_FAB2_LIB.BASEBOARD_FAB2(SCH_1):M_L_DQS_DN<5>
  J1A2   255  DQS5N  SCONN288_H44441004_PIP  I66
  J9L2   255  DQS5N  SCONN288_H44441003_PIP  I100
  U2D1   EE32  DDR4_DQS_DN<5>  SKX_EXT_B_BGA1  I172

M_L_DQS_DN<6>   @BASEBOARD_FAB2_LIB.BASEBOARD_FAB2(SCH_1):M_L_DQS_DN<6>
  J1A2   266  DQS6N  SCONN288_H44441004_PIP  I66
  J9L2   266  DQS6N  SCONN288_H44441003_PIP  I100
  U2D1   EE26  DDR4_DQS_DN<6>  SKX_EXT_B_BGA1  I172

M_L_DQS_DN<7>   @BASEBOARD_FAB2_LIB.BASEBOARD_FAB2(SCH_1):M_L_DQS_DN<7>
  J1A2   277  DQS7N  SCONN288_H44441004_PIP  I66
  J9L2   277  DQS7N  SCONN288_H44441003_PIP  I100
  U2D1   DL26  DDR4_DQS_DN<7>  SKX_EXT_B_BGA1  I172

M_L_DQS_DN<8>   @BASEBOARD_FAB2_LIB.BASEBOARD_FAB2(SCH_1):M_L_DQS_DN<8>
  J1A2   196  DQS8N  SCONN288_H44441004_PIP  I66
  J9L2   196  DQS8N  SCONN288_H44441003_PIP  I100
  U2D1   EB67  DDR4_DQS_DN<8>  SKX_EXT_B_BGA1  I172

M_L_DQS_DN<9>   @BASEBOARD_FAB2_LIB.BASEBOARD_FAB2(SCH_1):M_L_DQS_DN<9>
  J1A2     8  DQS9N  SCONN288_H44441004_PIP  I66
  J9L2     8  DQS9N  SCONN288_H44441003_PIP  I100
  U2D1   CN80  DDR4_DQS_DN<9>  SKX_EXT_B_BGA1  I172

M_L_DQS_DN<10>   @BASEBOARD_FAB2_LIB.BASEBOARD_FAB2(SCH_1):M_L_DQS_DN<10>
  J1A2    19  DQS10N  SCONN288_H44441004_PIP  I66
  J9L2    19  DQS10N  SCONN288_H44441003_PIP  I100
  U2D1   DC80  DDR4_DQS_DN<10>  SKX_EXT_B_BGA1  I172

M_L_DQS_DN<11>   @BASEBOARD_FAB2_LIB.BASEBOARD_FAB2(SCH_1):M_L_DQS_DN<11>
  J1A2    30  DQS11N  SCONN288_H44441004_PIP  I66
  J9L2    30  DQS11N  SCONN288_H44441003_PIP  I100
  U2D1   DY79  DDR4_DQS_DN<11>  SKX_EXT_B_BGA1  I172

M_L_DQS_DN<12>   @BASEBOARD_FAB2_LIB.BASEBOARD_FAB2(SCH_1):M_L_DQS_DN<12>
  J1A2    41  DQS12N  SCONN288_H44441004_PIP  I66
  J9L2    41  DQS12N  SCONN288_H44441003_PIP  I100
  U2D1   EB73  DDR4_DQS_DN<12>  SKX_EXT_B_BGA1  I172

M_L_DQS_DN<13>   @BASEBOARD_FAB2_LIB.BASEBOARD_FAB2(SCH_1):M_L_DQS_DN<13>
  J1A2   100  DQS13N  SCONN288_H44441004_PIP  I66
  J9L2   100  DQS13N  SCONN288_H44441003_PIP  I100
  U2D1   DP41  DDR4_DQS_DN<13>  SKX_EXT_B_BGA1  I172

M_L_DQS_DN<14>   @BASEBOARD_FAB2_LIB.BASEBOARD_FAB2(SCH_1):M_L_DQS_DN<14>
  J1A2   111  DQS14N  SCONN288_H44441004_PIP  I66
  J9L2   111  DQS14N  SCONN288_H44441003_PIP  I100
  U2D1   EA32  DDR4_DQS_DN<14>  SKX_EXT_B_BGA1  I172

M_L_DQS_DN<15>   @BASEBOARD_FAB2_LIB.BASEBOARD_FAB2(SCH_1):M_L_DQS_DN<15>
  J1A2   122  DQS15N  SCONN288_H44441004_PIP  I66
  J9L2   122  DQS15N  SCONN288_H44441003_PIP  I100
  U2D1   EA26  DDR4_DQS_DN<15>  SKX_EXT_B_BGA1  I172

M_L_DQS_DN<16>   @BASEBOARD_FAB2_LIB.BASEBOARD_FAB2(SCH_1):M_L_DQS_DN<16>
  J1A2   133  DQS16N  SCONN288_H44441004_PIP  I66
  J9L2   133  DQS16N  SCONN288_H44441003_PIP  I100
  U2D1   DG26  DDR4_DQS_DN<16>  SKX_EXT_B_BGA1  I172

M_L_DQS_DN<17>   @BASEBOARD_FAB2_LIB.BASEBOARD_FAB2(SCH_1):M_L_DQS_DN<17>
  J1A2    52  DQS17N  SCONN288_H44441004_PIP  I66
  J9L2    52  DQS17N  SCONN288_H44441003_PIP  I100
  U2D1   DV67  DDR4_DQS_DN<17>  SKX_EXT_B_BGA1  I172

M_L_DQS_DP<0>   @BASEBOARD_FAB2_LIB.BASEBOARD_FAB2(SCH_1):M_L_DQS_DP<0>
  J1A2   153  DQS0P  SCONN288_H44441004_PIP  I66
  J9L2   153  DQS0P  SCONN288_H44441003_PIP  I100
  U2D1   CM81  DDR4_DQS_DP<0>  SKX_EXT_B_BGA1  I172

M_L_DQS_DP<1>   @BASEBOARD_FAB2_LIB.BASEBOARD_FAB2(SCH_1):M_L_DQS_DP<1>
  J1A2   164  DQS1P  SCONN288_H44441004_PIP  I66
  J9L2   164  DQS1P  SCONN288_H44441003_PIP  I100
  U2D1   DB81  DDR4_DQS_DP<1>  SKX_EXT_B_BGA1  I172

M_L_DQS_DP<2>   @BASEBOARD_FAB2_LIB.BASEBOARD_FAB2(SCH_1):M_L_DQS_DP<2>
  J1A2   175  DQS2P  SCONN288_H44441004_PIP  I66
  J9L2   175  DQS2P  SCONN288_H44441003_PIP  I100
  U2D1   EB79  DDR4_DQS_DP<2>  SKX_EXT_B_BGA1  I172

M_L_DQS_DP<3>   @BASEBOARD_FAB2_LIB.BASEBOARD_FAB2(SCH_1):M_L_DQS_DP<3>
  J1A2   186  DQS3P  SCONN288_H44441004_PIP  I66
  J9L2   186  DQS3P  SCONN288_H44441003_PIP  I100
  U2D1   ED73  DDR4_DQS_DP<3>  SKX_EXT_B_BGA1  I172

M_L_DQS_DP<4>   @BASEBOARD_FAB2_LIB.BASEBOARD_FAB2(SCH_1):M_L_DQS_DP<4>
  J1A2   245  DQS4P  SCONN288_H44441004_PIP  I66
  J9L2   245  DQS4P  SCONN288_H44441003_PIP  I100
  U2D1   DT41  DDR4_DQS_DP<4>  SKX_EXT_B_BGA1  I172

M_L_DQS_DP<5>   @BASEBOARD_FAB2_LIB.BASEBOARD_FAB2(SCH_1):M_L_DQS_DP<5>
  J1A2   256  DQS5P  SCONN288_H44441004_PIP  I66
  J9L2   256  DQS5P  SCONN288_H44441003_PIP  I100
  U2D1   EC32  DDR4_DQS_DP<5>  SKX_EXT_B_BGA1  I172

M_L_DQS_DP<6>   @BASEBOARD_FAB2_LIB.BASEBOARD_FAB2(SCH_1):M_L_DQS_DP<6>
  J1A2   267  DQS6P  SCONN288_H44441004_PIP  I66
  J9L2   267  DQS6P  SCONN288_H44441003_PIP  I100
  U2D1   EC26  DDR4_DQS_DP<6>  SKX_EXT_B_BGA1  I172

M_L_DQS_DP<7>   @BASEBOARD_FAB2_LIB.BASEBOARD_FAB2(SCH_1):M_L_DQS_DP<7>
  J1A2   278  DQS7P  SCONN288_H44441004_PIP  I66
  J9L2   278  DQS7P  SCONN288_H44441003_PIP  I100
  U2D1   DJ26  DDR4_DQS_DP<7>  SKX_EXT_B_BGA1  I172

M_L_DQS_DP<8>   @BASEBOARD_FAB2_LIB.BASEBOARD_FAB2(SCH_1):M_L_DQS_DP<8>
  J1A2   197  DQS8P  SCONN288_H44441004_PIP  I66
  J9L2   197  DQS8P  SCONN288_H44441003_PIP  I100
  U2D1   DY67  DDR4_DQS_DP<8>  SKX_EXT_B_BGA1  I172

M_L_DQS_DP<9>   @BASEBOARD_FAB2_LIB.BASEBOARD_FAB2(SCH_1):M_L_DQS_DP<9>
  J1A2     7  DQS9P  SCONN288_H44441004_PIP  I66
  J9L2     7  DQS9P  SCONN288_H44441003_PIP  I100
  U2D1   CP79  DDR4_DQS_DP<9>  SKX_EXT_B_BGA1  I172

M_L_DQS_DP<10>   @BASEBOARD_FAB2_LIB.BASEBOARD_FAB2(SCH_1):M_L_DQS_DP<10>
  J1A2    18  DQS10P  SCONN288_H44441004_PIP  I66
  J9L2    18  DQS10P  SCONN288_H44441003_PIP  I100
  U2D1   DD79  DDR4_DQS_DP<10>  SKX_EXT_B_BGA1  I172

M_L_DQS_DP<11>   @BASEBOARD_FAB2_LIB.BASEBOARD_FAB2(SCH_1):M_L_DQS_DP<11>
  J1A2    29  DQS11P  SCONN288_H44441004_PIP  I66
  J9L2    29  DQS11P  SCONN288_H44441003_PIP  I100
  U2D1   DV79  DDR4_DQS_DP<11>  SKX_EXT_B_BGA1  I172

M_L_DQS_DP<12>   @BASEBOARD_FAB2_LIB.BASEBOARD_FAB2(SCH_1):M_L_DQS_DP<12>
  J1A2    40  DQS12P  SCONN288_H44441004_PIP  I66
  J9L2    40  DQS12P  SCONN288_H44441003_PIP  I100
  U2D1   DY73  DDR4_DQS_DP<12>  SKX_EXT_B_BGA1  I172

M_L_DQS_DP<13>   @BASEBOARD_FAB2_LIB.BASEBOARD_FAB2(SCH_1):M_L_DQS_DP<13>
  J1A2    99  DQS13P  SCONN288_H44441004_PIP  I66
  J9L2    99  DQS13P  SCONN288_H44441003_PIP  I100
  U2D1   DM41  DDR4_DQS_DP<13>  SKX_EXT_B_BGA1  I172

M_L_DQS_DP<14>   @BASEBOARD_FAB2_LIB.BASEBOARD_FAB2(SCH_1):M_L_DQS_DP<14>
  J1A2   110  DQS14P  SCONN288_H44441004_PIP  I66
  J9L2   110  DQS14P  SCONN288_H44441003_PIP  I100
  U2D1   DW32  DDR4_DQS_DP<14>  SKX_EXT_B_BGA1  I172

M_L_DQS_DP<15>   @BASEBOARD_FAB2_LIB.BASEBOARD_FAB2(SCH_1):M_L_DQS_DP<15>
  J1A2   121  DQS15P  SCONN288_H44441004_PIP  I66
  J9L2   121  DQS15P  SCONN288_H44441003_PIP  I100
  U2D1   DW26  DDR4_DQS_DP<15>  SKX_EXT_B_BGA1  I172

M_L_DQS_DP<16>   @BASEBOARD_FAB2_LIB.BASEBOARD_FAB2(SCH_1):M_L_DQS_DP<16>
  J1A2   132  DQS16P  SCONN288_H44441004_PIP  I66
  J9L2   132  DQS16P  SCONN288_H44441003_PIP  I100
  U2D1   DE26  DDR4_DQS_DP<16>  SKX_EXT_B_BGA1  I172

M_L_DQS_DP<17>   @BASEBOARD_FAB2_LIB.BASEBOARD_FAB2(SCH_1):M_L_DQS_DP<17>
  J1A2    51  DQS17P  SCONN288_H44441004_PIP  I66
  J9L2    51  DQS17P  SCONN288_H44441003_PIP  I100
  U2D1   DT67  DDR4_DQS_DP<17>  SKX_EXT_B_BGA1  I172

M_L_ECC<0>      @BASEBOARD_FAB2_LIB.BASEBOARD_FAB2(SCH_1):M_L_ECC<0>
  J1A2   194  CB<1>  SCONN288_H44441004_PIP  I111
  J9L2    49  CB<0>  SCONN288_H44441003_PIP  I12
  U2D1   DY69  DDR4_ECC<0>  SKX_EXT_B_BGA1  I172

M_L_ECC<1>      @BASEBOARD_FAB2_LIB.BASEBOARD_FAB2(SCH_1):M_L_ECC<1>
  J1A2    49  CB<0>  SCONN288_H44441004_PIP  I111
  J9L2   194  CB<1>  SCONN288_H44441003_PIP  I12
  U2D1   EA68  DDR4_ECC<1>  SKX_EXT_B_BGA1  I172

M_L_ECC<2>      @BASEBOARD_FAB2_LIB.BASEBOARD_FAB2(SCH_1):M_L_ECC<2>
  J1A2   201  CB<3>  SCONN288_H44441004_PIP  I111
  J9L2    56  CB<2>  SCONN288_H44441003_PIP  I12
  U2D1   DV65  DDR4_ECC<2>  SKX_EXT_B_BGA1  I172

M_L_ECC<3>      @BASEBOARD_FAB2_LIB.BASEBOARD_FAB2(SCH_1):M_L_ECC<3>
  J1A2    56  CB<2>  SCONN288_H44441004_PIP  I111
  J9L2   201  CB<3>  SCONN288_H44441003_PIP  I12
  U2D1   DY65  DDR4_ECC<3>  SKX_EXT_B_BGA1  I172

M_L_ECC<4>      @BASEBOARD_FAB2_LIB.BASEBOARD_FAB2(SCH_1):M_L_ECC<4>
  J1A2   192  CB<5>  SCONN288_H44441004_PIP  I111
  J9L2    47  CB<4>  SCONN288_H44441003_PIP  I12
  U2D1   DU68  DDR4_ECC<4>  SKX_EXT_B_BGA1  I172

M_L_ECC<5>      @BASEBOARD_FAB2_LIB.BASEBOARD_FAB2(SCH_1):M_L_ECC<5>
  J1A2    47  CB<4>  SCONN288_H44441004_PIP  I111
  J9L2   192  CB<5>  SCONN288_H44441003_PIP  I12
  U2D1   DV69  DDR4_ECC<5>  SKX_EXT_B_BGA1  I172

M_L_ECC<6>      @BASEBOARD_FAB2_LIB.BASEBOARD_FAB2(SCH_1):M_L_ECC<6>
  J1A2   199  CB<7>  SCONN288_H44441004_PIP  I111
  J9L2    54  CB<6>  SCONN288_H44441003_PIP  I12
  U2D1   DU66  DDR4_ECC<6>  SKX_EXT_B_BGA1  I172

M_L_ECC<7>      @BASEBOARD_FAB2_LIB.BASEBOARD_FAB2(SCH_1):M_L_ECC<7>
  J1A2    54  CB<6>  SCONN288_H44441004_PIP  I111
  J9L2   199  CB<7>  SCONN288_H44441003_PIP  I12
  U2D1   EA66  DDR4_ECC<7>  SKX_EXT_B_BGA1  I172

M_L_MA<0>       @BASEBOARD_FAB2_LIB.BASEBOARD_FAB2(SCH_1):M_L_MA<0>
  J1A2    79     A0  SCONN288_H44441004_PIP  I111
  J9L2    79     A0  SCONN288_H44441003_PIP  I12
  U2D1   DW52  DDR4_MA<0>  SKX_EXT_B_BGA1  I172

M_L_MA<1>       @BASEBOARD_FAB2_LIB.BASEBOARD_FAB2(SCH_1):M_L_MA<1>
  J1A2    72     A1  SCONN288_H44441004_PIP  I111
  J9L2    72     A1  SCONN288_H44441003_PIP  I12
  U2D1   DW58  DDR4_MA<1>  SKX_EXT_B_BGA1  I172

M_L_MA<2>       @BASEBOARD_FAB2_LIB.BASEBOARD_FAB2(SCH_1):M_L_MA<2>
  J1A2   216     A2  SCONN288_H44441004_PIP  I111
  J9L2   216     A2  SCONN288_H44441003_PIP  I12
  U2D1   DV57  DDR4_MA<2>  SKX_EXT_B_BGA1  I172

M_L_MA<3>       @BASEBOARD_FAB2_LIB.BASEBOARD_FAB2(SCH_1):M_L_MA<3>
  J1A2    71     A3  SCONN288_H44441004_PIP  I111
  J9L2    71     A3  SCONN288_H44441003_PIP  I12
  U2D1   DR58  DDR4_MA<3>  SKX_EXT_B_BGA1  I172

M_L_MA<4>       @BASEBOARD_FAB2_LIB.BASEBOARD_FAB2(SCH_1):M_L_MA<4>
  J1A2   214     A4  SCONN288_H44441004_PIP  I111
  J9L2   214     A4  SCONN288_H44441003_PIP  I12
  U2D1   DT59  DDR4_MA<4>  SKX_EXT_B_BGA1  I172

M_L_MA<5>       @BASEBOARD_FAB2_LIB.BASEBOARD_FAB2(SCH_1):M_L_MA<5>
  J1A2   213     A5  SCONN288_H44441004_PIP  I111
  J9L2   213     A5  SCONN288_H44441003_PIP  I12
  U2D1   DN58  DDR4_MA<5>  SKX_EXT_B_BGA1  I172

M_L_MA<6>       @BASEBOARD_FAB2_LIB.BASEBOARD_FAB2(SCH_1):M_L_MA<6>
  J1A2    69     A6  SCONN288_H44441004_PIP  I111
  J9L2    69     A6  SCONN288_H44441003_PIP  I12
  U2D1   DM59  DDR4_MA<6>  SKX_EXT_B_BGA1  I172

M_L_MA<7>       @BASEBOARD_FAB2_LIB.BASEBOARD_FAB2(SCH_1):M_L_MA<7>
  J1A2   211     A7  SCONN288_H44441004_PIP  I111
  J9L2   211     A7  SCONN288_H44441003_PIP  I12
  U2D1   DK61  DDR4_MA<7>  SKX_EXT_B_BGA1  I172

M_L_MA<8>       @BASEBOARD_FAB2_LIB.BASEBOARD_FAB2(SCH_1):M_L_MA<8>
  J1A2    68     A8  SCONN288_H44441004_PIP  I111
  J9L2    68     A8  SCONN288_H44441003_PIP  I12
  U2D1   DJ60  DDR4_MA<8>  SKX_EXT_B_BGA1  I172

M_L_MA<9>       @BASEBOARD_FAB2_LIB.BASEBOARD_FAB2(SCH_1):M_L_MA<9>
  J1A2    66     A9  SCONN288_H44441004_PIP  I111
  J9L2    66     A9  SCONN288_H44441003_PIP  I12
  U2D1   DV59  DDR4_MA<9>  SKX_EXT_B_BGA1  I172

M_L_MA<10>      @BASEBOARD_FAB2_LIB.BASEBOARD_FAB2(SCH_1):M_L_MA<10>
  J1A2   225    A10  SCONN288_H44441004_PIP  I111
  J9L2   225    A10  SCONN288_H44441003_PIP  I12
  U2D1   DT55  DDR4_MA<10>  SKX_EXT_B_BGA1  I172

M_L_MA<11>      @BASEBOARD_FAB2_LIB.BASEBOARD_FAB2(SCH_1):M_L_MA<11>
  J1A2   210    A11  SCONN288_H44441004_PIP  I111
  J9L2   210    A11  SCONN288_H44441003_PIP  I12
  U2D1   DR60  DDR4_MA<11>  SKX_EXT_B_BGA1  I172

M_L_MA<12>      @BASEBOARD_FAB2_LIB.BASEBOARD_FAB2(SCH_1):M_L_MA<12>
  J1A2    65    A12  SCONN288_H44441004_PIP  I111
  J9L2    65    A12  SCONN288_H44441003_PIP  I12
  U2D1   DN60  DDR4_MA<12>  SKX_EXT_B_BGA1  I172

M_L_MA<13>      @BASEBOARD_FAB2_LIB.BASEBOARD_FAB2(SCH_1):M_L_MA<13>
  J1A2   232    A13  SCONN288_H44441004_PIP  I111
  J9L2   232    A13  SCONN288_H44441003_PIP  I12
  U2D1   DT51  DDR4_MA<13>  SKX_EXT_B_BGA1  I172

M_L_MA<14>      @BASEBOARD_FAB2_LIB.BASEBOARD_FAB2(SCH_1):M_L_MA<14>
  J1A2   228  A14_WE_N  SCONN288_H44441004_PIP  I111
  J9L2   228  A14_WE_N  SCONN288_H44441003_PIP  I12
  U2D1   DM51  DDR4_MA<14>  SKX_EXT_B_BGA1  I172

M_L_MA<15>      @BASEBOARD_FAB2_LIB.BASEBOARD_FAB2(SCH_1):M_L_MA<15>
  J1A2    86  A15_CAS_N  SCONN288_H44441004_PIP  I111
  J9L2    86  A15_CAS_N  SCONN288_H44441003_PIP  I12
  U2D1   DR52  DDR4_MA<15>  SKX_EXT_B_BGA1  I172

M_L_MA<16>      @BASEBOARD_FAB2_LIB.BASEBOARD_FAB2(SCH_1):M_L_MA<16>
  J1A2    82  A16_RAS_N  SCONN288_H44441004_PIP  I111
  J9L2    82  A16_RAS_N  SCONN288_H44441003_PIP  I12
  U2D1   DN52  DDR4_MA<16>  SKX_EXT_B_BGA1  I172

M_L_MA<17>      @BASEBOARD_FAB2_LIB.BASEBOARD_FAB2(SCH_1):M_L_MA<17>
  J1A2   234    A17  SCONN288_H44441004_PIP  I111
  J9L2   234    A17  SCONN288_H44441003_PIP  I12
  U2D1   DR48  DDR4_MA<17>  SKX_EXT_B_BGA1  I172

M_L_ODT<0>      @BASEBOARD_FAB2_LIB.BASEBOARD_FAB2(SCH_1):M_L_ODT<0>
  J1A2    87  ODT<0>  SCONN288_H44441004_PIP  I111
  U2D1   DR50  DDR4_ODT<0>  SKX_EXT_B_BGA1  I172

M_L_ODT<1>      @BASEBOARD_FAB2_LIB.BASEBOARD_FAB2(SCH_1):M_L_ODT<1>
  J1A2    91  ODT<1>  SCONN288_H44441004_PIP  I111
  U2D1   DN48  DDR4_ODT<1>  SKX_EXT_B_BGA1  I172

M_L_ODT<2>      @BASEBOARD_FAB2_LIB.BASEBOARD_FAB2(SCH_1):M_L_ODT<2>
  J9L2    87  ODT<0>  SCONN288_H44441003_PIP  I12
  U2D1   DT49  DDR4_ODT<2>  SKX_EXT_B_BGA1  I172

M_L_ODT<3>      @BASEBOARD_FAB2_LIB.BASEBOARD_FAB2(SCH_1):M_L_ODT<3>
  J9L2    91  ODT<1>  SCONN288_H44441003_PIP  I12
  U2D1   DM47  DDR4_ODT<3>  SKX_EXT_B_BGA1  I172

M_L_PAR         @BASEBOARD_FAB2_LIB.BASEBOARD_FAB2(SCH_1):M_L_PAR
  J1A2   222    PAR  SCONN288_H44441004_PIP  I111
  J9L2   222    PAR  SCONN288_H44441003_PIP  I12
  U2D1   DV53  DDR4_PAR  SKX_EXT_B_BGA1  I172

M_L_VREF        @BASEBOARD_FAB2_LIB.BASEBOARD_FAB2(SCH_1):M_L_VREF
  C1A17    1      A  CAP_A       I182
  C9L7     1      A  CAP_A       I181
  J1A2   146  VREFCA  SCONN288_H44441004_PIP  I111
  J9L2   146  VREFCA  SCONN288_H44441003_PIP  I12
  R9L6     1      A  RES         I24
  R9L7     2      B  RES         I22
  R9L8     2      B  RES         I29

M_M_ACT_N       @BASEBOARD_FAB2_LIB.BASEBOARD_FAB2(SCH_1):M_M_ACT_N
  J1A1    62  ACT_N  SCONN288_H44441004_PIP  I186
  J9L1    62  ACT_N  SCONN288_H44441003_PIP  I111
  U2D1   DC62  DDR5_ACT_N  SKX_EXT_B_BGA1  I172

M_M_ALERT_N     @BASEBOARD_FAB2_LIB.BASEBOARD_FAB2(SCH_1):M_M_ALERT_N
  J1A1   208  ALERT_N  SCONN288_H44441004_PIP  I186
  J9L1   208  ALERT_N  SCONN288_H44441003_PIP  I111
  U2D1   DD61  DDR5_ALERT_N  SKX_EXT_B_BGA1  I172

M_M_BA<0>       @BASEBOARD_FAB2_LIB.BASEBOARD_FAB2(SCH_1):M_M_BA<0>
  J1A1    81  BA<0>  SCONN288_H44441004_PIP  I186
  J9L1    81  BA<0>  SCONN288_H44441003_PIP  I111
  U2D1   DJ52  DDR5_BA<0>  SKX_EXT_B_BGA1  I172

M_M_BA<1>       @BASEBOARD_FAB2_LIB.BASEBOARD_FAB2(SCH_1):M_M_BA<1>
  J1A1   224  BA<1>  SCONN288_H44441004_PIP  I186
  J9L1   224  BA<1>  SCONN288_H44441003_PIP  I111
  U2D1   DC56  DDR5_BA<1>  SKX_EXT_B_BGA1  I172

M_M_BG<0>       @BASEBOARD_FAB2_LIB.BASEBOARD_FAB2(SCH_1):M_M_BG<0>
  J1A1    63  BG<0>  SCONN288_H44441004_PIP  I186
  J9L1    63  BG<0>  SCONN288_H44441003_PIP  I111
  U2D1   DA62  DDR5_BG<0>  SKX_EXT_B_BGA1  I172

M_M_BG<1>       @BASEBOARD_FAB2_LIB.BASEBOARD_FAB2(SCH_1):M_M_BG<1>
  J1A1   207  BG<1>  SCONN288_H44441004_PIP  I186
  J9L1   207  BG<1>  SCONN288_H44441003_PIP  I111
  U2D1   DF61  DDR5_BG<1>  SKX_EXT_B_BGA1  I172

M_M_C<2>        @BASEBOARD_FAB2_LIB.BASEBOARD_FAB2(SCH_1):M_M_C<2>
  J1A1   235   C<2>  SCONN288_H44441004_PIP  I186
  J9L1   235   C<2>  SCONN288_H44441003_PIP  I111
  U2D1   DF45  DDR5_CID<2>  SKX_EXT_B_BGA1  I172

M_M_CKE<0>      @BASEBOARD_FAB2_LIB.BASEBOARD_FAB2(SCH_1):M_M_CKE<0>
  J1A1    60  CKE<0>  SCONN288_H44441004_PIP  I186
  U2D1   DG62  DDR5_CKE<0>  SKX_EXT_B_BGA1  I172

M_M_CKE<1>      @BASEBOARD_FAB2_LIB.BASEBOARD_FAB2(SCH_1):M_M_CKE<1>
  J1A1   203  CKE<1>  SCONN288_H44441004_PIP  I186
  U2D1   DD63  DDR5_CKE<1>  SKX_EXT_B_BGA1  I172

M_M_CKE<2>      @BASEBOARD_FAB2_LIB.BASEBOARD_FAB2(SCH_1):M_M_CKE<2>
  J9L1    60  CKE<0>  SCONN288_H44441003_PIP  I111
  U2D1   DK63  DDR5_CKE<2>  SKX_EXT_B_BGA1  I172

M_M_CKE<3>      @BASEBOARD_FAB2_LIB.BASEBOARD_FAB2(SCH_1):M_M_CKE<3>
  J9L1   203  CKE<1>  SCONN288_H44441003_PIP  I111
  U2D1   DF63  DDR5_CKE<3>  SKX_EXT_B_BGA1  I172

M_M_CLK_DN<0>   @BASEBOARD_FAB2_LIB.BASEBOARD_FAB2(SCH_1):M_M_CLK_DN<0>
  J1A1    75   CK0N  SCONN288_H44441004_PIP  I186
  U2D1   DK55  DDR5_CLK_DN<0>  SKX_EXT_B_BGA1  I172

M_M_CLK_DN<1>   @BASEBOARD_FAB2_LIB.BASEBOARD_FAB2(SCH_1):M_M_CLK_DN<1>
  J1A1   219   CK1N  SCONN288_H44441004_PIP  I186
  U2D1   DF55  DDR5_CLK_DN<1>  SKX_EXT_B_BGA1  I172

M_M_CLK_DN<2>   @BASEBOARD_FAB2_LIB.BASEBOARD_FAB2(SCH_1):M_M_CLK_DN<2>
  J9L1    75   CK0N  SCONN288_H44441003_PIP  I111
  U2D1   DK57  DDR5_CLK_DN<2>  SKX_EXT_B_BGA1  I172

M_M_CLK_DN<3>   @BASEBOARD_FAB2_LIB.BASEBOARD_FAB2(SCH_1):M_M_CLK_DN<3>
  J9L1   219   CK1N  SCONN288_H44441003_PIP  I111
  U2D1   DF57  DDR5_CLK_DN<3>  SKX_EXT_B_BGA1  I172

M_M_CLK_DP<0>   @BASEBOARD_FAB2_LIB.BASEBOARD_FAB2(SCH_1):M_M_CLK_DP<0>
  J1A1    74   CK0P  SCONN288_H44441004_PIP  I186
  U2D1   DJ54  DDR5_CLK_DP<0>  SKX_EXT_B_BGA1  I172

M_M_CLK_DP<1>   @BASEBOARD_FAB2_LIB.BASEBOARD_FAB2(SCH_1):M_M_CLK_DP<1>
  J1A1   218   CK1P  SCONN288_H44441004_PIP  I186
  U2D1   DG54  DDR5_CLK_DP<1>  SKX_EXT_B_BGA1  I172

M_M_CLK_DP<2>   @BASEBOARD_FAB2_LIB.BASEBOARD_FAB2(SCH_1):M_M_CLK_DP<2>
  J9L1    74   CK0P  SCONN288_H44441003_PIP  I111
  U2D1   DJ56  DDR5_CLK_DP<2>  SKX_EXT_B_BGA1  I172

M_M_CLK_DP<3>   @BASEBOARD_FAB2_LIB.BASEBOARD_FAB2(SCH_1):M_M_CLK_DP<3>
  J9L1   218   CK1P  SCONN288_H44441003_PIP  I111
  U2D1   DG56  DDR5_CLK_DP<3>  SKX_EXT_B_BGA1  I172

M_M_CPU_VREF    @BASEBOARD_FAB2_LIB.BASEBOARD_FAB2(SCH_1):M_M_CPU_VREF
  C9L3     1      A  CAP_A       I46
  R9L3     1      A  RES         I45
  U2D1   CV61  DDR5_CAVREF  SKX_EXT_B_BGA1  I172

M_M_CS_N<0>     @BASEBOARD_FAB2_LIB.BASEBOARD_FAB2(SCH_1):M_M_CS_N<0>
  J1A1    84   S0_N  SCONN288_H44441004_PIP  I186
  U2D1   DK51  DDR5_CS_N<0>  SKX_EXT_B_BGA1  I172

M_M_CS_N<1>     @BASEBOARD_FAB2_LIB.BASEBOARD_FAB2(SCH_1):M_M_CS_N<1>
  J1A1    89   S1_N  SCONN288_H44441004_PIP  I186
  U2D1   DF49  DDR5_CS_N<1>  SKX_EXT_B_BGA1  I172

M_M_CS_N<2>     @BASEBOARD_FAB2_LIB.BASEBOARD_FAB2(SCH_1):M_M_CS_N<2>
  J1A1    93  S2_N_C<0>  SCONN288_H44441004_PIP  I186
  U2D1   DJ46  DDR5_CS_N<2>  SKX_EXT_B_BGA1  I172

M_M_CS_N<3>     @BASEBOARD_FAB2_LIB.BASEBOARD_FAB2(SCH_1):M_M_CS_N<3>
  J1A1   237  S3_N_C<1>  SCONN288_H44441004_PIP  I186
  U2D1   DG46  DDR5_CS_N<3>  SKX_EXT_B_BGA1  I172

M_M_CS_N<4>     @BASEBOARD_FAB2_LIB.BASEBOARD_FAB2(SCH_1):M_M_CS_N<4>
  J9L1    84   S0_N  SCONN288_H44441003_PIP  I111
  U2D1   DF51  DDR5_CS_N<4>  SKX_EXT_B_BGA1  I172

M_M_CS_N<5>     @BASEBOARD_FAB2_LIB.BASEBOARD_FAB2(SCH_1):M_M_CS_N<5>
  J9L1    89   S1_N  SCONN288_H44441003_PIP  I111
  U2D1   DJ48  DDR5_CS_N<5>  SKX_EXT_B_BGA1  I172

M_M_CS_N<6>     @BASEBOARD_FAB2_LIB.BASEBOARD_FAB2(SCH_1):M_M_CS_N<6>
  J9L1    93  S2_N_C<0>  SCONN288_H44441003_PIP  I111
  U2D1   DM45  DDR5_CS_N<6>  SKX_EXT_B_BGA1  I172

M_M_CS_N<7>     @BASEBOARD_FAB2_LIB.BASEBOARD_FAB2(SCH_1):M_M_CS_N<7>
  J9L1   237  S3_N_C<1>  SCONN288_H44441003_PIP  I111
  U2D1   DK45  DDR5_CS_N<7>  SKX_EXT_B_BGA1  I172

M_M_DQ<0>       @BASEBOARD_FAB2_LIB.BASEBOARD_FAB2(SCH_1):M_M_DQ<0>
  J1A1   150  DQ<1>  SCONN288_H44441004_PIP  I186
  J9L1     5  DQ<0>  SCONN288_H44441003_PIP  I111
  U2D1   CR74  DDR5_DQ<0>  SKX_EXT_B_BGA1  I172

M_M_DQ<1>       @BASEBOARD_FAB2_LIB.BASEBOARD_FAB2(SCH_1):M_M_DQ<1>
  J1A1     5  DQ<0>  SCONN288_H44441004_PIP  I186
  J9L1   150  DQ<1>  SCONN288_H44441003_PIP  I111
  U2D1   CN76  DDR5_DQ<1>  SKX_EXT_B_BGA1  I172

M_M_DQ<2>       @BASEBOARD_FAB2_LIB.BASEBOARD_FAB2(SCH_1):M_M_DQ<2>
  J1A1   157  DQ<3>  SCONN288_H44441004_PIP  I186
  J9L1    12  DQ<2>  SCONN288_H44441003_PIP  I111
  U2D1   CW76  DDR5_DQ<2>  SKX_EXT_B_BGA1  I172

M_M_DQ<3>       @BASEBOARD_FAB2_LIB.BASEBOARD_FAB2(SCH_1):M_M_DQ<3>
  J1A1    12  DQ<2>  SCONN288_H44441004_PIP  I186
  J9L1   157  DQ<3>  SCONN288_H44441003_PIP  I111
  U2D1   CV77  DDR5_DQ<3>  SKX_EXT_B_BGA1  I172

M_M_DQ<4>       @BASEBOARD_FAB2_LIB.BASEBOARD_FAB2(SCH_1):M_M_DQ<4>
  J1A1   148  DQ<5>  SCONN288_H44441004_PIP  I186
  J9L1     3  DQ<4>  SCONN288_H44441003_PIP  I111
  U2D1   CN74  DDR5_DQ<4>  SKX_EXT_B_BGA1  I172

M_M_DQ<5>       @BASEBOARD_FAB2_LIB.BASEBOARD_FAB2(SCH_1):M_M_DQ<5>
  J1A1     3  DQ<4>  SCONN288_H44441004_PIP  I186
  J9L1   148  DQ<5>  SCONN288_H44441003_PIP  I111
  U2D1   CM75  DDR5_DQ<5>  SKX_EXT_B_BGA1  I172

M_M_DQ<6>       @BASEBOARD_FAB2_LIB.BASEBOARD_FAB2(SCH_1):M_M_DQ<6>
  J1A1   155  DQ<7>  SCONN288_H44441004_PIP  I186
  J9L1    10  DQ<6>  SCONN288_H44441003_PIP  I111
  U2D1   CV75  DDR5_DQ<6>  SKX_EXT_B_BGA1  I172

M_M_DQ<7>       @BASEBOARD_FAB2_LIB.BASEBOARD_FAB2(SCH_1):M_M_DQ<7>
  J1A1    10  DQ<6>  SCONN288_H44441004_PIP  I186
  J9L1   155  DQ<7>  SCONN288_H44441003_PIP  I111
  U2D1   CT77  DDR5_DQ<7>  SKX_EXT_B_BGA1  I172

M_M_DQ<8>       @BASEBOARD_FAB2_LIB.BASEBOARD_FAB2(SCH_1):M_M_DQ<8>
  J1A1   161  DQ<9>  SCONN288_H44441004_PIP  I186
  J9L1    16  DQ<8>  SCONN288_H44441003_PIP  I111
  U2D1   DE74  DDR5_DQ<8>  SKX_EXT_B_BGA1  I172

M_M_DQ<9>       @BASEBOARD_FAB2_LIB.BASEBOARD_FAB2(SCH_1):M_M_DQ<9>
  J1A1    16  DQ<8>  SCONN288_H44441004_PIP  I186
  J9L1   161  DQ<9>  SCONN288_H44441003_PIP  I111
  U2D1   DC76  DDR5_DQ<9>  SKX_EXT_B_BGA1  I172

M_M_DQ<10>      @BASEBOARD_FAB2_LIB.BASEBOARD_FAB2(SCH_1):M_M_DQ<10>
  J1A1   168  DQ<11>  SCONN288_H44441004_PIP  I186
  J9L1    23  DQ<10>  SCONN288_H44441003_PIP  I111
  U2D1   DH75  DDR5_DQ<10>  SKX_EXT_B_BGA1  I172

M_M_DQ<11>      @BASEBOARD_FAB2_LIB.BASEBOARD_FAB2(SCH_1):M_M_DQ<11>
  J1A1    23  DQ<10>  SCONN288_H44441004_PIP  I186
  J9L1   168  DQ<11>  SCONN288_H44441003_PIP  I111
  U2D1   DJ76  DDR5_DQ<11>  SKX_EXT_B_BGA1  I172

M_M_DQ<12>      @BASEBOARD_FAB2_LIB.BASEBOARD_FAB2(SCH_1):M_M_DQ<12>
  J1A1   159  DQ<13>  SCONN288_H44441004_PIP  I186
  J9L1    14  DQ<12>  SCONN288_H44441003_PIP  I111
  U2D1   DC74  DDR5_DQ<12>  SKX_EXT_B_BGA1  I172

M_M_DQ<13>      @BASEBOARD_FAB2_LIB.BASEBOARD_FAB2(SCH_1):M_M_DQ<13>
  J1A1    14  DQ<12>  SCONN288_H44441004_PIP  I186
  J9L1   159  DQ<13>  SCONN288_H44441003_PIP  I111
  U2D1   DB75  DDR5_DQ<13>  SKX_EXT_B_BGA1  I172

M_M_DQ<14>      @BASEBOARD_FAB2_LIB.BASEBOARD_FAB2(SCH_1):M_M_DQ<14>
  J1A1   166  DQ<15>  SCONN288_H44441004_PIP  I186
  J9L1    21  DQ<14>  SCONN288_H44441003_PIP  I111
  U2D1   DF77  DDR5_DQ<14>  SKX_EXT_B_BGA1  I172

M_M_DQ<15>      @BASEBOARD_FAB2_LIB.BASEBOARD_FAB2(SCH_1):M_M_DQ<15>
  J1A1    21  DQ<14>  SCONN288_H44441004_PIP  I186
  J9L1   166  DQ<15>  SCONN288_H44441003_PIP  I111
  U2D1   DH77  DDR5_DQ<15>  SKX_EXT_B_BGA1  I172

M_M_DQ<16>      @BASEBOARD_FAB2_LIB.BASEBOARD_FAB2(SCH_1):M_M_DQ<16>
  J1A1   172  DQ<17>  SCONN288_H44441004_PIP  I186
  J9L1    27  DQ<16>  SCONN288_H44441003_PIP  I111
  U2D1   DG70  DDR5_DQ<16>  SKX_EXT_B_BGA1  I172

M_M_DQ<17>      @BASEBOARD_FAB2_LIB.BASEBOARD_FAB2(SCH_1):M_M_DQ<17>
  J1A1    27  DQ<16>  SCONN288_H44441004_PIP  I186
  J9L1   172  DQ<17>  SCONN288_H44441003_PIP  I111
  U2D1   DJ72  DDR5_DQ<17>  SKX_EXT_B_BGA1  I172

M_M_DQ<18>      @BASEBOARD_FAB2_LIB.BASEBOARD_FAB2(SCH_1):M_M_DQ<18>
  J1A1   179  DQ<19>  SCONN288_H44441004_PIP  I186
  J9L1    34  DQ<18>  SCONN288_H44441003_PIP  I111
  U2D1   DM69  DDR5_DQ<18>  SKX_EXT_B_BGA1  I172

M_M_DQ<19>      @BASEBOARD_FAB2_LIB.BASEBOARD_FAB2(SCH_1):M_M_DQ<19>
  J1A1    34  DQ<18>  SCONN288_H44441004_PIP  I186
  J9L1   179  DQ<19>  SCONN288_H44441003_PIP  I111
  U2D1   DN70  DDR5_DQ<19>  SKX_EXT_B_BGA1  I172

M_M_DQ<20>      @BASEBOARD_FAB2_LIB.BASEBOARD_FAB2(SCH_1):M_M_DQ<20>
  J1A1   170  DQ<21>  SCONN288_H44441004_PIP  I186
  J9L1    25  DQ<20>  SCONN288_H44441003_PIP  I111
  U2D1   DF71  DDR5_DQ<20>  SKX_EXT_B_BGA1  I172

M_M_DQ<21>      @BASEBOARD_FAB2_LIB.BASEBOARD_FAB2(SCH_1):M_M_DQ<21>
  J1A1    25  DQ<20>  SCONN288_H44441004_PIP  I186
  J9L1   170  DQ<21>  SCONN288_H44441003_PIP  I111
  U2D1   DG72  DDR5_DQ<21>  SKX_EXT_B_BGA1  I172

M_M_DQ<22>      @BASEBOARD_FAB2_LIB.BASEBOARD_FAB2(SCH_1):M_M_DQ<22>
  J1A1   177  DQ<23>  SCONN288_H44441004_PIP  I186
  J9L1    32  DQ<22>  SCONN288_H44441003_PIP  I111
  U2D1   DK69  DDR5_DQ<22>  SKX_EXT_B_BGA1  I172

M_M_DQ<23>      @BASEBOARD_FAB2_LIB.BASEBOARD_FAB2(SCH_1):M_M_DQ<23>
  J1A1    32  DQ<22>  SCONN288_H44441004_PIP  I186
  J9L1   177  DQ<23>  SCONN288_H44441003_PIP  I111
  U2D1   DM71  DDR5_DQ<23>  SKX_EXT_B_BGA1  I172

M_M_DQ<24>      @BASEBOARD_FAB2_LIB.BASEBOARD_FAB2(SCH_1):M_M_DQ<24>
  J1A1   183  DQ<25>  SCONN288_H44441004_PIP  I186
  J9L1    38  DQ<24>  SCONN288_H44441003_PIP  I111
  U2D1   CN66  DDR5_DQ<24>  SKX_EXT_B_BGA1  I172

M_M_DQ<25>      @BASEBOARD_FAB2_LIB.BASEBOARD_FAB2(SCH_1):M_M_DQ<25>
  J1A1    38  DQ<24>  SCONN288_H44441004_PIP  I186
  J9L1   183  DQ<25>  SCONN288_H44441003_PIP  I111
  U2D1   CU66  DDR5_DQ<25>  SKX_EXT_B_BGA1  I172

M_M_DQ<26>      @BASEBOARD_FAB2_LIB.BASEBOARD_FAB2(SCH_1):M_M_DQ<26>
  J1A1   190  DQ<27>  SCONN288_H44441004_PIP  I186
  J9L1    45  DQ<26>  SCONN288_H44441003_PIP  I111
  U2D1   CP63  DDR5_DQ<26>  SKX_EXT_B_BGA1  I172

M_M_DQ<27>      @BASEBOARD_FAB2_LIB.BASEBOARD_FAB2(SCH_1):M_M_DQ<27>
  J1A1    45  DQ<26>  SCONN288_H44441004_PIP  I186
  J9L1   190  DQ<27>  SCONN288_H44441003_PIP  I111
  U2D1   CT63  DDR5_DQ<27>  SKX_EXT_B_BGA1  I172

M_M_DQ<28>      @BASEBOARD_FAB2_LIB.BASEBOARD_FAB2(SCH_1):M_M_DQ<28>
  J1A1   181  DQ<29>  SCONN288_H44441004_PIP  I186
  J9L1    36  DQ<28>  SCONN288_H44441003_PIP  I111
  U2D1   CP67  DDR5_DQ<28>  SKX_EXT_B_BGA1  I172

M_M_DQ<29>      @BASEBOARD_FAB2_LIB.BASEBOARD_FAB2(SCH_1):M_M_DQ<29>
  J1A1    36  DQ<28>  SCONN288_H44441004_PIP  I186
  J9L1   181  DQ<29>  SCONN288_H44441003_PIP  I111
  U2D1   CT67  DDR5_DQ<29>  SKX_EXT_B_BGA1  I172

M_M_DQ<30>      @BASEBOARD_FAB2_LIB.BASEBOARD_FAB2(SCH_1):M_M_DQ<30>
  J1A1   188  DQ<31>  SCONN288_H44441004_PIP  I186
  J9L1    43  DQ<30>  SCONN288_H44441003_PIP  I111
  U2D1   CN64  DDR5_DQ<30>  SKX_EXT_B_BGA1  I172

M_M_DQ<31>      @BASEBOARD_FAB2_LIB.BASEBOARD_FAB2(SCH_1):M_M_DQ<31>
  J1A1    43  DQ<30>  SCONN288_H44441004_PIP  I186
  J9L1   188  DQ<31>  SCONN288_H44441003_PIP  I111
  U2D1   CU64  DDR5_DQ<31>  SKX_EXT_B_BGA1  I172

M_M_DQ<32>      @BASEBOARD_FAB2_LIB.BASEBOARD_FAB2(SCH_1):M_M_DQ<32>
  J1A1   242  DQ<33>  SCONN288_H44441004_PIP  I186
  J9L1    97  DQ<32>  SCONN288_H44441003_PIP  I111
  U2D1   DD41  DDR5_DQ<32>  SKX_EXT_B_BGA1  I172

M_M_DQ<33>      @BASEBOARD_FAB2_LIB.BASEBOARD_FAB2(SCH_1):M_M_DQ<33>
  J1A1    97  DQ<32>  SCONN288_H44441004_PIP  I186
  J9L1   242  DQ<33>  SCONN288_H44441003_PIP  I111
  U2D1   DG42  DDR5_DQ<33>  SKX_EXT_B_BGA1  I172

M_M_DQ<34>      @BASEBOARD_FAB2_LIB.BASEBOARD_FAB2(SCH_1):M_M_DQ<34>
  J1A1   249  DQ<35>  SCONN288_H44441004_PIP  I186
  J9L1   104  DQ<34>  SCONN288_H44441003_PIP  I111
  U2D1   DE38  DDR5_DQ<34>  SKX_EXT_B_BGA1  I172

M_M_DQ<35>      @BASEBOARD_FAB2_LIB.BASEBOARD_FAB2(SCH_1):M_M_DQ<35>
  J1A1   104  DQ<34>  SCONN288_H44441004_PIP  I186
  J9L1   249  DQ<35>  SCONN288_H44441003_PIP  I111
  U2D1   DG38  DDR5_DQ<35>  SKX_EXT_B_BGA1  I172

M_M_DQ<36>      @BASEBOARD_FAB2_LIB.BASEBOARD_FAB2(SCH_1):M_M_DQ<36>
  J1A1   240  DQ<37>  SCONN288_H44441004_PIP  I186
  J9L1    95  DQ<36>  SCONN288_H44441003_PIP  I111
  U2D1   DA42  DDR5_DQ<36>  SKX_EXT_B_BGA1  I172

M_M_DQ<37>      @BASEBOARD_FAB2_LIB.BASEBOARD_FAB2(SCH_1):M_M_DQ<37>
  J1A1    95  DQ<36>  SCONN288_H44441004_PIP  I186
  J9L1   240  DQ<37>  SCONN288_H44441003_PIP  I111
  U2D1   DE42  DDR5_DQ<37>  SKX_EXT_B_BGA1  I172

M_M_DQ<38>      @BASEBOARD_FAB2_LIB.BASEBOARD_FAB2(SCH_1):M_M_DQ<38>
  J1A1   247  DQ<39>  SCONN288_H44441004_PIP  I186
  J9L1   102  DQ<38>  SCONN288_H44441003_PIP  I111
  U2D1   DD39  DDR5_DQ<38>  SKX_EXT_B_BGA1  I172

M_M_DQ<39>      @BASEBOARD_FAB2_LIB.BASEBOARD_FAB2(SCH_1):M_M_DQ<39>
  J1A1   102  DQ<38>  SCONN288_H44441004_PIP  I186
  J9L1   247  DQ<39>  SCONN288_H44441003_PIP  I111
  U2D1   DH39  DDR5_DQ<39>  SKX_EXT_B_BGA1  I172

M_M_DQ<40>      @BASEBOARD_FAB2_LIB.BASEBOARD_FAB2(SCH_1):M_M_DQ<40>
  J1A1   253  DQ<41>  SCONN288_H44441004_PIP  I186
  J9L1   108  DQ<40>  SCONN288_H44441003_PIP  I111
  U2D1   DF33  DDR5_DQ<40>  SKX_EXT_B_BGA1  I172

M_M_DQ<41>      @BASEBOARD_FAB2_LIB.BASEBOARD_FAB2(SCH_1):M_M_DQ<41>
  J1A1   108  DQ<40>  SCONN288_H44441004_PIP  I186
  J9L1   253  DQ<41>  SCONN288_H44441003_PIP  I111
  U2D1   DK33  DDR5_DQ<41>  SKX_EXT_B_BGA1  I172

M_M_DQ<42>      @BASEBOARD_FAB2_LIB.BASEBOARD_FAB2(SCH_1):M_M_DQ<42>
  J1A1   260  DQ<43>  SCONN288_H44441004_PIP  I186
  J9L1   115  DQ<42>  SCONN288_H44441003_PIP  I111
  U2D1   DG30  DDR5_DQ<42>  SKX_EXT_B_BGA1  I172

M_M_DQ<43>      @BASEBOARD_FAB2_LIB.BASEBOARD_FAB2(SCH_1):M_M_DQ<43>
  J1A1   115  DQ<42>  SCONN288_H44441004_PIP  I186
  J9L1   260  DQ<43>  SCONN288_H44441003_PIP  I111
  U2D1   DJ30  DDR5_DQ<43>  SKX_EXT_B_BGA1  I172

M_M_DQ<44>      @BASEBOARD_FAB2_LIB.BASEBOARD_FAB2(SCH_1):M_M_DQ<44>
  J1A1   251  DQ<45>  SCONN288_H44441004_PIP  I186
  J9L1   106  DQ<44>  SCONN288_H44441003_PIP  I111
  U2D1   DG34  DDR5_DQ<44>  SKX_EXT_B_BGA1  I172

M_M_DQ<45>      @BASEBOARD_FAB2_LIB.BASEBOARD_FAB2(SCH_1):M_M_DQ<45>
  J1A1   106  DQ<44>  SCONN288_H44441004_PIP  I186
  J9L1   251  DQ<45>  SCONN288_H44441003_PIP  I111
  U2D1   DJ34  DDR5_DQ<45>  SKX_EXT_B_BGA1  I172

M_M_DQ<46>      @BASEBOARD_FAB2_LIB.BASEBOARD_FAB2(SCH_1):M_M_DQ<46>
  J1A1   258  DQ<47>  SCONN288_H44441004_PIP  I186
  J9L1   113  DQ<46>  SCONN288_H44441003_PIP  I111
  U2D1   DF31  DDR5_DQ<46>  SKX_EXT_B_BGA1  I172

M_M_DQ<47>      @BASEBOARD_FAB2_LIB.BASEBOARD_FAB2(SCH_1):M_M_DQ<47>
  J1A1   113  DQ<46>  SCONN288_H44441004_PIP  I186
  J9L1   258  DQ<47>  SCONN288_H44441003_PIP  I111
  U2D1   DK31  DDR5_DQ<47>  SKX_EXT_B_BGA1  I172

M_M_DQ<48>      @BASEBOARD_FAB2_LIB.BASEBOARD_FAB2(SCH_1):M_M_DQ<48>
  J1A1   264  DQ<49>  SCONN288_H44441004_PIP  I186
  J9L1   119  DQ<48>  SCONN288_H44441003_PIP  I111
  U2D1   CW36  DDR5_DQ<48>  SKX_EXT_B_BGA1  I172

M_M_DQ<49>      @BASEBOARD_FAB2_LIB.BASEBOARD_FAB2(SCH_1):M_M_DQ<49>
  J1A1   119  DQ<48>  SCONN288_H44441004_PIP  I186
  J9L1   264  DQ<49>  SCONN288_H44441003_PIP  I111
  U2D1   DC36  DDR5_DQ<49>  SKX_EXT_B_BGA1  I172

M_M_DQ<50>      @BASEBOARD_FAB2_LIB.BASEBOARD_FAB2(SCH_1):M_M_DQ<50>
  J1A1   271  DQ<51>  SCONN288_H44441004_PIP  I186
  J9L1   126  DQ<50>  SCONN288_H44441003_PIP  I111
  U2D1   CY33  DDR5_DQ<50>  SKX_EXT_B_BGA1  I172

M_M_DQ<51>      @BASEBOARD_FAB2_LIB.BASEBOARD_FAB2(SCH_1):M_M_DQ<51>
  J1A1   126  DQ<50>  SCONN288_H44441004_PIP  I186
  J9L1   271  DQ<51>  SCONN288_H44441003_PIP  I111
  U2D1   DB33  DDR5_DQ<51>  SKX_EXT_B_BGA1  I172

M_M_DQ<52>      @BASEBOARD_FAB2_LIB.BASEBOARD_FAB2(SCH_1):M_M_DQ<52>
  J1A1   262  DQ<53>  SCONN288_H44441004_PIP  I186
  J9L1   117  DQ<52>  SCONN288_H44441003_PIP  I111
  U2D1   CY37  DDR5_DQ<52>  SKX_EXT_B_BGA1  I172

M_M_DQ<53>      @BASEBOARD_FAB2_LIB.BASEBOARD_FAB2(SCH_1):M_M_DQ<53>
  J1A1   117  DQ<52>  SCONN288_H44441004_PIP  I186
  J9L1   262  DQ<53>  SCONN288_H44441003_PIP  I111
  U2D1   DB37  DDR5_DQ<53>  SKX_EXT_B_BGA1  I172

M_M_DQ<54>      @BASEBOARD_FAB2_LIB.BASEBOARD_FAB2(SCH_1):M_M_DQ<54>
  J1A1   269  DQ<55>  SCONN288_H44441004_PIP  I186
  J9L1   124  DQ<54>  SCONN288_H44441003_PIP  I111
  U2D1   CW34  DDR5_DQ<54>  SKX_EXT_B_BGA1  I172

M_M_DQ<55>      @BASEBOARD_FAB2_LIB.BASEBOARD_FAB2(SCH_1):M_M_DQ<55>
  J1A1   124  DQ<54>  SCONN288_H44441004_PIP  I186
  J9L1   269  DQ<55>  SCONN288_H44441003_PIP  I111
  U2D1   DC34  DDR5_DQ<55>  SKX_EXT_B_BGA1  I172

M_M_DQ<56>      @BASEBOARD_FAB2_LIB.BASEBOARD_FAB2(SCH_1):M_M_DQ<56>
  J1A1   275  DQ<57>  SCONN288_H44441004_PIP  I186
  J9L1   130  DQ<56>  SCONN288_H44441003_PIP  I111
  U2D1   CW30  DDR5_DQ<56>  SKX_EXT_B_BGA1  I172

M_M_DQ<57>      @BASEBOARD_FAB2_LIB.BASEBOARD_FAB2(SCH_1):M_M_DQ<57>
  J1A1   130  DQ<56>  SCONN288_H44441004_PIP  I186
  J9L1   275  DQ<57>  SCONN288_H44441003_PIP  I111
  U2D1   DC30  DDR5_DQ<57>  SKX_EXT_B_BGA1  I172

M_M_DQ<58>      @BASEBOARD_FAB2_LIB.BASEBOARD_FAB2(SCH_1):M_M_DQ<58>
  J1A1   282  DQ<59>  SCONN288_H44441004_PIP  I186
  J9L1   137  DQ<58>  SCONN288_H44441003_PIP  I111
  U2D1   CY27  DDR5_DQ<58>  SKX_EXT_B_BGA1  I172

M_M_DQ<59>      @BASEBOARD_FAB2_LIB.BASEBOARD_FAB2(SCH_1):M_M_DQ<59>
  J1A1   137  DQ<58>  SCONN288_H44441004_PIP  I186
  J9L1   282  DQ<59>  SCONN288_H44441003_PIP  I111
  U2D1   DB27  DDR5_DQ<59>  SKX_EXT_B_BGA1  I172

M_M_DQ<60>      @BASEBOARD_FAB2_LIB.BASEBOARD_FAB2(SCH_1):M_M_DQ<60>
  J1A1   273  DQ<61>  SCONN288_H44441004_PIP  I186
  J9L1   128  DQ<60>  SCONN288_H44441003_PIP  I111
  U2D1   CY31  DDR5_DQ<60>  SKX_EXT_B_BGA1  I172

M_M_DQ<61>      @BASEBOARD_FAB2_LIB.BASEBOARD_FAB2(SCH_1):M_M_DQ<61>
  J1A1   128  DQ<60>  SCONN288_H44441004_PIP  I186
  J9L1   273  DQ<61>  SCONN288_H44441003_PIP  I111
  U2D1   DB31  DDR5_DQ<61>  SKX_EXT_B_BGA1  I172

M_M_DQ<62>      @BASEBOARD_FAB2_LIB.BASEBOARD_FAB2(SCH_1):M_M_DQ<62>
  J1A1   280  DQ<63>  SCONN288_H44441004_PIP  I186
  J9L1   135  DQ<62>  SCONN288_H44441003_PIP  I111
  U2D1   CW28  DDR5_DQ<62>  SKX_EXT_B_BGA1  I172

M_M_DQ<63>      @BASEBOARD_FAB2_LIB.BASEBOARD_FAB2(SCH_1):M_M_DQ<63>
  J1A1   135  DQ<62>  SCONN288_H44441004_PIP  I186
  J9L1   280  DQ<63>  SCONN288_H44441003_PIP  I111
  U2D1   DC28  DDR5_DQ<63>  SKX_EXT_B_BGA1  I172

M_M_DQS_DN<0>   @BASEBOARD_FAB2_LIB.BASEBOARD_FAB2(SCH_1):M_M_DQS_DN<0>
  J1A1   152  DQS0N  SCONN288_H44441004_PIP  I187
  J9L1   152  DQS0N  SCONN288_H44441003_PIP  I87
  U2D1   CP77  DDR5_DQS_DN<0>  SKX_EXT_B_BGA1  I172

M_M_DQS_DN<1>   @BASEBOARD_FAB2_LIB.BASEBOARD_FAB2(SCH_1):M_M_DQS_DN<1>
  J1A1   163  DQS1N  SCONN288_H44441004_PIP  I187
  J9L1   163  DQS1N  SCONN288_H44441003_PIP  I87
  U2D1   DD77  DDR5_DQS_DN<1>  SKX_EXT_B_BGA1  I172

M_M_DQS_DN<2>   @BASEBOARD_FAB2_LIB.BASEBOARD_FAB2(SCH_1):M_M_DQS_DN<2>
  J1A1   174  DQS2N  SCONN288_H44441004_PIP  I187
  J9L1   174  DQS2N  SCONN288_H44441003_PIP  I87
  U2D1   DL72  DDR5_DQS_DN<2>  SKX_EXT_B_BGA1  I172

M_M_DQS_DN<3>   @BASEBOARD_FAB2_LIB.BASEBOARD_FAB2(SCH_1):M_M_DQS_DN<3>
  J1A1   185  DQS3N  SCONN288_H44441004_PIP  I187
  J9L1   185  DQS3N  SCONN288_H44441003_PIP  I87
  U2D1   CV65  DDR5_DQS_DN<3>  SKX_EXT_B_BGA1  I172

M_M_DQS_DN<4>   @BASEBOARD_FAB2_LIB.BASEBOARD_FAB2(SCH_1):M_M_DQS_DN<4>
  J1A1   244  DQS4N  SCONN288_H44441004_PIP  I187
  J9L1   244  DQS4N  SCONN288_H44441003_PIP  I87
  U2D1   DG40  DDR5_DQS_DN<4>  SKX_EXT_B_BGA1  I172

M_M_DQS_DN<5>   @BASEBOARD_FAB2_LIB.BASEBOARD_FAB2(SCH_1):M_M_DQS_DN<5>
  J1A1   255  DQS5N  SCONN288_H44441004_PIP  I187
  J9L1   255  DQS5N  SCONN288_H44441003_PIP  I87
  U2D1   DL32  DDR5_DQS_DN<5>  SKX_EXT_B_BGA1  I172

M_M_DQS_DN<6>   @BASEBOARD_FAB2_LIB.BASEBOARD_FAB2(SCH_1):M_M_DQS_DN<6>
  J1A1   266  DQS6N  SCONN288_H44441004_PIP  I187
  J9L1   266  DQS6N  SCONN288_H44441003_PIP  I87
  U2D1   DD35  DDR5_DQS_DN<6>  SKX_EXT_B_BGA1  I172

M_M_DQS_DN<7>   @BASEBOARD_FAB2_LIB.BASEBOARD_FAB2(SCH_1):M_M_DQS_DN<7>
  J1A1   277  DQS7N  SCONN288_H44441004_PIP  I187
  J9L1   277  DQS7N  SCONN288_H44441003_PIP  I87
  U2D1   DD29  DDR5_DQS_DN<7>  SKX_EXT_B_BGA1  I172

M_M_DQS_DN<8>   @BASEBOARD_FAB2_LIB.BASEBOARD_FAB2(SCH_1):M_M_DQS_DN<8>
  J1A1   196  DQS8N  SCONN288_H44441004_PIP  I187
  J9L1   196  DQS8N  SCONN288_H44441003_PIP  I87
  U2D1   CN70  DDR5_DQS_DN<8>  SKX_EXT_B_BGA1  I172

M_M_DQS_DN<9>   @BASEBOARD_FAB2_LIB.BASEBOARD_FAB2(SCH_1):M_M_DQS_DN<9>
  J1A1     8  DQS9N  SCONN288_H44441004_PIP  I187
  J9L1     8  DQS9N  SCONN288_H44441003_PIP  I87
  U2D1   CT75  DDR5_DQS_DN<9>  SKX_EXT_B_BGA1  I172

M_M_DQS_DN<10>   @BASEBOARD_FAB2_LIB.BASEBOARD_FAB2(SCH_1):M_M_DQS_DN<10>
  J1A1    19  DQS10N  SCONN288_H44441004_PIP  I187
  J9L1    19  DQS10N  SCONN288_H44441003_PIP  I87
  U2D1   DF75  DDR5_DQS_DN<10>  SKX_EXT_B_BGA1  I172

M_M_DQS_DN<11>   @BASEBOARD_FAB2_LIB.BASEBOARD_FAB2(SCH_1):M_M_DQS_DN<11>
  J1A1    30  DQS11N  SCONN288_H44441004_PIP  I187
  J9L1    30  DQS11N  SCONN288_H44441003_PIP  I87
  U2D1   DJ70  DDR5_DQS_DN<11>  SKX_EXT_B_BGA1  I172

M_M_DQS_DN<12>   @BASEBOARD_FAB2_LIB.BASEBOARD_FAB2(SCH_1):M_M_DQS_DN<12>
  J1A1    41  DQS12N  SCONN288_H44441004_PIP  I187
  J9L1    41  DQS12N  SCONN288_H44441003_PIP  I87
  U2D1   CP65  DDR5_DQS_DN<12>  SKX_EXT_B_BGA1  I172

M_M_DQS_DN<13>   @BASEBOARD_FAB2_LIB.BASEBOARD_FAB2(SCH_1):M_M_DQS_DN<13>
  J1A1   100  DQS13N  SCONN288_H44441004_PIP  I187
  J9L1   100  DQS13N  SCONN288_H44441003_PIP  I87
  U2D1   DE40  DDR5_DQS_DN<13>  SKX_EXT_B_BGA1  I172

M_M_DQS_DN<14>   @BASEBOARD_FAB2_LIB.BASEBOARD_FAB2(SCH_1):M_M_DQS_DN<14>
  J1A1   111  DQS14N  SCONN288_H44441004_PIP  I187
  J9L1   111  DQS14N  SCONN288_H44441003_PIP  I87
  U2D1   DG32  DDR5_DQS_DN<14>  SKX_EXT_B_BGA1  I172

M_M_DQS_DN<15>   @BASEBOARD_FAB2_LIB.BASEBOARD_FAB2(SCH_1):M_M_DQS_DN<15>
  J1A1   122  DQS15N  SCONN288_H44441004_PIP  I187
  J9L1   122  DQS15N  SCONN288_H44441003_PIP  I87
  U2D1   CY35  DDR5_DQS_DN<15>  SKX_EXT_B_BGA1  I172

M_M_DQS_DN<16>   @BASEBOARD_FAB2_LIB.BASEBOARD_FAB2(SCH_1):M_M_DQS_DN<16>
  J1A1   133  DQS16N  SCONN288_H44441004_PIP  I187
  J9L1   133  DQS16N  SCONN288_H44441003_PIP  I87
  U2D1   CY29  DDR5_DQS_DN<16>  SKX_EXT_B_BGA1  I172

M_M_DQS_DN<17>   @BASEBOARD_FAB2_LIB.BASEBOARD_FAB2(SCH_1):M_M_DQS_DN<17>
  J1A1    52  DQS17N  SCONN288_H44441004_PIP  I187
  J9L1    52  DQS17N  SCONN288_H44441003_PIP  I87
  U2D1   CJ70  DDR5_DQS_DN<17>  SKX_EXT_B_BGA1  I172

M_M_DQS_DP<0>   @BASEBOARD_FAB2_LIB.BASEBOARD_FAB2(SCH_1):M_M_DQS_DP<0>
  J1A1   153  DQS0P  SCONN288_H44441004_PIP  I187
  J9L1   153  DQS0P  SCONN288_H44441003_PIP  I87
  U2D1   CR76  DDR5_DQS_DP<0>  SKX_EXT_B_BGA1  I172

M_M_DQS_DP<1>   @BASEBOARD_FAB2_LIB.BASEBOARD_FAB2(SCH_1):M_M_DQS_DP<1>
  J1A1   164  DQS1P  SCONN288_H44441004_PIP  I187
  J9L1   164  DQS1P  SCONN288_H44441003_PIP  I87
  U2D1   DE76  DDR5_DQS_DP<1>  SKX_EXT_B_BGA1  I172

M_M_DQS_DP<2>   @BASEBOARD_FAB2_LIB.BASEBOARD_FAB2(SCH_1):M_M_DQS_DP<2>
  J1A1   175  DQS2P  SCONN288_H44441004_PIP  I187
  J9L1   175  DQS2P  SCONN288_H44441003_PIP  I87
  U2D1   DK71  DDR5_DQS_DP<2>  SKX_EXT_B_BGA1  I172

M_M_DQS_DP<3>   @BASEBOARD_FAB2_LIB.BASEBOARD_FAB2(SCH_1):M_M_DQS_DP<3>
  J1A1   186  DQS3P  SCONN288_H44441004_PIP  I187
  J9L1   186  DQS3P  SCONN288_H44441003_PIP  I87
  U2D1   CT65  DDR5_DQS_DP<3>  SKX_EXT_B_BGA1  I172

M_M_DQS_DP<4>   @BASEBOARD_FAB2_LIB.BASEBOARD_FAB2(SCH_1):M_M_DQS_DP<4>
  J1A1   245  DQS4P  SCONN288_H44441004_PIP  I187
  J9L1   245  DQS4P  SCONN288_H44441003_PIP  I87
  U2D1   DJ40  DDR5_DQS_DP<4>  SKX_EXT_B_BGA1  I172

M_M_DQS_DP<5>   @BASEBOARD_FAB2_LIB.BASEBOARD_FAB2(SCH_1):M_M_DQS_DP<5>
  J1A1   256  DQS5P  SCONN288_H44441004_PIP  I187
  J9L1   256  DQS5P  SCONN288_H44441003_PIP  I87
  U2D1   DJ32  DDR5_DQS_DP<5>  SKX_EXT_B_BGA1  I172

M_M_DQS_DP<6>   @BASEBOARD_FAB2_LIB.BASEBOARD_FAB2(SCH_1):M_M_DQS_DP<6>
  J1A1   267  DQS6P  SCONN288_H44441004_PIP  I187
  J9L1   267  DQS6P  SCONN288_H44441003_PIP  I87
  U2D1   DB35  DDR5_DQS_DP<6>  SKX_EXT_B_BGA1  I172

M_M_DQS_DP<7>   @BASEBOARD_FAB2_LIB.BASEBOARD_FAB2(SCH_1):M_M_DQS_DP<7>
  J1A1   278  DQS7P  SCONN288_H44441004_PIP  I187
  J9L1   278  DQS7P  SCONN288_H44441003_PIP  I87
  U2D1   DB29  DDR5_DQS_DP<7>  SKX_EXT_B_BGA1  I172

M_M_DQS_DP<8>   @BASEBOARD_FAB2_LIB.BASEBOARD_FAB2(SCH_1):M_M_DQS_DP<8>
  J1A1   197  DQS8P  SCONN288_H44441004_PIP  I187
  J9L1   197  DQS8P  SCONN288_H44441003_PIP  I87
  U2D1   CL70  DDR5_DQS_DP<8>  SKX_EXT_B_BGA1  I172

M_M_DQS_DP<9>   @BASEBOARD_FAB2_LIB.BASEBOARD_FAB2(SCH_1):M_M_DQS_DP<9>
  J1A1     7  DQS9P  SCONN288_H44441004_PIP  I187
  J9L1     7  DQS9P  SCONN288_H44441003_PIP  I87
  U2D1   CU74  DDR5_DQS_DP<9>  SKX_EXT_B_BGA1  I172

M_M_DQS_DP<10>   @BASEBOARD_FAB2_LIB.BASEBOARD_FAB2(SCH_1):M_M_DQS_DP<10>
  J1A1    18  DQS10P  SCONN288_H44441004_PIP  I187
  J9L1    18  DQS10P  SCONN288_H44441003_PIP  I87
  U2D1   DG74  DDR5_DQS_DP<10>  SKX_EXT_B_BGA1  I172

M_M_DQS_DP<11>   @BASEBOARD_FAB2_LIB.BASEBOARD_FAB2(SCH_1):M_M_DQS_DP<11>
  J1A1    29  DQS11P  SCONN288_H44441004_PIP  I187
  J9L1    29  DQS11P  SCONN288_H44441003_PIP  I87
  U2D1   DH69  DDR5_DQS_DP<11>  SKX_EXT_B_BGA1  I172

M_M_DQS_DP<12>   @BASEBOARD_FAB2_LIB.BASEBOARD_FAB2(SCH_1):M_M_DQS_DP<12>
  J1A1    40  DQS12P  SCONN288_H44441004_PIP  I187
  J9L1    40  DQS12P  SCONN288_H44441003_PIP  I87
  U2D1   CM65  DDR5_DQS_DP<12>  SKX_EXT_B_BGA1  I172

M_M_DQS_DP<13>   @BASEBOARD_FAB2_LIB.BASEBOARD_FAB2(SCH_1):M_M_DQS_DP<13>
  J1A1    99  DQS13P  SCONN288_H44441004_PIP  I187
  J9L1    99  DQS13P  SCONN288_H44441003_PIP  I87
  U2D1   DC40  DDR5_DQS_DP<13>  SKX_EXT_B_BGA1  I172

M_M_DQS_DP<14>   @BASEBOARD_FAB2_LIB.BASEBOARD_FAB2(SCH_1):M_M_DQS_DP<14>
  J1A1   110  DQS14P  SCONN288_H44441004_PIP  I187
  J9L1   110  DQS14P  SCONN288_H44441003_PIP  I87
  U2D1   DE32  DDR5_DQS_DP<14>  SKX_EXT_B_BGA1  I172

M_M_DQS_DP<15>   @BASEBOARD_FAB2_LIB.BASEBOARD_FAB2(SCH_1):M_M_DQS_DP<15>
  J1A1   121  DQS15P  SCONN288_H44441004_PIP  I187
  J9L1   121  DQS15P  SCONN288_H44441003_PIP  I87
  U2D1   CV35  DDR5_DQS_DP<15>  SKX_EXT_B_BGA1  I172

M_M_DQS_DP<16>   @BASEBOARD_FAB2_LIB.BASEBOARD_FAB2(SCH_1):M_M_DQS_DP<16>
  J1A1   132  DQS16P  SCONN288_H44441004_PIP  I187
  J9L1   132  DQS16P  SCONN288_H44441003_PIP  I87
  U2D1   CV29  DDR5_DQS_DP<16>  SKX_EXT_B_BGA1  I172

M_M_DQS_DP<17>   @BASEBOARD_FAB2_LIB.BASEBOARD_FAB2(SCH_1):M_M_DQS_DP<17>
  J1A1    51  DQS17P  SCONN288_H44441004_PIP  I187
  J9L1    51  DQS17P  SCONN288_H44441003_PIP  I87
  U2D1   CG70  DDR5_DQS_DP<17>  SKX_EXT_B_BGA1  I172

M_M_ECC<0>      @BASEBOARD_FAB2_LIB.BASEBOARD_FAB2(SCH_1):M_M_ECC<0>
  J1A1   194  CB<1>  SCONN288_H44441004_PIP  I186
  J9L1    49  CB<0>  SCONN288_H44441003_PIP  I111
  U2D1   CH71  DDR5_ECC<0>  SKX_EXT_B_BGA1  I172

M_M_ECC<1>      @BASEBOARD_FAB2_LIB.BASEBOARD_FAB2(SCH_1):M_M_ECC<1>
  J1A1    49  CB<0>  SCONN288_H44441004_PIP  I186
  J9L1   194  CB<1>  SCONN288_H44441003_PIP  I111
  U2D1   CM71  DDR5_ECC<1>  SKX_EXT_B_BGA1  I172

M_M_ECC<2>      @BASEBOARD_FAB2_LIB.BASEBOARD_FAB2(SCH_1):M_M_ECC<2>
  J1A1   201  CB<3>  SCONN288_H44441004_PIP  I186
  J9L1    56  CB<2>  SCONN288_H44441003_PIP  I111
  U2D1   CJ68  DDR5_ECC<2>  SKX_EXT_B_BGA1  I172

M_M_ECC<3>      @BASEBOARD_FAB2_LIB.BASEBOARD_FAB2(SCH_1):M_M_ECC<3>
  J1A1    56  CB<2>  SCONN288_H44441004_PIP  I186
  J9L1   201  CB<3>  SCONN288_H44441003_PIP  I111
  U2D1   CL68  DDR5_ECC<3>  SKX_EXT_B_BGA1  I172

M_M_ECC<4>      @BASEBOARD_FAB2_LIB.BASEBOARD_FAB2(SCH_1):M_M_ECC<4>
  J1A1   192  CB<5>  SCONN288_H44441004_PIP  I186
  J9L1    47  CB<4>  SCONN288_H44441003_PIP  I111
  U2D1   CJ72  DDR5_ECC<4>  SKX_EXT_B_BGA1  I172

M_M_ECC<5>      @BASEBOARD_FAB2_LIB.BASEBOARD_FAB2(SCH_1):M_M_ECC<5>
  J1A1    47  CB<4>  SCONN288_H44441004_PIP  I186
  J9L1   192  CB<5>  SCONN288_H44441003_PIP  I111
  U2D1   CL72  DDR5_ECC<5>  SKX_EXT_B_BGA1  I172

M_M_ECC<6>      @BASEBOARD_FAB2_LIB.BASEBOARD_FAB2(SCH_1):M_M_ECC<6>
  J1A1   199  CB<7>  SCONN288_H44441004_PIP  I186
  J9L1    54  CB<6>  SCONN288_H44441003_PIP  I111
  U2D1   CH69  DDR5_ECC<6>  SKX_EXT_B_BGA1  I172

M_M_ECC<7>      @BASEBOARD_FAB2_LIB.BASEBOARD_FAB2(SCH_1):M_M_ECC<7>
  J1A1    54  CB<6>  SCONN288_H44441004_PIP  I186
  J9L1   199  CB<7>  SCONN288_H44441003_PIP  I111
  U2D1   CM69  DDR5_ECC<7>  SKX_EXT_B_BGA1  I172

M_M_MA<0>       @BASEBOARD_FAB2_LIB.BASEBOARD_FAB2(SCH_1):M_M_MA<0>
  J1A1    79     A0  SCONN288_H44441004_PIP  I186
  J9L1    79     A0  SCONN288_H44441003_PIP  I111
  U2D1   DF53  DDR5_MA<0>  SKX_EXT_B_BGA1  I172

M_M_MA<1>       @BASEBOARD_FAB2_LIB.BASEBOARD_FAB2(SCH_1):M_M_MA<1>
  J1A1    72     A1  SCONN288_H44441004_PIP  I186
  J9L1    72     A1  SCONN288_H44441003_PIP  I111
  U2D1   DC58  DDR5_MA<1>  SKX_EXT_B_BGA1  I172

M_M_MA<2>       @BASEBOARD_FAB2_LIB.BASEBOARD_FAB2(SCH_1):M_M_MA<2>
  J1A1   216     A2  SCONN288_H44441004_PIP  I186
  J9L1   216     A2  SCONN288_H44441003_PIP  I111
  U2D1   DD57  DDR5_MA<2>  SKX_EXT_B_BGA1  I172

M_M_MA<3>       @BASEBOARD_FAB2_LIB.BASEBOARD_FAB2(SCH_1):M_M_MA<3>
  J1A1    71     A3  SCONN288_H44441004_PIP  I186
  J9L1    71     A3  SCONN288_H44441003_PIP  I111
  U2D1   DG58  DDR5_MA<3>  SKX_EXT_B_BGA1  I172

M_M_MA<4>       @BASEBOARD_FAB2_LIB.BASEBOARD_FAB2(SCH_1):M_M_MA<4>
  J1A1   214     A4  SCONN288_H44441004_PIP  I186
  J9L1   214     A4  SCONN288_H44441003_PIP  I111
  U2D1   DJ58  DDR5_MA<4>  SKX_EXT_B_BGA1  I172

M_M_MA<5>       @BASEBOARD_FAB2_LIB.BASEBOARD_FAB2(SCH_1):M_M_MA<5>
  J1A1   213     A5  SCONN288_H44441004_PIP  I186
  J9L1   213     A5  SCONN288_H44441003_PIP  I111
  U2D1   DF59  DDR5_MA<5>  SKX_EXT_B_BGA1  I172

M_M_MA<6>       @BASEBOARD_FAB2_LIB.BASEBOARD_FAB2(SCH_1):M_M_MA<6>
  J1A1    69     A6  SCONN288_H44441004_PIP  I186
  J9L1    69     A6  SCONN288_H44441003_PIP  I111
  U2D1   DK59  DDR5_MA<6>  SKX_EXT_B_BGA1  I172

M_M_MA<7>       @BASEBOARD_FAB2_LIB.BASEBOARD_FAB2(SCH_1):M_M_MA<7>
  J1A1   211     A7  SCONN288_H44441004_PIP  I186
  J9L1   211     A7  SCONN288_H44441003_PIP  I111
  U2D1   DC60  DDR5_MA<7>  SKX_EXT_B_BGA1  I172

M_M_MA<8>       @BASEBOARD_FAB2_LIB.BASEBOARD_FAB2(SCH_1):M_M_MA<8>
  J1A1    68     A8  SCONN288_H44441004_PIP  I186
  J9L1    68     A8  SCONN288_H44441003_PIP  I111
  U2D1   DD59  DDR5_MA<8>  SKX_EXT_B_BGA1  I172

M_M_MA<9>       @BASEBOARD_FAB2_LIB.BASEBOARD_FAB2(SCH_1):M_M_MA<9>
  J1A1    66     A9  SCONN288_H44441004_PIP  I186
  J9L1    66     A9  SCONN288_H44441003_PIP  I111
  U2D1   DA58  DDR5_MA<9>  SKX_EXT_B_BGA1  I172

M_M_MA<10>      @BASEBOARD_FAB2_LIB.BASEBOARD_FAB2(SCH_1):M_M_MA<10>
  J1A1   225    A10  SCONN288_H44441004_PIP  I186
  J9L1   225    A10  SCONN288_H44441003_PIP  I111
  U2D1   DD55  DDR5_MA<10>  SKX_EXT_B_BGA1  I172

M_M_MA<11>      @BASEBOARD_FAB2_LIB.BASEBOARD_FAB2(SCH_1):M_M_MA<11>
  J1A1   210    A11  SCONN288_H44441004_PIP  I186
  J9L1   210    A11  SCONN288_H44441003_PIP  I111
  U2D1   DA60  DDR5_MA<11>  SKX_EXT_B_BGA1  I172

M_M_MA<12>      @BASEBOARD_FAB2_LIB.BASEBOARD_FAB2(SCH_1):M_M_MA<12>
  J1A1    65    A12  SCONN288_H44441004_PIP  I186
  J9L1    65    A12  SCONN288_H44441003_PIP  I111
  U2D1   DG60  DDR5_MA<12>  SKX_EXT_B_BGA1  I172

M_M_MA<13>      @BASEBOARD_FAB2_LIB.BASEBOARD_FAB2(SCH_1):M_M_MA<13>
  J1A1   232    A13  SCONN288_H44441004_PIP  I186
  J9L1   232    A13  SCONN288_H44441003_PIP  I111
  U2D1   DD53  DDR5_MA<13>  SKX_EXT_B_BGA1  I172

M_M_MA<14>      @BASEBOARD_FAB2_LIB.BASEBOARD_FAB2(SCH_1):M_M_MA<14>
  J1A1   228  A14_WE_N  SCONN288_H44441004_PIP  I186
  J9L1   228  A14_WE_N  SCONN288_H44441003_PIP  I111
  U2D1   DJ50  DDR5_MA<14>  SKX_EXT_B_BGA1  I172

M_M_MA<15>      @BASEBOARD_FAB2_LIB.BASEBOARD_FAB2(SCH_1):M_M_MA<15>
  J1A1    86  A15_CAS_N  SCONN288_H44441004_PIP  I186
  J9L1    86  A15_CAS_N  SCONN288_H44441003_PIP  I111
  U2D1   DC54  DDR5_MA<15>  SKX_EXT_B_BGA1  I172

M_M_MA<16>      @BASEBOARD_FAB2_LIB.BASEBOARD_FAB2(SCH_1):M_M_MA<16>
  J1A1    82  A16_RAS_N  SCONN288_H44441004_PIP  I186
  J9L1    82  A16_RAS_N  SCONN288_H44441003_PIP  I111
  U2D1   DG52  DDR5_MA<16>  SKX_EXT_B_BGA1  I172

M_M_MA<17>      @BASEBOARD_FAB2_LIB.BASEBOARD_FAB2(SCH_1):M_M_MA<17>
  J1A1   234    A17  SCONN288_H44441004_PIP  I186
  J9L1   234    A17  SCONN288_H44441003_PIP  I111
  U2D1   DE46  DDR5_MA<17>  SKX_EXT_B_BGA1  I172

M_M_ODT<0>      @BASEBOARD_FAB2_LIB.BASEBOARD_FAB2(SCH_1):M_M_ODT<0>
  J1A1    87  ODT<0>  SCONN288_H44441004_PIP  I186
  U2D1   DG50  DDR5_ODT<0>  SKX_EXT_B_BGA1  I172

M_M_ODT<1>      @BASEBOARD_FAB2_LIB.BASEBOARD_FAB2(SCH_1):M_M_ODT<1>
  J1A1    91  ODT<1>  SCONN288_H44441004_PIP  I186
  U2D1   DG48  DDR5_ODT<1>  SKX_EXT_B_BGA1  I172

M_M_ODT<2>      @BASEBOARD_FAB2_LIB.BASEBOARD_FAB2(SCH_1):M_M_ODT<2>
  J9L1    87  ODT<0>  SCONN288_H44441003_PIP  I111
  U2D1   DK49  DDR5_ODT<2>  SKX_EXT_B_BGA1  I172

M_M_ODT<3>      @BASEBOARD_FAB2_LIB.BASEBOARD_FAB2(SCH_1):M_M_ODT<3>
  J9L1    91  ODT<1>  SCONN288_H44441003_PIP  I111
  U2D1   DF47  DDR5_ODT<3>  SKX_EXT_B_BGA1  I172

M_M_PAR         @BASEBOARD_FAB2_LIB.BASEBOARD_FAB2(SCH_1):M_M_PAR
  J1A1   222    PAR  SCONN288_H44441004_PIP  I186
  J9L1   222    PAR  SCONN288_H44441003_PIP  I111
  U2D1   DK53  DDR5_PAR  SKX_EXT_B_BGA1  I172

M_M_VREF        @BASEBOARD_FAB2_LIB.BASEBOARD_FAB2(SCH_1):M_M_VREF
  C1A5     1      A  CAP_A       I178
  C9L1     1      A  CAP_A       I177
  J1A1   146  VREFCA  SCONN288_H44441004_PIP  I186
  J9L1   146  VREFCA  SCONN288_H44441003_PIP  I111
  R9L1     1      A  RES         I40
  R9L2     2      B  RES         I38
  R9L3     2      B  RES         I45

NC_CLK_156M_CPU0_OSC   @BASEBOARD_FAB2_LIB.BASEBOARD_FAB2(SCH_1):NC_CLK_156M_CPU0_OSC
  Y6F1     2  NC_GND  OSC_C_6P10  I71

NC_CLK_156M_CPU1_OSC   @BASEBOARD_FAB2_LIB.BASEBOARD_FAB2(SCH_1):NC_CLK_156M_CPU1_OSC
  Y3F1     2  NC_GND  OSC_C_6P10  I72

NC_CPLD1        @BASEBOARD_FAB2_LIB.BASEBOARD_FAB2(SCH_1):NC_CPLD1
  U8D7    A2  NC<0>  LCMXO2_A_256BGA  I14

NC_DB1200ZL<0>   @BASEBOARD_FAB2_LIB.BASEBOARD_FAB2(SCH_1):NC_DB1200ZL<0>
  EU4D2    3  NC<0>  NB3W1200L_LCC   I1

NC_DB1200ZL<1>   @BASEBOARD_FAB2_LIB.BASEBOARD_FAB2(SCH_1):NC_DB1200ZL<1>
  EU4D2   16  NC<1>  NB3W1200L_LCC   I1

NC_DB1200ZL<2>   @BASEBOARD_FAB2_LIB.BASEBOARD_FAB2(SCH_1):NC_DB1200ZL<2>
  EU4D2   15  NC<2>  NB3W1200L_LCC   I1

NC_M2<0>        @BASEBOARD_FAB2_LIB.BASEBOARD_FAB2(SCH_1):NC_M2<0>
  J8F1     6  NC<0>  SCONN75K_H17033002_SMT1  I53

NC_M2<1>        @BASEBOARD_FAB2_LIB.BASEBOARD_FAB2(SCH_1):NC_M2<1>
  J8F1     8  NC<1>  SCONN75K_H17033002_SMT1  I53

NC_M2<2>        @BASEBOARD_FAB2_LIB.BASEBOARD_FAB2(SCH_1):NC_M2<2>
  J8F1    20  NC<2>  SCONN75K_H17033002_SMT1  I53

NC_M2<3>        @BASEBOARD_FAB2_LIB.BASEBOARD_FAB2(SCH_1):NC_M2<3>
  J8F1    22  NC<3>  SCONN75K_H17033002_SMT1  I53

NC_M2<4>        @BASEBOARD_FAB2_LIB.BASEBOARD_FAB2(SCH_1):NC_M2<4>
  J8F1    24  NC<4>  SCONN75K_H17033002_SMT1  I53

NC_M2<5>        @BASEBOARD_FAB2_LIB.BASEBOARD_FAB2(SCH_1):NC_M2<5>
  J8F1    26  NC<5>  SCONN75K_H17033002_SMT1  I53

NC_M2<6>        @BASEBOARD_FAB2_LIB.BASEBOARD_FAB2(SCH_1):NC_M2<6>
  J8F1    28  NC<6>  SCONN75K_H17033002_SMT1  I53

NC_M2<7>        @BASEBOARD_FAB2_LIB.BASEBOARD_FAB2(SCH_1):NC_M2<7>
  J8F1    30  NC<7>  SCONN75K_H17033002_SMT1  I53

NC_M2<8>        @BASEBOARD_FAB2_LIB.BASEBOARD_FAB2(SCH_1):NC_M2<8>
  J8F1    32  NC<8>  SCONN75K_H17033002_SMT1  I53

NC_M2<9>        @BASEBOARD_FAB2_LIB.BASEBOARD_FAB2(SCH_1):NC_M2<9>
  J8F1    34  NC<9>  SCONN75K_H17033002_SMT1  I53

NC_M2<10>       @BASEBOARD_FAB2_LIB.BASEBOARD_FAB2(SCH_1):NC_M2<10>
  J8F1    36  NC<10>  SCONN75K_H17033002_SMT1  I53

NC_M2<11>       @BASEBOARD_FAB2_LIB.BASEBOARD_FAB2(SCH_1):NC_M2<11>
  J8F1    40  NC<11>  SCONN75K_H17033002_SMT1  I53

NC_M2<12>       @BASEBOARD_FAB2_LIB.BASEBOARD_FAB2(SCH_1):NC_M2<12>
  J8F1    42  NC<12>  SCONN75K_H17033002_SMT1  I53

NC_M2<13>       @BASEBOARD_FAB2_LIB.BASEBOARD_FAB2(SCH_1):NC_M2<13>
  J8F1    44  NC<13>  SCONN75K_H17033002_SMT1  I53

NC_M2<14>       @BASEBOARD_FAB2_LIB.BASEBOARD_FAB2(SCH_1):NC_M2<14>
  J8F1    46  NC<14>  SCONN75K_H17033002_SMT1  I53

NC_M2<15>       @BASEBOARD_FAB2_LIB.BASEBOARD_FAB2(SCH_1):NC_M2<15>
  J8F1    48  NC<15>  SCONN75K_H17033002_SMT1  I53

NC_M2<16>       @BASEBOARD_FAB2_LIB.BASEBOARD_FAB2(SCH_1):NC_M2<16>
  J8F1    56  NC<16>  SCONN75K_H17033002_SMT1  I53

NC_M2<17>       @BASEBOARD_FAB2_LIB.BASEBOARD_FAB2(SCH_1):NC_M2<17>
  J8F1    58  NC<17>  SCONN75K_H17033002_SMT1  I53

NC_M2<18>       @BASEBOARD_FAB2_LIB.BASEBOARD_FAB2(SCH_1):NC_M2<18>
  J8F1    67  NC<18>  SCONN75K_H17033002_SMT1  I53

NC_P1V05_PCH_STBY_PH1_P31   @BASEBOARD_FAB2_LIB.BASEBOARD_FAB2(SCH_1):NC_P1V05_PCH_STBY_PH1_P31
  EU7A2   31     NC  IR354XX_SM  I117

NC_PI7C9X1172_1   @BASEBOARD_FAB2_LIB.BASEBOARD_FAB2(SCH_1):NC_PI7C9X1172_1
  EU9F3    1  NC<0>  PI7C9X1172_QFN   I1

NC_PI7C9X1172_8   @BASEBOARD_FAB2_LIB.BASEBOARD_FAB2(SCH_1):NC_PI7C9X1172_8
  EU9F3    8  NC<1>  PI7C9X1172_QFN   I1

NC_PVCCIN_CPU0_PH1_P31   @BASEBOARD_FAB2_LIB.BASEBOARD_FAB2(SCH_1):NC_PVCCIN_CPU0_PH1_P31
  EU4E1   31     NC  IR354XX_SM  I63

NC_PVCCIN_CPU0_PH2_P31   @BASEBOARD_FAB2_LIB.BASEBOARD_FAB2(SCH_1):NC_PVCCIN_CPU0_PH2_P31
  EU4D6   31     NC  IR354XX_SM  I64

NC_PVCCIN_CPU0_PH3_P31   @BASEBOARD_FAB2_LIB.BASEBOARD_FAB2(SCH_1):NC_PVCCIN_CPU0_PH3_P31
  EU4D3   31     NC  IR354XX_SM  I70

NC_PVCCIN_CPU0_PH4_P31   @BASEBOARD_FAB2_LIB.BASEBOARD_FAB2(SCH_1):NC_PVCCIN_CPU0_PH4_P31
  EU4D1   31     NC  IR354XX_SM  I71

NC_PVCCIN_CPU0_PH5_P31   @BASEBOARD_FAB2_LIB.BASEBOARD_FAB2(SCH_1):NC_PVCCIN_CPU0_PH5_P31
  EU4C2   31     NC  IR354XX_SM  I71

NC_PVCCIN_CPU1_PH1_P31   @BASEBOARD_FAB2_LIB.BASEBOARD_FAB2(SCH_1):NC_PVCCIN_CPU1_PH1_P31
  EU1E2   31     NC  IR354XX_SM  I20

NC_PVCCIN_CPU1_PH2_P31   @BASEBOARD_FAB2_LIB.BASEBOARD_FAB2(SCH_1):NC_PVCCIN_CPU1_PH2_P31
  EU1D4   31     NC  IR354XX_SM  I24

NC_PVCCIN_CPU1_PH3_P31   @BASEBOARD_FAB2_LIB.BASEBOARD_FAB2(SCH_1):NC_PVCCIN_CPU1_PH3_P31
  EU1D3   31     NC  IR354XX_SM  I27

NC_PVCCIN_CPU1_PH4_P31   @BASEBOARD_FAB2_LIB.BASEBOARD_FAB2(SCH_1):NC_PVCCIN_CPU1_PH4_P31
  EU1D1   31     NC  IR354XX_SM  I71

NC_PVCCIN_CPU1_PH5_P31   @BASEBOARD_FAB2_LIB.BASEBOARD_FAB2(SCH_1):NC_PVCCIN_CPU1_PH5_P31
  EU1C3   31     NC  IR354XX_SM  I56

NC_PVCCIO_CPU0_DNC0   @BASEBOARD_FAB2_LIB.BASEBOARD_FAB2(SCH_1):NC_PVCCIO_CPU0_DNC0
  EU3P1    1  DNC<0>  PXE1110B_QFN  I93

NC_PVCCIO_CPU0_DNC1   @BASEBOARD_FAB2_LIB.BASEBOARD_FAB2(SCH_1):NC_PVCCIO_CPU0_DNC1
  EU3P1    2  DNC<1>  PXE1110B_QFN  I93

NC_PVCCIO_CPU0_DNC2   @BASEBOARD_FAB2_LIB.BASEBOARD_FAB2(SCH_1):NC_PVCCIO_CPU0_DNC2
  EU3P1    4  DNC<2>  PXE1110B_QFN  I93

NC_PVCCIO_CPU0_DNC3   @BASEBOARD_FAB2_LIB.BASEBOARD_FAB2(SCH_1):NC_PVCCIO_CPU0_DNC3
  EU3P1   24  DNC<3>  PXE1110B_QFN  I93

NC_PVCCIO_CPU0_DNC4   @BASEBOARD_FAB2_LIB.BASEBOARD_FAB2(SCH_1):NC_PVCCIO_CPU0_DNC4
  EU3P1   28  DNC<4>  PXE1110B_QFN  I93

NC_PVCCIO_CPU0_PH1_P31   @BASEBOARD_FAB2_LIB.BASEBOARD_FAB2(SCH_1):NC_PVCCIO_CPU0_PH1_P31
  EU7C1   31     NC  IR354XX_SM  I101

NC_PVCCIO_CPU1_DNC0   @BASEBOARD_FAB2_LIB.BASEBOARD_FAB2(SCH_1):NC_PVCCIO_CPU1_DNC0
  EU4D5    1  DNC<0>  PXE1110B_QFN  I96

NC_PVCCIO_CPU1_DNC1   @BASEBOARD_FAB2_LIB.BASEBOARD_FAB2(SCH_1):NC_PVCCIO_CPU1_DNC1
  EU4D5    2  DNC<1>  PXE1110B_QFN  I96

NC_PVCCIO_CPU1_DNC2   @BASEBOARD_FAB2_LIB.BASEBOARD_FAB2(SCH_1):NC_PVCCIO_CPU1_DNC2
  EU4D5    4  DNC<2>  PXE1110B_QFN  I96

NC_PVCCIO_CPU1_DNC3   @BASEBOARD_FAB2_LIB.BASEBOARD_FAB2(SCH_1):NC_PVCCIO_CPU1_DNC3
  EU4D5   24  DNC<3>  PXE1110B_QFN  I96

NC_PVCCIO_CPU1_DNC4   @BASEBOARD_FAB2_LIB.BASEBOARD_FAB2(SCH_1):NC_PVCCIO_CPU1_DNC4
  EU4D5   28  DNC<4>  PXE1110B_QFN  I96

NC_PVCCIO_CPU1_PH1_P31   @BASEBOARD_FAB2_LIB.BASEBOARD_FAB2(SCH_1):NC_PVCCIO_CPU1_PH1_P31
  EU4E2   31     NC  IR354XX_SM  I126

NC_PVDDQ_ABC_DNC0   @BASEBOARD_FAB2_LIB.BASEBOARD_FAB2(SCH_1):NC_PVDDQ_ABC_DNC0
  EU7G1    2  DNC<0>  PXM1310B_QFN  I358

NC_PVDDQ_ABC_DNC1   @BASEBOARD_FAB2_LIB.BASEBOARD_FAB2(SCH_1):NC_PVDDQ_ABC_DNC1
  EU7G1   28  DNC<1>  PXM1310B_QFN  I358

NC_PVDDQ_ABC_PH1_P31   @BASEBOARD_FAB2_LIB.BASEBOARD_FAB2(SCH_1):NC_PVDDQ_ABC_PH1_P31
  EU7G2   31     NC  IR354XX_SM  I102

NC_PVDDQ_ABC_PH2_P31   @BASEBOARD_FAB2_LIB.BASEBOARD_FAB2(SCH_1):NC_PVDDQ_ABC_PH2_P31
  EU7G3   31     NC  IR354XX_SM  I103

NC_PVDDQ_DEF_DNC0   @BASEBOARD_FAB2_LIB.BASEBOARD_FAB2(SCH_1):NC_PVDDQ_DEF_DNC0
  EU7A5    2  DNC<0>  PXM1310B_QFN  I75

NC_PVDDQ_DEF_DNC1   @BASEBOARD_FAB2_LIB.BASEBOARD_FAB2(SCH_1):NC_PVDDQ_DEF_DNC1
  EU7A5   28  DNC<1>  PXM1310B_QFN  I75

NC_PVDDQ_DEF_PH1_P31   @BASEBOARD_FAB2_LIB.BASEBOARD_FAB2(SCH_1):NC_PVDDQ_DEF_PH1_P31
  EU7A1   31     NC  IR354XX_SM  I106

NC_PVDDQ_DEF_PH2_P31   @BASEBOARD_FAB2_LIB.BASEBOARD_FAB2(SCH_1):NC_PVDDQ_DEF_PH2_P31
  EU7A4   31     NC  IR354XX_SM  I107

NC_PVDDQ_GHJ_DNC0   @BASEBOARD_FAB2_LIB.BASEBOARD_FAB2(SCH_1):NC_PVDDQ_GHJ_DNC0
  EU1G2    2  DNC<0>  PXM1310B_QFN  I90

NC_PVDDQ_GHJ_DNC1   @BASEBOARD_FAB2_LIB.BASEBOARD_FAB2(SCH_1):NC_PVDDQ_GHJ_DNC1
  EU1G2   28  DNC<1>  PXM1310B_QFN  I90

NC_PVDDQ_GHJ_PH1_P31   @BASEBOARD_FAB2_LIB.BASEBOARD_FAB2(SCH_1):NC_PVDDQ_GHJ_PH1_P31
  EU1G1   31     NC  IR354XX_SM  I110

NC_PVDDQ_GHJ_PH2_P31   @BASEBOARD_FAB2_LIB.BASEBOARD_FAB2(SCH_1):NC_PVDDQ_GHJ_PH2_P31
  EU1F1   31     NC  IR354XX_SM  I111

NC_PVDDQ_GHJ_PINALRT_N   @BASEBOARD_FAB2_LIB.BASEBOARD_FAB2(SCH_1):NC_PVDDQ_GHJ_PINALRT_N
  EU1G2   12  PINALRT_N  PXM1310B_QFN  I90

NC_PVDDQ_KLM_DNC0   @BASEBOARD_FAB2_LIB.BASEBOARD_FAB2(SCH_1):NC_PVDDQ_KLM_DNC0
  EU1B1    2  DNC<0>  PXM1310B_QFN  I90

NC_PVDDQ_KLM_DNC1   @BASEBOARD_FAB2_LIB.BASEBOARD_FAB2(SCH_1):NC_PVDDQ_KLM_DNC1
  EU1B1   28  DNC<1>  PXM1310B_QFN  I90

NC_PVDDQ_KLM_GP0   @BASEBOARD_FAB2_LIB.BASEBOARD_FAB2(SCH_1):NC_PVDDQ_KLM_GP0
  EU1B1   18    MP2  PXM1310B_QFN  I90

NC_PVDDQ_KLM_GP1   @BASEBOARD_FAB2_LIB.BASEBOARD_FAB2(SCH_1):NC_PVDDQ_KLM_GP1
  EU1B1   14    MP1  PXM1310B_QFN  I90

NC_PVDDQ_KLM_PH1_P31   @BASEBOARD_FAB2_LIB.BASEBOARD_FAB2(SCH_1):NC_PVDDQ_KLM_PH1_P31
  EU1A2   31     NC  IR354XX_SM  I101

NC_PVDDQ_KLM_PH2_P31   @BASEBOARD_FAB2_LIB.BASEBOARD_FAB2(SCH_1):NC_PVDDQ_KLM_PH2_P31
  EU1A1   31     NC  IR354XX_SM  I102

NC_PVDDQ_KLM_PINALRT_N   @BASEBOARD_FAB2_LIB.BASEBOARD_FAB2(SCH_1):NC_PVDDQ_KLM_PINALRT_N
  EU1B1   12  PINALRT_N  PXM1310B_QFN  I90

NC_PVDDQ_KLM_PWM3   @BASEBOARD_FAB2_LIB.BASEBOARD_FAB2(SCH_1):NC_PVDDQ_KLM_PWM3
  EU1B1    3  APWM3  PXM1310B_QFN  I90

NC_PVNN_PCH_DNC0   @BASEBOARD_FAB2_LIB.BASEBOARD_FAB2(SCH_1):NC_PVNN_PCH_DNC0
  EU8A1    1  DNC<0>  PXE1110B_QFN  I229

NC_PVNN_PCH_DNC1   @BASEBOARD_FAB2_LIB.BASEBOARD_FAB2(SCH_1):NC_PVNN_PCH_DNC1
  EU8A1    2  DNC<1>  PXE1110B_QFN  I229

NC_PVNN_PCH_DNC2   @BASEBOARD_FAB2_LIB.BASEBOARD_FAB2(SCH_1):NC_PVNN_PCH_DNC2
  EU8A1    4  DNC<2>  PXE1110B_QFN  I229

NC_PVNN_PCH_DNC3   @BASEBOARD_FAB2_LIB.BASEBOARD_FAB2(SCH_1):NC_PVNN_PCH_DNC3
  EU8A1   24  DNC<3>  PXE1110B_QFN  I229

NC_PVNN_PCH_DNC4   @BASEBOARD_FAB2_LIB.BASEBOARD_FAB2(SCH_1):NC_PVNN_PCH_DNC4
  EU8A1   28  DNC<4>  PXE1110B_QFN  I229

NC_PVNN_PCH_PH1_P31   @BASEBOARD_FAB2_LIB.BASEBOARD_FAB2(SCH_1):NC_PVNN_PCH_PH1_P31
  EU7A3   31     NC  IR354XX_SM  I116

NC_PVSA_CPU0_P31   @BASEBOARD_FAB2_LIB.BASEBOARD_FAB2(SCH_1):NC_PVSA_CPU0_P31
  EU4C1   31     NC  IR354XX_SM  I46

NC_PVSA_CPU1_P31   @BASEBOARD_FAB2_LIB.BASEBOARD_FAB2(SCH_1):NC_PVSA_CPU1_P31
  EU1C1   31     NC  IR354XX_SM  I51

NC_SPRNGVLLE_22   @BASEBOARD_FAB2_LIB.BASEBOARD_FAB2(SCH_1):NC_SPRNGVLLE_22
  EU9E1   22     NC  SPRINGVILLE_SM1  I72

NIC_LED_ACT_ANODE_R   @BASEBOARD_FAB2_LIB.BASEBOARD_FAB2(SCH_1):NIC_LED_ACT_ANODE_R
  JA9G1   L4     L4  CONN17_H71061002_PIP1  I109
  R9G4     1      A  RES         I56

NIC_MDI_MNG_RX_DN   @BASEBOARD_FAB2_LIB.BASEBOARD_FAB2(SCH_1):NIC_MDI_MNG_RX_DN
  C9G12    2      B  CAP         I100
  J1F1    E5   IOE5  CONN76_H22707001_THMT1  I111

NIC_MDI_MNG_RX_DP   @BASEBOARD_FAB2_LIB.BASEBOARD_FAB2(SCH_1):NIC_MDI_MNG_RX_DP
  C9G9     2      B  CAP         I99
  J1F1    D5   IOD5  CONN76_H22707001_THMT1  I111

NIC_MDI_MNG_TX_DN   @BASEBOARD_FAB2_LIB.BASEBOARD_FAB2(SCH_1):NIC_MDI_MNG_TX_DN
  C9G13    2      B  CAP         I102
  J1F1    B5   IOB5  CONN76_H22707001_THMT1  I111

NIC_MDI_MNG_TX_DP   @BASEBOARD_FAB2_LIB.BASEBOARD_FAB2(SCH_1):NIC_MDI_MNG_TX_DP
  C9G16    2      B  CAP         I101
  J1F1    A5   IOA5  CONN76_H22707001_THMT1  I111

NIC_MDI_SPRV_RJ45_0_DN   @BASEBOARD_FAB2_LIB.BASEBOARD_FAB2(SCH_1):NIC_MDI_SPRV_RJ45_0_DN
  EU9E1   57  MDI_MINUS0_SFP_I2C_DATA  SPRINGVILLE_SM1  I72
  R9G22    1      A  RES         I82

NIC_MDI_SPRV_RJ45_0_DP   @BASEBOARD_FAB2_LIB.BASEBOARD_FAB2(SCH_1):NIC_MDI_SPRV_RJ45_0_DP
  EU9E1   58  MDI_PLUS0_NC  SPRINGVILLE_SM1  I72
  R9G24    1      A  RES         I81

NIC_MDI_SPRV_RJ45_0_R_DN   @BASEBOARD_FAB2_LIB.BASEBOARD_FAB2(SCH_1):NIC_MDI_SPRV_RJ45_0_R_DN
  JA9G1  R10  TRD1N  CONN17_H71061002_PIP1  I109
  R9G22    2      B  RES         I82

NIC_MDI_SPRV_RJ45_0_R_DP   @BASEBOARD_FAB2_LIB.BASEBOARD_FAB2(SCH_1):NIC_MDI_SPRV_RJ45_0_R_DP
  JA9G1  R11  TRD1P  CONN17_H71061002_PIP1  I109
  R9G24    2      B  RES         I81

NIC_MDI_SPRV_RJ45_1_DN   @BASEBOARD_FAB2_LIB.BASEBOARD_FAB2(SCH_1):NIC_MDI_SPRV_RJ45_1_DN
  EU9E1   54  MDI_MINUS1_SRDS_SIG_DET  SPRINGVILLE_SM1  I72
  R9G20    1      A  RES         I80

NIC_MDI_SPRV_RJ45_1_DP   @BASEBOARD_FAB2_LIB.BASEBOARD_FAB2(SCH_1):NIC_MDI_SPRV_RJ45_1_DP
  EU9E1   55  MDI_PLUS1_SFP_I2C_CLK  SPRINGVILLE_SM1  I72
  R9G19    1      A  RES         I79

NIC_MDI_SPRV_RJ45_1_R_DN   @BASEBOARD_FAB2_LIB.BASEBOARD_FAB2(SCH_1):NIC_MDI_SPRV_RJ45_1_R_DN
  JA9G1   R5  TRD2N  CONN17_H71061002_PIP1  I109
  R9G20    2      B  RES         I80

NIC_MDI_SPRV_RJ45_1_R_DP   @BASEBOARD_FAB2_LIB.BASEBOARD_FAB2(SCH_1):NIC_MDI_SPRV_RJ45_1_R_DP
  JA9G1   R4  TRD2P  CONN17_H71061002_PIP1  I109
  R9G19    2      B  RES         I79

NIC_MDI_SPRV_RJ45_2_R_DN   @BASEBOARD_FAB2_LIB.BASEBOARD_FAB2(SCH_1):NIC_MDI_SPRV_RJ45_2_R_DN
  JA9G1   R2  TRD3N  CONN17_H71061002_PIP1  I109
  R9G17    2      B  RES         I78

NIC_MDI_SPRV_RJ45_2_R_DP   @BASEBOARD_FAB2_LIB.BASEBOARD_FAB2(SCH_1):NIC_MDI_SPRV_RJ45_2_R_DP
  JA9G1   R3  TRD3P  CONN17_H71061002_PIP1  I109
  R9G18    2      B  RES         I77

NIC_MDI_SPRV_RJ45_3_R_DN   @BASEBOARD_FAB2_LIB.BASEBOARD_FAB2(SCH_1):NIC_MDI_SPRV_RJ45_3_R_DN
  JA9G1   R9  TRD4N  CONN17_H71061002_PIP1  I109
  R9G11    2      B  RES         I76

NIC_MDI_SPRV_RJ45_3_R_DP   @BASEBOARD_FAB2_LIB.BASEBOARD_FAB2(SCH_1):NIC_MDI_SPRV_RJ45_3_R_DP
  JA9G1   R8  TRD4P  CONN17_H71061002_PIP1  I109
  R9G9     2      B  RES         I75

NIC_SER_N_MDI_3_DN   @BASEBOARD_FAB2_LIB.BASEBOARD_FAB2(SCH_1):NIC_SER_N_MDI_3_DN
  C9G12    1      A  CAP         I100
  EU9E1   49  MDI_MINUS3_SERN  SPRINGVILLE_SM1  I72
  R9G11    1      A  RES         I76

NIC_SER_P_MDI_3_DP   @BASEBOARD_FAB2_LIB.BASEBOARD_FAB2(SCH_1):NIC_SER_P_MDI_3_DP
  C9G9     1      A  CAP         I99
  EU9E1   50  MDI_PLUS3_SERP  SPRINGVILLE_SM1  I72
  R9G9     1      A  RES         I75

NIC_SET_N_MDI_2_DN   @BASEBOARD_FAB2_LIB.BASEBOARD_FAB2(SCH_1):NIC_SET_N_MDI_2_DN
  C9G13    1      A  CAP         I102
  EU9E1   52  MDI_MINUS2_SETN  SPRINGVILLE_SM1  I72
  R9G17    1      A  RES         I78

NIC_SET_P_MDI_2_DP   @BASEBOARD_FAB2_LIB.BASEBOARD_FAB2(SCH_1):NIC_SET_P_MDI_2_DP
  C9G16    1      A  CAP         I101
  EU9E1   53  MDI_PLUS2_SETP  SPRINGVILLE_SM1  I72
  R9G18    1      A  RES         I77

P0V7_GTL2014_2   @BASEBOARD_FAB2_LIB.BASEBOARD_FAB2(SCH_1):P0V7_GTL2014_2
  C1U22    1      A  CAP_A       I27
  R1U37    1      A  RES         I26
  R1U43    2      B  RES         I25
  U9G1     4   VREF  GTL2014_SM   I1

P0V7_GTL2104_5_VREF   @BASEBOARD_FAB2_LIB.BASEBOARD_FAB2(SCH_1):P0V7_GTL2104_5_VREF
  C2T32    1      A  CAP_A       I95
  R2T36    2      B  RES         I97
  R2T39    1      A  RES         I98
  U2T4     4   VREF  GTL2014_SM  I30

P0V7_GTL2104_VREF_0   @BASEBOARD_FAB2_LIB.BASEBOARD_FAB2(SCH_1):P0V7_GTL2104_VREF_0
  C7D5     1      A  CAP_A       I52
  R7D32    1      A  RES         I48
  R7D33    2      B  RES         I51
  U7D2     4   VREF  GTL2014_SM  I32

P0V7_GTL2104_VREF_1   @BASEBOARD_FAB2_LIB.BASEBOARD_FAB2(SCH_1):P0V7_GTL2104_VREF_1
  C3P49    1      A  CAP_A       I37
  R3P45    2      B  RES         I39
  R3P49    1      A  RES         I38
  U3P2     4   VREF  GTL2014_SM   I1

P0V9_LAN        @BASEBOARD_FAB2_LIB.BASEBOARD_FAB2(SCH_1):P0V9_LAN
  C1R15    1      A  CAP_A       I160
  C1R16    1      A  CAP         I161
  C1R18    1      A  CAP_A       I157
  C1R24    1      A  CAP_A       I159
  C1T4     1      A  CAP         I134
  C1T5     1      A  CAP_A       I158
  C9E1     1      A  CAP_A       I163
  C9E12    1      A  CAP_A       I241
  EU9E1   11  VDD0P9<2>  SPRINGVILLE_SM1  I72
  EU9E1   32  VDD0P9<1>  SPRINGVILLE_SM1  I72
  EU9E1   42  VDD0P9<3>  SPRINGVILLE_SM1  I72
  EU9E1   59  VDD0P9<0>  SPRINGVILLE_SM1  I72
  R1R15    1      A  RES         I237

P0V9_LAN_I210   @BASEBOARD_FAB2_LIB.BASEBOARD_FAB2(SCH_1):P0V9_LAN_I210
  EU9E1   38  VDD0P9_OUT  SPRINGVILLE_SM1  I72
  R1R15    2      B  RES         I237

P12V            @BASEBOARD_FAB2_LIB.BASEBOARD_FAB2(SCH_1):P12V
  C2U20    1      A  CAP_A        I1
  C2U24    1      A  CAP_A        I2
  C7E8     1      A  CAP         I50
  C7E9     1      A  CAP_A       I49
  EU7E1    6      S  SLG55021_SM  I19
  F9B1     1   A<0>  FUSE_SM     I38
  J8G1     1    IO1  SCONN200_H68296001_SM  I258
  J8G1     2    IO2  SCONN200_H68296001_SM  I258
  J8G1     3    IO3  SCONN200_H68296001_SM  I258
  J8G1     4    IO4  SCONN200_H68296001_SM  I258
  J8G1     5    IO5  SCONN200_H68296001_SM  I258
  J8G1     6    IO6  SCONN200_H68296001_SM  I258
  J8G1     7    IO7  SCONN200_H68296001_SM  I258
  J8G1     8    IO8  SCONN200_H68296001_SM  I258
  J8G1     9    IO9  SCONN200_H68296001_SM  I258
  J8G1    10   IO10  SCONN200_H68296001_SM  I258
  J8G1    11   IO11  SCONN200_H68296001_SM  I258
  J8G1    12   IO12  SCONN200_H68296001_SM  I258
  Q7E7     1    SRC  MOSFET_N_LCC3  I88
  R8D38    1      A  RES         I112

P12V_FAN        @BASEBOARD_FAB2_LIB.BASEBOARD_FAB2(SCH_1):P12V_FAN
  C1B18    1      A  CAP         I61
  C1B19    1      A  CAP_A       I64
  C1E20    1      A  CAP_A        I4
  C1E21    1      A  CAP          I3
  C9M4     1      A  CAP         I27
  C9M5     1      A  CAP_A       I26
  EU9M1    6      S  SLG55021_SM  I69
  J1B2     2    IO2  CONN6_C74770005  I32
  J1F2     2    IO2  CONN6_C74770005   I1
  Q1B1     1    SRC  MOSFET_N_LCC3  I86

P12V_FAN_SWITCH_G   @BASEBOARD_FAB2_LIB.BASEBOARD_FAB2(SCH_1):P12V_FAN_SWITCH_G
  EU9M1    7      G  SLG55021_SM  I69
  Q1B1     4   GATE  MOSFET_N_LCC3  I86

P12V_HDD_SATA   @BASEBOARD_FAB2_LIB.BASEBOARD_FAB2(SCH_1):P12V_HDD_SATA
  C9B2     1      A  CAP         I36
  F9B1     2   B<0>  FUSE_SM     I38
  J2L1     4    IO4  CONN4_H73295001_PIP  I53
  J8A4     4    IO4  CONN4_H73295001_PIP  I25

P12V_HSC_SENN0   @BASEBOARD_FAB2_LIB.BASEBOARD_FAB2(SCH_1):P12V_HSC_SENN0
  R1D47    1      A  RES         I52
  R1D49    4      4  RES_PWR_6PAD  I50

P12V_HSC_SENN1   @BASEBOARD_FAB2_LIB.BASEBOARD_FAB2(SCH_1):P12V_HSC_SENN1
  R9P26    1      A  RES         I51
  R9R1     4      4  RES_PWR_6PAD  I49

P12V_HSC_SENP0   @BASEBOARD_FAB2_LIB.BASEBOARD_FAB2(SCH_1):P12V_HSC_SENP0
  R1D46    1      A  RES         I48
  R1D49    3      3  RES_PWR_6PAD  I50

P12V_HSC_SENP1   @BASEBOARD_FAB2_LIB.BASEBOARD_FAB2(SCH_1):P12V_HSC_SENP1
  R9P27    1      A  RES         I47
  R9R1     3      3  RES_PWR_6PAD  I49

P12V_HSC_VCC    @BASEBOARD_FAB2_LIB.BASEBOARD_FAB2(SCH_1):P12V_HSC_VCC
  C1D25    1      A  CAP_0402     I3
  EU1D2   30    VCC  ADM1278_SM  I10
  R9P30    2      B  RES          I2

P12V_MB0_SW     @BASEBOARD_FAB2_LIB.BASEBOARD_FAB2(SCH_1):P12V_MB0_SW
  EU1E1    5      D  MOSFETN_1D3S_SOT5  I59
  EU1E3    5      D  MOSFETN_1D3S_SOT5  I54
  EU9R1    5      D  MOSFETN_1D3S_SOT5  I57
  R1D49    2      2  RES_PWR_6PAD  I50
  R1D49    6      6  RES_PWR_6PAD  I50
  R9R1     2      2  RES_PWR_6PAD  I49
  R9R1     6      6  RES_PWR_6PAD  I49

P12V_NVDIMM_ABC   @BASEBOARD_FAB2_LIB.BASEBOARD_FAB2(SCH_1):P12V_NVDIMM_ABC
  C6T2     1      A  CAP         I54
  C6U10    1      A  CAP         I65
  C6U18    1      A  CAP         I52
  J4G1     1  12V<1>  SCONN288_H44441004_PIP  I260
  J4G1   145  12V<0>  SCONN288_H44441004_PIP  I260
  J4G2     1  12V<1>  SCONN288_H44441004_PIP  I169
  J4G2   145  12V<0>  SCONN288_H44441004_PIP  I169
  J4G3     1  12V<1>  SCONN288_H44441004_PIP  I179
  J4G3   145  12V<0>  SCONN288_H44441004_PIP  I179
  J6T1     1  12V<1>  SCONN288_H44441003_PIP  I75
  J6T1   145  12V<0>  SCONN288_H44441003_PIP  I75
  J6U1     1  12V<1>  SCONN288_H44441003_PIP  I67
  J6U1   145  12V<0>  SCONN288_H44441003_PIP  I67
  J6U2     1  12V<1>  SCONN288_H44441003_PIP  I171
  J6U2   145  12V<0>  SCONN288_H44441003_PIP  I171
  R4F2     1      A  RES         I99
  U4F1     4    RSN  MAX9634_SOT  I97

P12V_NVDIMM_DEF   @BASEBOARD_FAB2_LIB.BASEBOARD_FAB2(SCH_1):P12V_NVDIMM_DEF
  C4A4     1      A  CAP         I62
  C4A17    1      A  CAP         I67
  C4B11    1      A  CAP         I59
  J4A1     1  12V<1>  SCONN288_H44441004_PIP  I171
  J4A1   145  12V<0>  SCONN288_H44441004_PIP  I171
  J4A2     1  12V<1>  SCONN288_H44441004_PIP  I167
  J4A2   145  12V<0>  SCONN288_H44441004_PIP  I167
  J4B1     1  12V<1>  SCONN288_H44441004_PIP  I169
  J4B1   145  12V<0>  SCONN288_H44441004_PIP  I169
  J6L1     1  12V<1>  SCONN288_H44441003_PIP  I170
  J6L1   145  12V<0>  SCONN288_H44441003_PIP  I170
  J6L2     1  12V<1>  SCONN288_H44441003_PIP  I55
  J6L2   145  12V<0>  SCONN288_H44441003_PIP  I55
  J6M1     1  12V<1>  SCONN288_H44441003_PIP  I50
  J6M1   145  12V<0>  SCONN288_H44441003_PIP  I50
  R4B12    1      A  RES         I121
  U4B1     4    RSN  MAX9634_SOT  I120

P12V_NVDIMM_GHJ   @BASEBOARD_FAB2_LIB.BASEBOARD_FAB2(SCH_1):P12V_NVDIMM_GHJ
  C9T8     1      A  CAP         I70
  C9U8     1      A  CAP         I76
  C9U11    1      A  CAP         I73
  J1G1     1  12V<1>  SCONN288_H44441004_PIP  I171
  J1G1   145  12V<0>  SCONN288_H44441004_PIP  I171
  J1G2     1  12V<1>  SCONN288_H44441004_PIP  I169
  J1G2   145  12V<0>  SCONN288_H44441004_PIP  I169
  J1G3     1  12V<1>  SCONN288_H44441004_PIP  I169
  J1G3   145  12V<0>  SCONN288_H44441004_PIP  I169
  J9T1     1  12V<1>  SCONN288_H44441003_PIP  I75
  J9T1   145  12V<0>  SCONN288_H44441003_PIP  I75
  J9U1     1  12V<1>  SCONN288_H44441003_PIP  I56
  J9U1   145  12V<0>  SCONN288_H44441003_PIP  I56
  J9U2     1  12V<1>  SCONN288_H44441003_PIP  I171
  J9U2   145  12V<0>  SCONN288_H44441003_PIP  I171
  R1F3     1      A  RES         I131
  U1F1     4    RSN  MAX9634_SOT  I133

P12V_NVDIMM_KLM   @BASEBOARD_FAB2_LIB.BASEBOARD_FAB2(SCH_1):P12V_NVDIMM_KLM
  C1A4     1      A  CAP         I79
  C1A16    1      A  CAP         I85
  C1B7     1      A  CAP         I82
  J1A1     1  12V<1>  SCONN288_H44441004_PIP  I169
  J1A1   145  12V<0>  SCONN288_H44441004_PIP  I169
  J1A2     1  12V<1>  SCONN288_H44441004_PIP  I172
  J1A2   145  12V<0>  SCONN288_H44441004_PIP  I172
  J1B1     1  12V<1>  SCONN288_H44441004_PIP  I167
  J1B1   145  12V<0>  SCONN288_H44441004_PIP  I167
  J9L1     1  12V<1>  SCONN288_H44441003_PIP  I168
  J9L1   145  12V<0>  SCONN288_H44441003_PIP  I168
  J9L2     1  12V<1>  SCONN288_H44441003_PIP  I55
  J9L2   145  12V<0>  SCONN288_H44441003_PIP  I55
  J9M1     1  12V<1>  SCONN288_H44441003_PIP  I57
  J9M1   145  12V<0>  SCONN288_H44441003_PIP  I57
  R9M4     1      A  RES         I142
  U1B1     4    RSN  MAX9634_SOT  I144

P12V_PSU        @BASEBOARD_FAB2_LIB.BASEBOARD_FAB2(SCH_1):P12V_PSU
  C1E12    1      A  CAP         I32
  C1E15    1      A  CAP         I35
  C1E16    1      A  CAP_A       I39
  C1E17    1      A  CAP_A       I38
  C9R5     1      A  CAP         I31
  C9R6     1      A  CAP_A       I37
  C9R12    1      A  CAP_A       I36
  J1D1    A1     A1  CONN12_G98257001_THMT  I78
  J1D1    A2     A2  CONN12_G98257001_THMT  I78
  J1D1    A3     A3  CONN12_G98257001_THMT  I78
  J1D1    B1     B1  CONN12_G98257001_THMT  I78
  J1D1    B2     B2  CONN12_G98257001_THMT  I78
  J1D1    B3     B3  CONN12_G98257001_THMT  I78
  J1E1    A1     A1  CONN12_G98257001_THMT  I29
  J1E1    A2     A2  CONN12_G98257001_THMT  I29
  J1E1    A3     A3  CONN12_G98257001_THMT  I29
  J1E1    B1     B1  CONN12_G98257001_THMT  I29
  J1E1    B2     B2  CONN12_G98257001_THMT  I29
  J1E1    B3     B3  CONN12_G98257001_THMT  I29
  R1D15    1      A  RES         I92
  R1D49    1      1  RES_PWR_6PAD  I50
  R1D49    5      5  RES_PWR_6PAD  I50
  R9P28    1      A  RES          I6
  R9P29    1      A  RES         I12
  R9P30    1      A  RES          I2
  R9R1     1      1  RES_PWR_6PAD  I49
  R9R1     5      5  RES_PWR_6PAD  I49
  R9T6     1      A  RES         I183
  R9T9     1      A  RES         I177
  VR1D1    1      C  ZENER_SM    I99

P12V_STBY       @BASEBOARD_FAB2_LIB.BASEBOARD_FAB2(SCH_1):P12V_STBY
  C1B14    1      A  CAPP        I84
  C1D9     1      A  CAP_A       I187
  C1F7     1      A  CAPP        I85
  C1M5     1      A  CAPP        I103
  C1M22    1      A  CAP_A        I8
  C1M23    1      A  CAP_A        I7
  C1M26    1      A  CAP          I6
  C1M27    1      A  CAP          I3
  C1R23    1      A  CAPP        I101
  C2P10    1      A  CAP         I41
  C2P11    1      A  CAP_A       I21
  C2P12    1      A  CAP_A       I23
  C2P13    1      A  CAP_A       I57
  C2P14    1      A  CAP_A       I56
  C2P15    1      A  CAP_A       I55
  C2P16    1      A  CAP_A       I53
  C2R15    1      A  CAP_A        I2
  C2R16    1      A  CAP_A       I40
  C2R17    1      A  CAP_A       I25
  C2R18    1      A  CAP_A        I3
  C3B6     1      A  CAPP        I100
  C3T3     1      A  CAPP        I113
  C3T6     1      A  CAPP        I98
  C3T13    1      A  CAPP        I104
  C3T15    1      A  CAPP        I106
  C4B13    1      A  CAPP        I83
  C4B14    1      A  CAPP        I97
  C4F4     1      A  CAPP        I112
  C4F5     1      A  CAPP        I96
  C4F6     1      A  CAPP        I82
  C4M6     1      A  CAPP        I102
  C4M7     1      A  CAPP        I105
  C6N5     1      A  CAPP        I109
  C7E5     1      A  CAP_A       I52
  C7E6     1      A  CAP         I53
  C7M6     1      A  CAPP        I108
  C9M3     1      A  CAPP        I99
  C9M9     1      A  CAP_A       I76
  C9M10    1      A  CAP         I74
  C9P6     1      A  CAP_A       I185
  C9T3     1      A  CAPP        I111
  CR1F5    1      C  DIODE_SM    I220
  EU1E1    1     S1  MOSFETN_1D3S_SOT5  I59
  EU1E1    2     S2  MOSFETN_1D3S_SOT5  I59
  EU1E1    3     S3  MOSFETN_1D3S_SOT5  I59
  EU1E3    1     S1  MOSFETN_1D3S_SOT5  I54
  EU1E3    2     S2  MOSFETN_1D3S_SOT5  I54
  EU1E3    3     S3  MOSFETN_1D3S_SOT5  I54
  EU7E1    5      D  SLG55021_SM  I19
  EU9M1    5      D  SLG55021_SM  I69
  EU9R1    1     S1  MOSFETN_1D3S_SOT5  I57
  EU9R1    2     S2  MOSFETN_1D3S_SOT5  I57
  EU9R1    3     S3  MOSFETN_1D3S_SOT5  I57
  FB4A1    1      A  FERRITE_SM  I154
  FB4G1    1      A  FERRITE_SM  I198
  FB7B1    1      A  FERRITE_SM  I200
  FB7E1    1      A  FERRITE_SM  I82
  FB7F1    1      A  FERRITE_SM  I162
  FB9E1    1      A  FERRITE_SM  I132
  J4B2    A1   IOA1  SCONN120_H61426002_SM  I46
  J4B2    A2   IOA2  SCONN120_H61426002_SM  I46
  J4B2    A3   IOA3  SCONN120_H61426002_SM  I46
  J4B2    A4   IOA4  SCONN120_H61426002_SM  I46
  J4B2    A5   IOA5  SCONN120_H61426002_SM  I46
  J4B2    A6   IOA6  SCONN120_H61426002_SM  I46
  J4B2    A7   IOA7  SCONN120_H61426002_SM  I46
  J4B2    A8   IOA8  SCONN120_H61426002_SM  I46
  J4B2    B1   IOB1  SCONN120_H61426002_SM  I46
  J4B2    B2   IOB2  SCONN120_H61426002_SM  I46
  J4B2    B3   IOB3  SCONN120_H61426002_SM  I46
  J4B2    B4   IOB4  SCONN120_H61426002_SM  I46
  J4B2    B5   IOB5  SCONN120_H61426002_SM  I46
  J4B2    B6   IOB6  SCONN120_H61426002_SM  I46
  J4B2    B7   IOB7  SCONN120_H61426002_SM  I46
  J4B2    B8   IOB8  SCONN120_H61426002_SM  I46
  J6B1    A1   IOA1  SCONN120_H61426002_SM  I56
  J6B1    A2   IOA2  SCONN120_H61426002_SM  I56
  J6B1    A3   IOA3  SCONN120_H61426002_SM  I56
  J6B1    A4   IOA4  SCONN120_H61426002_SM  I56
  J6B1    A5   IOA5  SCONN120_H61426002_SM  I56
  J6B1    A6   IOA6  SCONN120_H61426002_SM  I56
  J6B1    A7   IOA7  SCONN120_H61426002_SM  I56
  J6B1    A8   IOA8  SCONN120_H61426002_SM  I56
  J6B1    B1   IOB1  SCONN120_H61426002_SM  I56
  J6B1    B2   IOB2  SCONN120_H61426002_SM  I56
  J6B1    B3   IOB3  SCONN120_H61426002_SM  I56
  J6B1    B4   IOB4  SCONN120_H61426002_SM  I56
  J6B1    B5   IOB5  SCONN120_H61426002_SM  I56
  J6B1    B6   IOB6  SCONN120_H61426002_SM  I56
  J6B1    B7   IOB7  SCONN120_H61426002_SM  I56
  J6B1    B8   IOB8  SCONN120_H61426002_SM  I56
  J8E3     2    IO2  SCONN80_E67482007_SM  I119
  J8E3     4    IO4  SCONN80_E67482007_SM  I119
  J8E4    33   IO33  SCONN64_H87568002_A_SMT  I27
  J8E4    34   IO34  SCONN64_H87568002_A_SMT  I27
  J8E4    35   IO35  SCONN64_H87568002_A_SMT  I27
  J9B3     2    IO2  SCONN120_A28699018_SM  I336
  J9B3     4    IO4  SCONN120_A28699018_SM  I336
  J9B3     6    IO6  SCONN120_A28699018_SM  I336
  L1B1     1    INA  INDUCTOR    I124
  L1B2     1    INA  INDUCTOR    I32
  L1F1     1    INA  INDUCTOR    I124
  L4C1     1    INA  INDUCTOR    I46
  L7A5     1    INA  INDUCTOR    I124
  L7C1     1    INA  INDUCTOR    I56
  L7F2     1    INA  INDUCTOR    I124
  Q1B1     5    DRN  MOSFET_N_LCC3  I86
  Q7E7     5    DRN  MOSFET_N_LCC3  I88
  R1D36    1      A  RES         I65
  R1F3     2      B  RES         I131
  R1L9     1      A  RES         I130
  R1U32    1      A  RES         I82
  R3P48    1      A  RES         I74
  R4B12    2      B  RES         I121
  R4F2     2      B  RES         I99
  R9M4     2      B  RES         I142
  R9P7     1      A  RES         I145
  R9P13    1      A  RES         I107
  R9P18    1      A  RES         I41
  R9P23    1      A  RES         I54
  R9P33    1      A  RES         I222
  U1B1     5    RSP  MAX9634_SOT  I144
  U1D2     2    VDD  TPS3700_SM  I170
  U1F1     5    RSP  MAX9634_SOT  I133
  U4B1     5    RSP  MAX9634_SOT  I120
  U4F1     5    RSP  MAX9634_SOT  I97
  U9P1     2    VDD  TPS3700_SM  I163

P12V_SWITCH_G   @BASEBOARD_FAB2_LIB.BASEBOARD_FAB2(SCH_1):P12V_SWITCH_G
  EU7E1    7      G  SLG55021_SM  I19
  Q7E7     4   GATE  MOSFET_N_LCC3  I88

P1V05_PCH_STBY   @BASEBOARD_FAB2_LIB.BASEBOARD_FAB2(SCH_1):P1V05_PCH_STBY
  C1L5     1      A  CAP_A       I30
  C2L25    1      A  CAPP        I79
  C2L46    1      A  CAPP        I77
  C2M6     1      A  CAP_A       I76
  C2M8     1      A  CAP_A       I74
  C2M11    1      A  CAP         I35
  C2M12    1      A  CAP_A       I52
  C2M13    1      A  CAP_A       I48
  C2M17    1      A  CAP         I34
  C2M18    1      A  CAP_A       I29
  C2M19    1      A  CAP_A       I31
  C2M20    1      A  CAP_A       I39
  C2M21    1      A  CAP_A       I28
  C2M22    1      A  CAP_A       I27
  C2M25    1      A  CAP_A       I78
  C2N2     1      A  CAP_A       I41
  C2N7     1      A  CAP_A       I43
  C2N8     1      A  CAP_A       I47
  C2N10    1      A  CAP_A       I50
  C2N13    1      A  CAP_A       I40
  C3L19    1      A  CAPP        I76
  C3M21    1      A  CAP_A        I9
  C3M22    1      A  CAP_A       I18
  C3M30    1      A  CAP_A       I27
  C3M31    1      A  CAP_A       I57
  C3M38    1      A  CAP_A       I32
  C3M39    1      A  CAP_A       I44
  C3M42    1      A  CAP_A       I45
  C3M43    1      A  CAP_A       I42
  C7A42    1      A  CAP         I46
  C7B15    1      A  CAP_A        I1
  C7B16    1      A  CAP_A        I3
  C7B17    1      A  CAP_A       I18
  C7B18    1      A  CAP_A       I12
  C7B19    1      A  CAP_A        I2
  C7B20    1      A  CAP_A        I6
  C7B21    1      A  CAP_A        I4
  C7B22    1      A  CAP_A       I10
  C7B23    1      A  CAP_A        I7
  C7B24    1      A  CAP_A       I11
  C8A13    1      A  CAP         I37
  C8A15    1      A  CAPP        I78
  C8B9     1      A  CAP_A       I14
  C8B10    1      A  CAP_A        I8
  C8B11    1      A  CAP_A       I15
  C8B13    1      A  CAP_A       I20
  C8B14    1      A  CAP_A       I16
  C8B15    1      A  CAP         I24
  C8B16    1      A  CAP         I22
  C9A6     1      A  CAP_A       I25
  EU7A2    1    VOS  IR354XX_SM  I117
  FB1U3    2      B  FERRITE     I57
  FB2M1    1      A  FERRITE_SM  I46
  FB2M2    1      A  FERRITE_SM  I69
  FB3M1    1      A  FERRITE_SM   I8
  FB3M2    1      A  FERRITE_SM  I17
  FB3M3    1      A  FERRITE_SM  I26
  FB3M4    1      A  FERRITE_SM  I56
  J9A3    43   IO43  SCONN60_C21100002  I26
  J9A3    44   IO44  SCONN60_C21100002  I26
  L2M1     1    INA  INDUCTOR    I71
  L7A4     2    INB  INDUCTOR    I45
  R1L39    1      A  RES         I76
  R1L41    1      A  RES         I77
  R3N15    1      A  RES         I318
  R3N16    1      A  RES         I321
  R3P5     1      A  RES         I316
  R3P6     1      A  RES         I317
  R3P7     1      A  RES         I315
  R3P8     1      A  RES         I322
  R3P53    1      A  RES         I357
  R7C21    1      A  RES          I9
  R7D44    1      A  RES         I356
  R8A13    1      A  RES         I79
  R8A14    1      A  RES         I80
  R8B14    2      B  RES         I56
  R9A11    1      A  RES         I78
  R9A17    2      B  RES         I57
  U7C1   AA24  VCCPRIM_1P05<18>  LBG_CORE_QAT_EXT_D  I63
  U7C1   AA45  VCCPRIM_1P05<9>  LBG_CORE_QAT_EXT_D  I63
  U7C1   AA46  VCCPRIM_1P05<8>  LBG_CORE_QAT_EXT_D  I63
  U7C1   AC26  VCCPRIM_1P05<7>  LBG_CORE_QAT_EXT_D  I63
  U7C1   AE27  VCCMPHY_1P05<13>  LBG_CORE_QAT_EXT_D  I21
  U7C1   AH50  VCCA_CLKUNF_1P05<0>  LBG_CORE_QAT_EXT_D  I63
  U7C1   AJ29  VCCPRIM_1P05<6>  LBG_CORE_QAT_EXT_D  I63
  U7C1   AJ43  VCCMPHY_1P05<2>  LBG_CORE_QAT_EXT_D  I63
  U7C1   AK27  VCCPRIM_1P05<17>  LBG_CORE_QAT_EXT_D  I63
  U7C1   AK43  VCCMPHY_1P05<12>  LBG_CORE_QAT_EXT_D  I63
  U7C1   AK45  VCCMPHY_1P05<11>  LBG_CORE_QAT_EXT_D  I63
  U7C1   AM27  VCCPRIM_1P05<5>  LBG_CORE_QAT_EXT_D  I63
  U7C1   AM43  VCCMPHY_1P05<10>  LBG_CORE_QAT_EXT_D  I63
  U7C1   AM45  VCCMPHY_1P05<9>  LBG_CORE_QAT_EXT_D  I63
  U7C1   AM48  VCCP_UPPLLUNF_1P05  LBG_CORE_QAT_EXT_D  I63
  U7C1   AP43  VCCMPHY_1P05<8>  LBG_CORE_QAT_EXT_D  I63
  U7C1   AP45  VCCMPHY_1P05<7>  LBG_CORE_QAT_EXT_D  I63
  U7C1   AT39  VCCPRIM_1P05<4>  LBG_CORE_QAT_EXT_D  I63
  U7C1   AT43  VCCMPHY_1P05<6>  LBG_CORE_QAT_EXT_D  I63
  U7C1   AT45  VCCMPHY_1P05<5>  LBG_CORE_QAT_EXT_D  I63
  U7C1   AT48  VCCP_HSIOPLLUNF_1P05  LBG_CORE_QAT_EXT_D  I63
  U7C1   AU37  VCCPRIM_1P05<3>  LBG_CORE_QAT_EXT_D  I63
  U7C1   AU39  VCCPRIM_1P05<2>  LBG_CORE_QAT_EXT_D  I63
  U7C1   AU43  VCCMPHY_1P05<4>  LBG_CORE_QAT_EXT_D  I63
  U7C1   AU45  VCCMPHY_1P05<3>  LBG_CORE_QAT_EXT_D  I63
  U7C1   AW43  VCCMPHY_1P05<1>  LBG_CORE_QAT_EXT_D  I63
  U7C1   AW45  VCCMPHY_1P05<0>  LBG_CORE_QAT_EXT_D  I63
  U7C1   BA30  VCCP10GBE_LV_1P05<6>  LBG_CORE_QAT_EXT_D  I63
  U7C1   BA32  VCCP10GBE_LV_1P05<5>  LBG_CORE_QAT_EXT_D  I63
  U7C1   BA34  VCCP10GBE_LV_1P05<4>  LBG_CORE_QAT_EXT_D  I63
  U7C1   BA36  VCCP10GBE_LV_1P05<3>  LBG_CORE_QAT_EXT_D  I63
  U7C1   BA37  VCCP10GBE_LV_1P05<2>  LBG_CORE_QAT_EXT_D  I63
  U7C1   BB33  VCCP10GBE_LV_1P05<1>  LBG_CORE_QAT_EXT_D  I63
  U7C1   BB37  VCCP10GBE_LV_1P05<0>  LBG_CORE_QAT_EXT_D  I63
  U7C1   BE48  VCCPRIM_1P05<1>  LBG_CORE_QAT_EXT_D  I63
  U7C1   BF46  VCCPRIM_1P05<0>  LBG_CORE_QAT_EXT_D  I63
  U7C1   R42  VCCPRIM_1P05<16>  LBG_CORE_QAT_EXT_D  I63
  U7C1   R46  VCCPRIM_1P05<15>  LBG_CORE_QAT_EXT_D  I63
  U7C1   T44  VCCPRIM_1P05<14>  LBG_CORE_QAT_EXT_D  I63
  U7C1   U46  VCCPRIM_1P05<13>  LBG_CORE_QAT_EXT_D  I63
  U7C1   U50  VCCA_CLKUNF_1P05<1>  LBG_CORE_QAT_EXT_D  I63
  U7C1   V44  VCCPRIM_1P05<12>  LBG_CORE_QAT_EXT_D  I63
  U7C1   Y26  VCCPRIM_1P05<19>  LBG_CORE_QAT_EXT_D  I63
  U7C1   Y45  VCCPRIM_1P05<11>  LBG_CORE_QAT_EXT_D  I63
  U7C1   Y46  VCCPRIM_1P05<10>  LBG_CORE_QAT_EXT_D  I63

P1V05_PCH_STBY_ISCLK_PLL   @BASEBOARD_FAB2_LIB.BASEBOARD_FAB2(SCH_1):P1V05_PCH_STBY_ISCLK_PLL
  C3M24    1      A  CAP         I81
  C3M29    1      A  CAP_A       I80
  FB3M4    2      B  FERRITE_SM  I56
  U7C1   AE46  VCCA_CLKFILT_1P05<4>  LBG_CORE_QAT_EXT_D  I63
  U7C1   AG45  VCCA_CLKFILT_1P05<1>  LBG_CORE_QAT_EXT_D  I63
  U7C1   AJ46  VCCA_CLKFILT_1P05<2>  LBG_CORE_QAT_EXT_D  I63
  U7C1   AJ48  VCCA_CLKFILT_1P05<3>  LBG_CORE_QAT_EXT_D  I63
  U7C1   W50  VCCA_CLKFILT_1P05<0>  LBG_CORE_QAT_EXT_D  I63

P1V05_PCH_STBY_KR_PLL   @BASEBOARD_FAB2_LIB.BASEBOARD_FAB2(SCH_1):P1V05_PCH_STBY_KR_PLL
  C2N5     1      A  CAP_A       I65
  C2N6     1      A  CAP         I64
  L2M1     2    INB  INDUCTOR    I71
  R2M6     2      B  RES         I99
  R2N4     1      A  RES         I96
  U7C1   BA39  VCCP10GBEPLL_1P05<3>  LBG_CORE_QAT_EXT_D  I63
  U7C1   BA41  VCCP10GBEPLL_1P05<2>  LBG_CORE_QAT_EXT_D  I63
  U7C1   BB40  VCCP10GBEPLL_1P05<1>  LBG_CORE_QAT_EXT_D  I63
  U7C1   BD38  VCCP10GBEPLL_1P05<0>  LBG_CORE_QAT_EXT_D  I63

P1V05_PCH_STBY_VCCA_PLL0   @BASEBOARD_FAB2_LIB.BASEBOARD_FAB2(SCH_1):P1V05_PCH_STBY_VCCA_PLL0
  C3M18    1      A  CAP         I85
  C3M20    1      A  CAP_A       I84
  FB3M2    2      B  FERRITE_SM  I17
  U7C1   AG48  VCCA_PLL0_1P05  LBG_CORE_QAT_EXT_D  I63

P1V05_PCH_STBY_VCCA_PLL1   @BASEBOARD_FAB2_LIB.BASEBOARD_FAB2(SCH_1):P1V05_PCH_STBY_VCCA_PLL1
  C3M17    1      A  CAP         I86
  C3M19    1      A  CAP_A       I87
  FB3M1    2      B  FERRITE_SM   I8
  U7C1   AE45  VCCA_PLL1_1P05  LBG_CORE_QAT_EXT_D  I63

P1V05_PCH_STBY_VCCA_XTAL   @BASEBOARD_FAB2_LIB.BASEBOARD_FAB2(SCH_1):P1V05_PCH_STBY_VCCA_XTAL
  C3M23    1      A  CAP         I82
  C3M27    1      A  CAP_A       I83
  FB3M3    2      B  FERRITE_SM  I26
  U7C1   AD50  VCCA_CLKXTAL_1P05  LBG_CORE_QAT_EXT_D  I63

P1V05_PCH_STBY_WM20_PLL   @BASEBOARD_FAB2_LIB.BASEBOARD_FAB2(SCH_1):P1V05_PCH_STBY_WM20_PLL
  C2M5     1      A  CAP         I43
  C2M7     1      A  CAP_A       I44
  FB2M1    2      B  FERRITE_SM  I46
  U7C1   AK50  VCCP_UPPLL_1P05<2>  LBG_CORE_QAT_EXT_D  I63
  U7C1   AN50  VCCP_UPPLL_1P05<0>  LBG_CORE_QAT_EXT_D  I63

P1V05_PCH_STBY_WM26_PLL   @BASEBOARD_FAB2_LIB.BASEBOARD_FAB2(SCH_1):P1V05_PCH_STBY_WM26_PLL
  C2M9     1      A  CAP_A       I50
  C2M10    1      A  CAP         I49
  FB2M2    2      B  FERRITE_SM  I69
  U7C1   AP48  VCCP_HSIOPLL_1P05<3>  LBG_CORE_QAT_EXT_D  I63
  U7C1   AU48  VCCP_HSIOPLL_1P05<2>  LBG_CORE_QAT_EXT_D  I63
  U7C1   AW48  VCCP_HSIOPLL_1P05<0>  LBG_CORE_QAT_EXT_D  I63

P1V26_BMC_STBY   @BASEBOARD_FAB2_LIB.BASEBOARD_FAB2(SCH_1):P1V26_BMC_STBY
  C1T24    1      A  CAP_A       I81
  C1T27    1      A  CAP_A       I82
  C1T28    1      A  CAP_A       I77
  C1T34    1      A  CAP_A       I80
  C1T36    1      A  CAP_A       I83
  C1T42    1      A  CAP         I85
  C1U1     1      A  CAP         I84
  C1U6     1      A  CAP_A       I78
  C1U7     1      A  CAP_A       I79
  C9E10    1      A  CAP         I23
  C9F4     1      A  CAP         I30
  EU9F1    1  VOUT<0>  RT9059_DFN  I40
  EU9F1    2  VOUT<1>  RT9059_DFN  I40
  EU9F1    3  VOUT<2>  RT9059_DFN  I40
  FB9F1    1      A  FERRITE     I107
  R9F6     1      A  RES         I17
  U9F4   F14  IV12D<0>  AST1250_BGA  I11
  U9F4   F15  IV12D<1>  AST1250_BGA  I11
  U9F4    K6  IV12D<2>  AST1250_BGA  I11
  U9F4   K17  PEAV12  AST1250_BGA  I11
  U9F4    L6  IV12D<3>  AST1250_BGA  I11
  U9F4   L17  IV12D<4>  AST1250_BGA  I11
  U9F4    P6  IV12D<5>  AST1250_BGA  I11
  U9F4   P17  IV12D<6>  AST1250_BGA  I11
  U9F4    R6  IV12D<7>  AST1250_BGA  I11
  U9F4   R17  IV12D<8>  AST1250_BGA  I11
  U9F4   U12  IV12D<9>  AST1250_BGA  I11
  U9F4   U13  IV12D<10>  AST1250_BGA  I11
  U9F4   Y18  MPLLDV12  AST1250_BGA  I11

P1V26_BMC_STBY_V1PLLAV12   @BASEBOARD_FAB2_LIB.BASEBOARD_FAB2(SCH_1):P1V26_BMC_STBY_V1PLLAV12
  C9F12    1      A  CAP_A       I106
  C9F14    1      A  CAP_A       I105
  C9F18    1      A  CAP         I104
  FB9F1    2      B  FERRITE     I107
  U9F4   W19  V1PLLAV12  AST1250_BGA  I11
  U9F4   Y20  V2PLLAV12  AST1250_BGA  I11

P1V538_BMC_STBY   @BASEBOARD_FAB2_LIB.BASEBOARD_FAB2(SCH_1):P1V538_BMC_STBY
  C1T15    1      A  CAP         I12
  C1T31    1      A  CAP_A       I92
  C1T32    1      A  CAP_A       I89
  C1T33    1      A  CAP_A       I80
  C1T35    1      A  CAP_A       I93
  C1T39    1      A  CAP_A       I64
  C1T40    1      A  CAP_A       I76
  C1T46    1      A  CAP_A       I91
  C1T49    1      A  CAP_A       I94
  C1T53    1      A  CAP_A       I82
  C1T54    1      A  CAP_A       I83
  C1T55    1      A  CAP_A       I90
  C1U10    1      A  CAP_A       I86
  C1U12    1      A  CAP         I88
  C1U13    1      A  CAP_A       I79
  C1U14    1      A  CAP_A       I84
  C1U15    1      A  CAP_A       I78
  C1U16    1      A  CAP_A       I81
  C9F3     1      A  CAP          I7
  C9F13    1      A  CAP          I7
  EU9F1    7  VIN<0>  RT9059_DFN  I40
  EU9F1    8  VIN<1>  RT9059_DFN  I40
  EU9F1    9  VIN<2>  RT9059_DFN  I40
  EU9F2    1  VOUT<0>  RT9059_DFN  I70
  EU9F2    2  VOUT<1>  RT9059_DFN  I70
  EU9F2    3  VOUT<2>  RT9059_DFN  I70
  R1T30    1      A  RES         I60
  R9F29    1      A  RES         I71
  R9F31    1      A  RES         I14
  U9F4   U10  MVDD<0>  AST1250_BGA  I11
  U9F4   U11  MVDD<1>  AST1250_BGA  I11
  U9F4   U14  MVDD<2>  AST1250_BGA  I11
  U9F4   U15  MVDD<3>  AST1250_BGA  I11
  U9F5    A1  VDDQ<0>  K4B1G16_BGA1   I1
  U9F5    A8  VDDQ<1>  K4B1G16_BGA1   I1
  U9F5    B2  VDD<0>  K4B1G16_BGA1   I1
  U9F5    C1  VDDQ<2>  K4B1G16_BGA1   I1
  U9F5    C9  VDDQ<3>  K4B1G16_BGA1   I1
  U9F5    D2  VDDQ<4>  K4B1G16_BGA1   I1
  U9F5    D9  VDD<1>  K4B1G16_BGA1   I1
  U9F5    E9  VDDQ<5>  K4B1G16_BGA1   I1
  U9F5    F1  VDDQ<6>  K4B1G16_BGA1   I1
  U9F5    G7  VDD<2>  K4B1G16_BGA1   I1
  U9F5    H2  VDDQ<7>  K4B1G16_BGA1   I1
  U9F5    H9  VDDQ<8>  K4B1G16_BGA1   I1
  U9F5    K2  VDD<3>  K4B1G16_BGA1   I1
  U9F5    K8  VDD<4>  K4B1G16_BGA1   I1
  U9F5    N1  VDD<5>  K4B1G16_BGA1   I1
  U9F5    N9  VDD<6>  K4B1G16_BGA1   I1
  U9F5    R1  VDD<7>  K4B1G16_BGA1   I1
  U9F5    R9  VDD<8>  K4B1G16_BGA1   I1

P1V5_LAN        @BASEBOARD_FAB2_LIB.BASEBOARD_FAB2(SCH_1):P1V5_LAN
  C1R17    1      A  CAP         I153
  C1R19    1      A  CAP_A       I151
  C1R26    1      A  CAP_A       I149
  C1R29    1      A  CAP_A       I150
  C1R30    1      A  CAP         I135
  C1R31    1      A  CAP_A       I152
  C9E6     1      A  CAP         I155
  EU9E1   39  VDD1P5_OUT  SPRINGVILLE_SM1  I72
  EU9E1   47  VDD1P5<1>  SPRINGVILLE_SM1  I72
  R1T32    1      A  RES         I238
  R1T33    1      A  RES         I240

P1V5_LAN_I210   @BASEBOARD_FAB2_LIB.BASEBOARD_FAB2(SCH_1):P1V5_LAN_I210
  EU9E1   56  VDD1P5<0>  SPRINGVILLE_SM1  I72
  R1T32    2      B  RES         I238

P1V8_BMC_STBY_PCIE   @BASEBOARD_FAB2_LIB.BASEBOARD_FAB2(SCH_1):P1V8_BMC_STBY_PCIE
  C1T16    1      A  CAP         I150
  C1T17    1      A  CAP_A       I151
  C1T18    1      A  CAP_A       I152
  FB1T1    2      B  FERRITE     I153
  U9F4   G20  GPIOY2_SIOPWREQ_N  AST1250_BGA  I11

P1V8_BMC_STBY_PCIEA   @BASEBOARD_FAB2_LIB.BASEBOARD_FAB2(SCH_1):P1V8_BMC_STBY_PCIEA
  C8F9     1      A  CAP_A       I161
  C8F10    1      A  CAP         I159
  C9F15    1      A  CAP_A       I160
  FB2T1    2      B  FERRITE     I163
  U9F4   C21  GPIOY0_SIOS3_N  AST1250_BGA  I11
  U9F4   F20  GPIOY1_SIOS5_N  AST1250_BGA  I11

P1V8_MCP_CPU0   @BASEBOARD_FAB2_LIB.BASEBOARD_FAB2(SCH_1):P1V8_MCP_CPU0
  C1M29    1      A  CAP_A       I147
  C3T1     1      A  CAP_A       I149
  C3T2     1      A  CAP_A       I150
  C4T1     1      A  CAP_A       I16
  C4T2     1      A  CAP_A        I9
  C6D1     1      A  CAP         I19
  J6E1    E1   IOE1  SCONN120_H61426002_SM  I55
  J6E1    E2   IOE2  SCONN120_H61426002_SM  I55
  J6E1    F1   IOF1  SCONN120_H61426002_SM  I55
  J6E1    F2   IOF2  SCONN120_H61426002_SM  I55
  J9B4     4    IO4  SCONN10_C12536004  I175
  R1M19    1      A  RES         I202
  R1M20    1      A  RES         I204
  R1M21    1      A  RES         I205
  R9B12    1      A  RES         I203
  U1M5     2      A  74CBTLV1G125  I196
  U4R1     2      A  74CBTLV1G125  I206
  U5D1   A14  RSVD<302>  SKX_EXT_B_BGA1  I204
  U5D1   A16  RSVD<301>  SKX_EXT_B_BGA1  I204
  U5D1   B13  RSVD<296>  SKX_EXT_B_BGA1  I204
  U5D1   B15  RSVD<295>  SKX_EXT_B_BGA1  I204
  U5D1   B17  RSVD<294>  SKX_EXT_B_BGA1  I204
  U5D1   BT27  CD_VCCIN<0>  SKX_EXT_B_BGA1  I34
  U5D1   BU26  CD_VCCIN<1>  SKX_EXT_B_BGA1  I34
  U5D1   BV27  CD_VCCIN<2>  SKX_EXT_B_BGA1  I34
  U5D1   BY27  CD_VCCIN<3>  SKX_EXT_B_BGA1  I34

P1V8_MCP_CPU1   @BASEBOARD_FAB2_LIB.BASEBOARD_FAB2(SCH_1):P1V8_MCP_CPU1
  C3D3     1      A  CAP         I25
  C3F1     1      A  CAP_A       I140
  C4F1     1      A  CAP_A       I68
  C4F2     1      A  CAP_A       I141
  C4F3     1      A  CAP_A       I70
  J4E1    E1   IOE1  SCONN120_H61426002_SM  I45
  J4E1    E2   IOE2  SCONN120_H61426002_SM  I45
  J4E1    F1   IOF1  SCONN120_H61426002_SM  I45
  J4E1    F2   IOF2  SCONN120_H61426002_SM  I45
  U2D1   A14  RSVD<302>  SKX_EXT_B_BGA1  I169
  U2D1   A16  RSVD<301>  SKX_EXT_B_BGA1  I169
  U2D1   B13  RSVD<296>  SKX_EXT_B_BGA1  I169
  U2D1   B15  RSVD<295>  SKX_EXT_B_BGA1  I169
  U2D1   B17  RSVD<294>  SKX_EXT_B_BGA1  I169
  U2D1   BT27  CD_VCCIN<0>  SKX_EXT_B_BGA1  I33
  U2D1   BU26  CD_VCCIN<1>  SKX_EXT_B_BGA1  I33
  U2D1   BV27  CD_VCCIN<2>  SKX_EXT_B_BGA1  I33
  U2D1   BY27  CD_VCCIN<3>  SKX_EXT_B_BGA1  I33
  U6M1     2      A  74CBTLV1G125  I190

P1V8_PCH_STBY   @BASEBOARD_FAB2_LIB.BASEBOARD_FAB2(SCH_1):P1V8_PCH_STBY
  C2L32    1      A  CAP         I79
  C2L45    1      A  CAP         I12
  C2M1     1      A  CAP_A       I43
  C2M2     1      A  CAP_A       I45
  C2N15    1      A  CAP_A       I47
  C2N16    1      A  CAP_A       I52
  C3N21    1      A  CAP_A       I49
  C3N22    1      A  CAP_A       I53
  C3N25    1      A  CAP_A       I50
  C7D3     1      A  CAP_A       I38
  C8A12    1      A  CAP         I77
  C8A14    1      A  CAP         I13
  C8B1     1      A  CAP_A       I41
  C8B2     1      A  CAP_A       I30
  C8B3     1      A  CAP_A       I32
  C8B4     1      A  CAP_A       I39
  EU8A2    1  VOUT<0>  RT9059_DFN  I86
  EU8A2    2  VOUT<1>  RT9059_DFN  I86
  EU8A2    3  VOUT<2>  RT9059_DFN  I86
  FB1T1    1      A  FERRITE     I153
  FB2T1    1      A  FERRITE     I163
  R2L20    1      A  RES         I81
  R8A12    1      A  RES         I15
  U7C1   AE26  VCCP_1P8<1>  LBG_CORE_QAT_EXT_D  I63
  U7C1   AG27  VCCPHDA_1P8  LBG_CORE_QAT_EXT_D  I63
  U7C1   AK24  VCCPGPP_1P8<6>  LBG_CORE_QAT_EXT_D  I63
  U7C1   AK29  VCCPSPI_1P8  LBG_CORE_QAT_EXT_D  I63
  U7C1   AM29  VCCPGPP_1P8<3>  LBG_CORE_QAT_EXT_D  I63
  U7C1   AP29  VCCPGPP_1P8<4>  LBG_CORE_QAT_EXT_D  I63
  U7C1   AT29  VCCPGPP_1P8<2>  LBG_CORE_QAT_EXT_D  I63
  U7C1   AU29  VCCPGPP_1P8<0>  LBG_CORE_QAT_EXT_D  I63
  U7C1   AW27  VCCPGPP_1P8<5>  LBG_CORE_QAT_EXT_D  I63
  U7C1   AW29  VCCPGPP_1P8<1>  LBG_CORE_QAT_EXT_D  I63
  U7C1   BA27  VCCP10GBE_HV_1P8<1>  LBG_CORE_QAT_EXT_D  I63
  U7C1   BA29  VCCP10GBE_HV_1P8<0>  LBG_CORE_QAT_EXT_D  I63
  U7C1   BD46  VCCP_1P8<0>  LBG_CORE_QAT_EXT_D  I63

P2E_SSB_BMC_RX_C_DN   @BASEBOARD_FAB2_LIB.BASEBOARD_FAB2(SCH_1):P2E_SSB_BMC_RX_C_DN
  C9F16    2      B  CAP_A       I202
  R3M9     1      A  RES         I234
  U7C1   AN70  PCIE4_GBE_RXN  LBG_CORE_QAT_EXT_D  I220

P2E_SSB_BMC_RX_C_DP   @BASEBOARD_FAB2_LIB.BASEBOARD_FAB2(SCH_1):P2E_SSB_BMC_RX_C_DP
  C9F17    2      B  CAP_A       I201
  R3M8     1      A  RES         I235
  U7C1   AN72  PCIE4_GBE_RXP  LBG_CORE_QAT_EXT_D  I220

P2E_SSB_BMC_RX_DN   @BASEBOARD_FAB2_LIB.BASEBOARD_FAB2(SCH_1):P2E_SSB_BMC_RX_DN
  C9F16    1      A  CAP_A       I202
  U9F4   E21  NC_PETXN  AST1250_BGA  I100

P2E_SSB_BMC_RX_DP   @BASEBOARD_FAB2_LIB.BASEBOARD_FAB2(SCH_1):P2E_SSB_BMC_RX_DP
  C9F17    1      A  CAP_A       I201
  U9F4   E22  NC_PETXP  AST1250_BGA  I100

P2E_SSB_BMC_TX_C_DN   @BASEBOARD_FAB2_LIB.BASEBOARD_FAB2(SCH_1):P2E_SSB_BMC_TX_C_DN
  C2M3     2      B  CAP_A       I183
  R9F43    1      A  RES         I216
  U9F4   F22  NC_PERXN  AST1250_BGA  I100

P2E_SSB_BMC_TX_C_DP   @BASEBOARD_FAB2_LIB.BASEBOARD_FAB2(SCH_1):P2E_SSB_BMC_TX_C_DP
  C2M4     2      B  CAP_A       I182
  R9F42    1      A  RES         I214
  U9F4   F21  NC_PERXP  AST1250_BGA  I100

P2E_SSB_BMC_TX_DN   @BASEBOARD_FAB2_LIB.BASEBOARD_FAB2(SCH_1):P2E_SSB_BMC_TX_DN
  C2M3     1      A  CAP_A       I183
  U7C1   BG66  PCIE4_GBE_TXN  LBG_CORE_QAT_EXT_D  I220

P2E_SSB_BMC_TX_DP   @BASEBOARD_FAB2_LIB.BASEBOARD_FAB2(SCH_1):P2E_SSB_BMC_TX_DP
  C2M4     1      A  CAP_A       I182
  U7C1   BJ66  PCIE4_GBE_TXP  LBG_CORE_QAT_EXT_D  I220

P3E_CPU0_PE1_PCH_C_TXN<8>   @BASEBOARD_FAB2_LIB.BASEBOARD_FAB2(SCH_1):P3E_CPU0_PE1_PCH_C_TXN<8>
  C6B19    2      B  CAP_0402    I160
  U7C1   A57  PCIEUP_8_RXP  LBG_CORE_QAT_EXT_D   I9

P3E_CPU0_PE1_PCH_C_TXN<9>   @BASEBOARD_FAB2_LIB.BASEBOARD_FAB2(SCH_1):P3E_CPU0_PE1_PCH_C_TXN<9>
  C6B17    2      B  CAP_0402    I175
  U7C1   B58  PCIEUP_9_RXP  LBG_CORE_QAT_EXT_D   I9

P3E_CPU0_PE1_PCH_C_TXN<10>   @BASEBOARD_FAB2_LIB.BASEBOARD_FAB2(SCH_1):P3E_CPU0_PE1_PCH_C_TXN<10>
  C6B15    2      B  CAP_0402    I163
  U7C1   A59  PCIEUP_10_RXP  LBG_CORE_QAT_EXT_D   I9

P3E_CPU0_PE1_PCH_C_TXN<11>   @BASEBOARD_FAB2_LIB.BASEBOARD_FAB2(SCH_1):P3E_CPU0_PE1_PCH_C_TXN<11>
  C6B14    2      B  CAP_0402    I181
  U7C1   D60  PCIEUP_11_RXN  LBG_CORE_QAT_EXT_D   I9

P3E_CPU0_PE1_PCH_C_TXN<12>   @BASEBOARD_FAB2_LIB.BASEBOARD_FAB2(SCH_1):P3E_CPU0_PE1_PCH_C_TXN<12>
  C6B11    2      B  CAP_0402    I166
  U7C1   A61  PCIEUP_12_RXP  LBG_CORE_QAT_EXT_D   I9

P3E_CPU0_PE1_PCH_C_TXN<13>   @BASEBOARD_FAB2_LIB.BASEBOARD_FAB2(SCH_1):P3E_CPU0_PE1_PCH_C_TXN<13>
  C6B9     2      B  CAP_0402    I185
  U7C1   B62  PCIEUP_13_RXP  LBG_CORE_QAT_EXT_D   I9

P3E_CPU0_PE1_PCH_C_TXN<14>   @BASEBOARD_FAB2_LIB.BASEBOARD_FAB2(SCH_1):P3E_CPU0_PE1_PCH_C_TXN<14>
  C6B6     2      B  CAP_0402    I169
  U7C1   A63  PCIEUP_14_RXP  LBG_CORE_QAT_EXT_D   I9

P3E_CPU0_PE1_PCH_C_TXN<15>   @BASEBOARD_FAB2_LIB.BASEBOARD_FAB2(SCH_1):P3E_CPU0_PE1_PCH_C_TXN<15>
  C6B4     2      B  CAP_0402    I196
  U7C1   B64  PCIEUP_15_RXP  LBG_CORE_QAT_EXT_D   I9

P3E_CPU0_PE1_PCH_C_TXP<8>   @BASEBOARD_FAB2_LIB.BASEBOARD_FAB2(SCH_1):P3E_CPU0_PE1_PCH_C_TXP<8>
  C6B20    2      B  CAP_0402    I173
  U7C1   C57  PCIEUP_8_RXN  LBG_CORE_QAT_EXT_D   I9

P3E_CPU0_PE1_PCH_C_TXP<9>   @BASEBOARD_FAB2_LIB.BASEBOARD_FAB2(SCH_1):P3E_CPU0_PE1_PCH_C_TXP<9>
  C6B18    2      B  CAP_0402    I153
  U7C1   D58  PCIEUP_9_RXN  LBG_CORE_QAT_EXT_D   I9

P3E_CPU0_PE1_PCH_C_TXP<10>   @BASEBOARD_FAB2_LIB.BASEBOARD_FAB2(SCH_1):P3E_CPU0_PE1_PCH_C_TXP<10>
  C6B16    2      B  CAP_0402    I180
  U7C1   C59  PCIEUP_10_RXN  LBG_CORE_QAT_EXT_D   I9

P3E_CPU0_PE1_PCH_C_TXP<11>   @BASEBOARD_FAB2_LIB.BASEBOARD_FAB2(SCH_1):P3E_CPU0_PE1_PCH_C_TXP<11>
  C6B13    2      B  CAP_0402    I189
  U7C1   B60  PCIEUP_11_RXP  LBG_CORE_QAT_EXT_D   I9

P3E_CPU0_PE1_PCH_C_TXP<12>   @BASEBOARD_FAB2_LIB.BASEBOARD_FAB2(SCH_1):P3E_CPU0_PE1_PCH_C_TXP<12>
  C6B12    2      B  CAP_0402    I187
  U7C1   C61  PCIEUP_12_RXN  LBG_CORE_QAT_EXT_D   I9

P3E_CPU0_PE1_PCH_C_TXP<13>   @BASEBOARD_FAB2_LIB.BASEBOARD_FAB2(SCH_1):P3E_CPU0_PE1_PCH_C_TXP<13>
  C6B10    2      B  CAP_0402    I193
  U7C1   D62  PCIEUP_13_RXN  LBG_CORE_QAT_EXT_D   I9

P3E_CPU0_PE1_PCH_C_TXP<14>   @BASEBOARD_FAB2_LIB.BASEBOARD_FAB2(SCH_1):P3E_CPU0_PE1_PCH_C_TXP<14>
  C6B8     2      B  CAP_0402    I198
  U7C1   C63  PCIEUP_14_RXN  LBG_CORE_QAT_EXT_D   I9

P3E_CPU0_PE1_PCH_C_TXP<15>   @BASEBOARD_FAB2_LIB.BASEBOARD_FAB2(SCH_1):P3E_CPU0_PE1_PCH_C_TXP<15>
  C6B5     2      B  CAP_0402    I201
  U7C1   D64  PCIEUP_15_RXN  LBG_CORE_QAT_EXT_D   I9

P3E_CPU0_PE1_PCH_RXN<0>   @BASEBOARD_FAB2_LIB.BASEBOARD_FAB2(SCH_1):P3E_CPU0_PE1_PCH_RXN<0>
  C2U4     1      A  CAP_0402    I257
  U7C1   J52  PCIEUP_0_TXN  LBG_CORE_QAT_EXT_D   I9

P3E_CPU0_PE1_PCH_RXN<1>   @BASEBOARD_FAB2_LIB.BASEBOARD_FAB2(SCH_1):P3E_CPU0_PE1_PCH_RXN<1>
  C2U6     1      A  CAP_0402    I260
  U7C1   P56  PCIEUP_1_TXN  LBG_CORE_QAT_EXT_D   I9

P3E_CPU0_PE1_PCH_RXN<2>   @BASEBOARD_FAB2_LIB.BASEBOARD_FAB2(SCH_1):P3E_CPU0_PE1_PCH_RXN<2>
  C2U8     1      A  CAP_0402    I264
  U7C1   H54  PCIEUP_2_TXN  LBG_CORE_QAT_EXT_D   I9

P3E_CPU0_PE1_PCH_RXN<3>   @BASEBOARD_FAB2_LIB.BASEBOARD_FAB2(SCH_1):P3E_CPU0_PE1_PCH_RXN<3>
  C2U10    1      A  CAP_0402    I267
  U7C1   J56  PCIEUP_3_TXN  LBG_CORE_QAT_EXT_D   I9

P3E_CPU0_PE1_PCH_RXN<4>   @BASEBOARD_FAB2_LIB.BASEBOARD_FAB2(SCH_1):P3E_CPU0_PE1_PCH_RXN<4>
  C2U12    1      A  CAP_0402    I265
  U7C1   N58  PCIEUP_4_TXN  LBG_CORE_QAT_EXT_D   I9

P3E_CPU0_PE1_PCH_RXN<5>   @BASEBOARD_FAB2_LIB.BASEBOARD_FAB2(SCH_1):P3E_CPU0_PE1_PCH_RXN<5>
  C2U14    1      A  CAP_0402    I287
  U7C1   N61  PCIEUP_5_TXN  LBG_CORE_QAT_EXT_D   I9

P3E_CPU0_PE1_PCH_RXN<6>   @BASEBOARD_FAB2_LIB.BASEBOARD_FAB2(SCH_1):P3E_CPU0_PE1_PCH_RXN<6>
  C2U16    1      A  CAP_0402    I286
  U7C1   H61  PCIEUP_6_TXN  LBG_CORE_QAT_EXT_D   I9

P3E_CPU0_PE1_PCH_RXN<7>   @BASEBOARD_FAB2_LIB.BASEBOARD_FAB2(SCH_1):P3E_CPU0_PE1_PCH_RXN<7>
  C2U18    1      A  CAP_0402    I294
  U7C1   P59  PCIEUP_7_TXN  LBG_CORE_QAT_EXT_D   I9

P3E_CPU0_PE1_PCH_RXN<8>   @BASEBOARD_FAB2_LIB.BASEBOARD_FAB2(SCH_1):P3E_CPU0_PE1_PCH_RXN<8>
  C3M33    2      B  CAP_0402    I217
  U5D1   DM11  PE1_RX_DN<8>  SKX_EXT_B_BGA1  I84

P3E_CPU0_PE1_PCH_RXN<9>   @BASEBOARD_FAB2_LIB.BASEBOARD_FAB2(SCH_1):P3E_CPU0_PE1_PCH_RXN<9>
  C3M35    2      B  CAP_0402    I225
  U5D1   DP11  PE1_RX_DN<9>  SKX_EXT_B_BGA1  I84

P3E_CPU0_PE1_PCH_RXN<10>   @BASEBOARD_FAB2_LIB.BASEBOARD_FAB2(SCH_1):P3E_CPU0_PE1_PCH_RXN<10>
  C3M32    2      B  CAP_0402    I223
  U5D1   DT11  PE1_RX_DN<10>  SKX_EXT_B_BGA1  I84

P3E_CPU0_PE1_PCH_RXN<11>   @BASEBOARD_FAB2_LIB.BASEBOARD_FAB2(SCH_1):P3E_CPU0_PE1_PCH_RXN<11>
  C3M26    2      B  CAP_0402    I229
  U5D1   DT13  PE1_RX_DN<11>  SKX_EXT_B_BGA1  I84

P3E_CPU0_PE1_PCH_RXN<12>   @BASEBOARD_FAB2_LIB.BASEBOARD_FAB2(SCH_1):P3E_CPU0_PE1_PCH_RXN<12>
  C3M4     2      B  CAP_0402    I244
  U5D1   DV13  PE1_RX_DN<12>  SKX_EXT_B_BGA1  I84

P3E_CPU0_PE1_PCH_RXN<13>   @BASEBOARD_FAB2_LIB.BASEBOARD_FAB2(SCH_1):P3E_CPU0_PE1_PCH_RXN<13>
  C3M14    2      B  CAP_0402    I253
  U5D1   DW14  PE1_RX_DN<13>  SKX_EXT_B_BGA1  I84

P3E_CPU0_PE1_PCH_RXN<14>   @BASEBOARD_FAB2_LIB.BASEBOARD_FAB2(SCH_1):P3E_CPU0_PE1_PCH_RXN<14>
  C3M12    2      B  CAP_0402    I246
  U5D1   DY15  PE1_RX_DN<14>  SKX_EXT_B_BGA1  I84

P3E_CPU0_PE1_PCH_RXN<15>   @BASEBOARD_FAB2_LIB.BASEBOARD_FAB2(SCH_1):P3E_CPU0_PE1_PCH_RXN<15>
  C3M1     2      B  CAP_0402    I255
  U5D1   DU16  PE1_RX_DN<15>  SKX_EXT_B_BGA1  I84

P3E_CPU0_PE1_PCH_RXP<0>   @BASEBOARD_FAB2_LIB.BASEBOARD_FAB2(SCH_1):P3E_CPU0_PE1_PCH_RXP<0>
  C2U3     1      A  CAP_0402    I272
  U7C1   G52  PCIEUP_0_TXP  LBG_CORE_QAT_EXT_D   I9

P3E_CPU0_PE1_PCH_RXP<1>   @BASEBOARD_FAB2_LIB.BASEBOARD_FAB2(SCH_1):P3E_CPU0_PE1_PCH_RXP<1>
  C2U5     1      A  CAP_0402    I274
  U7C1   M56  PCIEUP_1_TXP  LBG_CORE_QAT_EXT_D   I9

P3E_CPU0_PE1_PCH_RXP<2>   @BASEBOARD_FAB2_LIB.BASEBOARD_FAB2(SCH_1):P3E_CPU0_PE1_PCH_RXP<2>
  C2U7     1      A  CAP_0402    I277
  U7C1   G56  PCIEUP_2_TXP  LBG_CORE_QAT_EXT_D   I9

P3E_CPU0_PE1_PCH_RXP<3>   @BASEBOARD_FAB2_LIB.BASEBOARD_FAB2(SCH_1):P3E_CPU0_PE1_PCH_RXP<3>
  C2U9     1      A  CAP_0402    I279
  U7C1   K58  PCIEUP_3_TXP  LBG_CORE_QAT_EXT_D   I9

P3E_CPU0_PE1_PCH_RXP<4>   @BASEBOARD_FAB2_LIB.BASEBOARD_FAB2(SCH_1):P3E_CPU0_PE1_PCH_RXP<4>
  C2U11    1      A  CAP_0402    I278
  U7C1   M59  PCIEUP_4_TXP  LBG_CORE_QAT_EXT_D   I9

P3E_CPU0_PE1_PCH_RXP<5>   @BASEBOARD_FAB2_LIB.BASEBOARD_FAB2(SCH_1):P3E_CPU0_PE1_PCH_RXP<5>
  C2U13    1      A  CAP_0402    I297
  U7C1   K61  PCIEUP_5_TXP  LBG_CORE_QAT_EXT_D   I9

P3E_CPU0_PE1_PCH_RXP<6>   @BASEBOARD_FAB2_LIB.BASEBOARD_FAB2(SCH_1):P3E_CPU0_PE1_PCH_RXP<6>
  C2U15    1      A  CAP_0402    I296
  U7C1   J63  PCIEUP_6_TXP  LBG_CORE_QAT_EXT_D   I9

P3E_CPU0_PE1_PCH_RXP<7>   @BASEBOARD_FAB2_LIB.BASEBOARD_FAB2(SCH_1):P3E_CPU0_PE1_PCH_RXP<7>
  C2U17    1      A  CAP_0402    I300
  U7C1   R61  PCIEUP_7_TXP  LBG_CORE_QAT_EXT_D   I9

P3E_CPU0_PE1_PCH_RXP<8>   @BASEBOARD_FAB2_LIB.BASEBOARD_FAB2(SCH_1):P3E_CPU0_PE1_PCH_RXP<8>
  C3M34    2      B  CAP_0402    I206
  U5D1   DK11  PE1_RX_DP<8>  SKX_EXT_B_BGA1  I84

P3E_CPU0_PE1_PCH_RXP<9>   @BASEBOARD_FAB2_LIB.BASEBOARD_FAB2(SCH_1):P3E_CPU0_PE1_PCH_RXP<9>
  C3M36    2      B  CAP_0402    I218
  U5D1   DN10  PE1_RX_DP<9>  SKX_EXT_B_BGA1  I84

P3E_CPU0_PE1_PCH_RXP<10>   @BASEBOARD_FAB2_LIB.BASEBOARD_FAB2(SCH_1):P3E_CPU0_PE1_PCH_RXP<10>
  C3M28    2      B  CAP_0402    I212
  U5D1   DR12  PE1_RX_DP<10>  SKX_EXT_B_BGA1  I84

P3E_CPU0_PE1_PCH_RXP<11>   @BASEBOARD_FAB2_LIB.BASEBOARD_FAB2(SCH_1):P3E_CPU0_PE1_PCH_RXP<11>
  C3M25    2      B  CAP_0402    I205
  U5D1   DP13  PE1_RX_DP<11>  SKX_EXT_B_BGA1  I84

P3E_CPU0_PE1_PCH_RXP<12>   @BASEBOARD_FAB2_LIB.BASEBOARD_FAB2(SCH_1):P3E_CPU0_PE1_PCH_RXP<12>
  C3M3     2      B  CAP_0402    I232
  U5D1   DU12  PE1_RX_DP<12>  SKX_EXT_B_BGA1  I84

P3E_CPU0_PE1_PCH_RXP<13>   @BASEBOARD_FAB2_LIB.BASEBOARD_FAB2(SCH_1):P3E_CPU0_PE1_PCH_RXP<13>
  C3M13    2      B  CAP_0402    I239
  U5D1   DY13  PE1_RX_DP<13>  SKX_EXT_B_BGA1  I84

P3E_CPU0_PE1_PCH_RXP<14>   @BASEBOARD_FAB2_LIB.BASEBOARD_FAB2(SCH_1):P3E_CPU0_PE1_PCH_RXP<14>
  C3M11    2      B  CAP_0402    I234
  U5D1   DV15  PE1_RX_DP<14>  SKX_EXT_B_BGA1  I84

P3E_CPU0_PE1_PCH_RXP<15>   @BASEBOARD_FAB2_LIB.BASEBOARD_FAB2(SCH_1):P3E_CPU0_PE1_PCH_RXP<15>
  C3M2     2      B  CAP_0402    I247
  U5D1   DT15  PE1_RX_DP<15>  SKX_EXT_B_BGA1  I84

P3E_CPU0_PE1_PCH_R_RXN<8>   @BASEBOARD_FAB2_LIB.BASEBOARD_FAB2(SCH_1):P3E_CPU0_PE1_PCH_R_RXN<8>
  C3M33    1      A  CAP_0402    I217
  U7C1   K65  PCIEUP_8_TXN  LBG_CORE_QAT_EXT_D   I9

P3E_CPU0_PE1_PCH_R_RXN<9>   @BASEBOARD_FAB2_LIB.BASEBOARD_FAB2(SCH_1):P3E_CPU0_PE1_PCH_R_RXN<9>
  C3M35    1      A  CAP_0402    I225
  U7C1   J66  PCIEUP_9_TXN  LBG_CORE_QAT_EXT_D   I9

P3E_CPU0_PE1_PCH_R_RXN<10>   @BASEBOARD_FAB2_LIB.BASEBOARD_FAB2(SCH_1):P3E_CPU0_PE1_PCH_R_RXN<10>
  C3M32    1      A  CAP_0402    I223
  U7C1   N65  PCIEUP_10_TXN  LBG_CORE_QAT_EXT_D   I9

P3E_CPU0_PE1_PCH_R_RXN<11>   @BASEBOARD_FAB2_LIB.BASEBOARD_FAB2(SCH_1):P3E_CPU0_PE1_PCH_R_RXN<11>
  C3M26    1      A  CAP_0402    I229
  U7C1   T59  PCIEUP_11_TXN  LBG_CORE_QAT_EXT_D   I9

P3E_CPU0_PE1_PCH_R_RXN<12>   @BASEBOARD_FAB2_LIB.BASEBOARD_FAB2(SCH_1):P3E_CPU0_PE1_PCH_R_RXN<12>
  C3M4     1      A  CAP_0402    I244
  U7C1   R65  PCIEUP_12_TXN  LBG_CORE_QAT_EXT_D   I9

P3E_CPU0_PE1_PCH_R_RXN<13>   @BASEBOARD_FAB2_LIB.BASEBOARD_FAB2(SCH_1):P3E_CPU0_PE1_PCH_R_RXN<13>
  C3M14    1      A  CAP_0402    I253
  U7C1   T63  PCIEUP_13_TXN  LBG_CORE_QAT_EXT_D   I9

P3E_CPU0_PE1_PCH_R_RXN<14>   @BASEBOARD_FAB2_LIB.BASEBOARD_FAB2(SCH_1):P3E_CPU0_PE1_PCH_R_RXN<14>
  C3M12    1      A  CAP_0402    I246
  U7C1   W65  PCIEUP_14_TXN  LBG_CORE_QAT_EXT_D   I9

P3E_CPU0_PE1_PCH_R_RXN<15>   @BASEBOARD_FAB2_LIB.BASEBOARD_FAB2(SCH_1):P3E_CPU0_PE1_PCH_R_RXN<15>
  C3M1     1      A  CAP_0402    I255
  U7C1   Y66  PCIEUP_15_TXN  LBG_CORE_QAT_EXT_D   I9

P3E_CPU0_PE1_PCH_R_RXP<8>   @BASEBOARD_FAB2_LIB.BASEBOARD_FAB2(SCH_1):P3E_CPU0_PE1_PCH_R_RXP<8>
  C3M34    1      A  CAP_0402    I206
  U7C1   M63  PCIEUP_8_TXP  LBG_CORE_QAT_EXT_D   I9

P3E_CPU0_PE1_PCH_R_RXP<9>   @BASEBOARD_FAB2_LIB.BASEBOARD_FAB2(SCH_1):P3E_CPU0_PE1_PCH_R_RXP<9>
  C3M36    1      A  CAP_0402    I218
  U7C1   M66  PCIEUP_9_TXP  LBG_CORE_QAT_EXT_D   I9

P3E_CPU0_PE1_PCH_R_RXP<10>   @BASEBOARD_FAB2_LIB.BASEBOARD_FAB2(SCH_1):P3E_CPU0_PE1_PCH_R_RXP<10>
  C3M28    1      A  CAP_0402    I212
  U7C1   P66  PCIEUP_10_TXP  LBG_CORE_QAT_EXT_D   I9

P3E_CPU0_PE1_PCH_R_RXP<11>   @BASEBOARD_FAB2_LIB.BASEBOARD_FAB2(SCH_1):P3E_CPU0_PE1_PCH_R_RXP<11>
  C3M25    1      A  CAP_0402    I205
  U7C1   V59  PCIEUP_11_TXP  LBG_CORE_QAT_EXT_D   I9

P3E_CPU0_PE1_PCH_R_RXP<12>   @BASEBOARD_FAB2_LIB.BASEBOARD_FAB2(SCH_1):P3E_CPU0_PE1_PCH_R_RXP<12>
  C3M3     1      A  CAP_0402    I232
  U7C1   U65  PCIEUP_12_TXP  LBG_CORE_QAT_EXT_D   I9

P3E_CPU0_PE1_PCH_R_RXP<13>   @BASEBOARD_FAB2_LIB.BASEBOARD_FAB2(SCH_1):P3E_CPU0_PE1_PCH_R_RXP<13>
  C3M13    1      A  CAP_0402    I239
  U7C1   U61  PCIEUP_13_TXP  LBG_CORE_QAT_EXT_D   I9

P3E_CPU0_PE1_PCH_R_RXP<14>   @BASEBOARD_FAB2_LIB.BASEBOARD_FAB2(SCH_1):P3E_CPU0_PE1_PCH_R_RXP<14>
  C3M11    1      A  CAP_0402    I234
  U7C1   V63  PCIEUP_14_TXP  LBG_CORE_QAT_EXT_D   I9

P3E_CPU0_PE1_PCH_R_RXP<15>   @BASEBOARD_FAB2_LIB.BASEBOARD_FAB2(SCH_1):P3E_CPU0_PE1_PCH_R_RXP<15>
  C3M2     1      A  CAP_0402    I247
  U7C1   AA65  PCIEUP_15_TXP  LBG_CORE_QAT_EXT_D   I9

P3E_CPU0_PE1_PCH_TXN<0>   @BASEBOARD_FAB2_LIB.BASEBOARD_FAB2(SCH_1):P3E_CPU0_PE1_PCH_TXN<0>
  C3P13    2      B  CAP_0402    I207
  U7C1   C48  PCIEUP_0_RXN  LBG_CORE_QAT_EXT_D   I9

P3E_CPU0_PE1_PCH_TXN<1>   @BASEBOARD_FAB2_LIB.BASEBOARD_FAB2(SCH_1):P3E_CPU0_PE1_PCH_TXN<1>
  C3P17    2      B  CAP_0402    I208
  U7C1   D49  PCIEUP_1_RXN  LBG_CORE_QAT_EXT_D   I9

P3E_CPU0_PE1_PCH_TXN<2>   @BASEBOARD_FAB2_LIB.BASEBOARD_FAB2(SCH_1):P3E_CPU0_PE1_PCH_TXN<2>
  C3P20    2      B  CAP_0402    I215
  U7C1   C50  PCIEUP_2_RXN  LBG_CORE_QAT_EXT_D   I9

P3E_CPU0_PE1_PCH_TXN<3>   @BASEBOARD_FAB2_LIB.BASEBOARD_FAB2(SCH_1):P3E_CPU0_PE1_PCH_TXN<3>
  C3P25    2      B  CAP_0402    I216
  U7C1   D51  PCIEUP_3_RXN  LBG_CORE_QAT_EXT_D   I9

P3E_CPU0_PE1_PCH_TXN<4>   @BASEBOARD_FAB2_LIB.BASEBOARD_FAB2(SCH_1):P3E_CPU0_PE1_PCH_TXN<4>
  C3P28    2      B  CAP_0402    I232
  U7C1   C52  PCIEUP_4_RXN  LBG_CORE_QAT_EXT_D   I9

P3E_CPU0_PE1_PCH_TXN<5>   @BASEBOARD_FAB2_LIB.BASEBOARD_FAB2(SCH_1):P3E_CPU0_PE1_PCH_TXN<5>
  C3P32    2      B  CAP_0402    I234
  U7C1   D53  PCIEUP_5_RXN  LBG_CORE_QAT_EXT_D   I9

P3E_CPU0_PE1_PCH_TXN<6>   @BASEBOARD_FAB2_LIB.BASEBOARD_FAB2(SCH_1):P3E_CPU0_PE1_PCH_TXN<6>
  C3P37    2      B  CAP_0402    I235
  U7C1   C54  PCIEUP_6_RXN  LBG_CORE_QAT_EXT_D   I9

P3E_CPU0_PE1_PCH_TXN<7>   @BASEBOARD_FAB2_LIB.BASEBOARD_FAB2(SCH_1):P3E_CPU0_PE1_PCH_TXN<7>
  C3P40    2      B  CAP_0402    I241
  U7C1   D55  PCIEUP_7_RXN  LBG_CORE_QAT_EXT_D   I9

P3E_CPU0_PE1_PCH_TXN<8>   @BASEBOARD_FAB2_LIB.BASEBOARD_FAB2(SCH_1):P3E_CPU0_PE1_PCH_TXN<8>
  C6B19    1      A  CAP_0402    I160
  U5D1   DT5  PE1_TX_DN<8>  SKX_EXT_B_BGA1  I84

P3E_CPU0_PE1_PCH_TXN<9>   @BASEBOARD_FAB2_LIB.BASEBOARD_FAB2(SCH_1):P3E_CPU0_PE1_PCH_TXN<9>
  C6B17    1      A  CAP_0402    I175
  U5D1   DV3  PE1_TX_DN<9>  SKX_EXT_B_BGA1  I84

P3E_CPU0_PE1_PCH_TXN<10>   @BASEBOARD_FAB2_LIB.BASEBOARD_FAB2(SCH_1):P3E_CPU0_PE1_PCH_TXN<10>
  C6B15    1      A  CAP_0402    I163
  U5D1   DW4  PE1_TX_DN<10>  SKX_EXT_B_BGA1  I84

P3E_CPU0_PE1_PCH_TXN<11>   @BASEBOARD_FAB2_LIB.BASEBOARD_FAB2(SCH_1):P3E_CPU0_PE1_PCH_TXN<11>
  C6B14    1      A  CAP_0402    I181
  U5D1   DU6  PE1_TX_DN<11>  SKX_EXT_B_BGA1  I84

P3E_CPU0_PE1_PCH_TXN<12>   @BASEBOARD_FAB2_LIB.BASEBOARD_FAB2(SCH_1):P3E_CPU0_PE1_PCH_TXN<12>
  C6B11    1      A  CAP_0402    I166
  U5D1   DV7  PE1_TX_DN<12>  SKX_EXT_B_BGA1  I84

P3E_CPU0_PE1_PCH_TXN<13>   @BASEBOARD_FAB2_LIB.BASEBOARD_FAB2(SCH_1):P3E_CPU0_PE1_PCH_TXN<13>
  C6B9     1      A  CAP_0402    I185
  U5D1   DY7  PE1_TX_DN<13>  SKX_EXT_B_BGA1  I84

P3E_CPU0_PE1_PCH_TXN<14>   @BASEBOARD_FAB2_LIB.BASEBOARD_FAB2(SCH_1):P3E_CPU0_PE1_PCH_TXN<14>
  C6B6     1      A  CAP_0402    I169
  U5D1   EA8  PE1_TX_DN<14>  SKX_EXT_B_BGA1  I84

P3E_CPU0_PE1_PCH_TXN<15>   @BASEBOARD_FAB2_LIB.BASEBOARD_FAB2(SCH_1):P3E_CPU0_PE1_PCH_TXN<15>
  C6B4     1      A  CAP_0402    I196
  U5D1   ED9  PE1_TX_DN<15>  SKX_EXT_B_BGA1  I84

P3E_CPU0_PE1_PCH_TXP<0>   @BASEBOARD_FAB2_LIB.BASEBOARD_FAB2(SCH_1):P3E_CPU0_PE1_PCH_TXP<0>
  C3P11    2      B  CAP_0402    I212
  U7C1   A48  PCIEUP_0_RXP  LBG_CORE_QAT_EXT_D   I9

P3E_CPU0_PE1_PCH_TXP<1>   @BASEBOARD_FAB2_LIB.BASEBOARD_FAB2(SCH_1):P3E_CPU0_PE1_PCH_TXP<1>
  C3P15    2      B  CAP_0402    I226
  U7C1   B49  PCIEUP_1_RXP  LBG_CORE_QAT_EXT_D   I9

P3E_CPU0_PE1_PCH_TXP<2>   @BASEBOARD_FAB2_LIB.BASEBOARD_FAB2(SCH_1):P3E_CPU0_PE1_PCH_TXP<2>
  C3P18    2      B  CAP_0402    I219
  U7C1   A50  PCIEUP_2_RXP  LBG_CORE_QAT_EXT_D   I9

P3E_CPU0_PE1_PCH_TXP<3>   @BASEBOARD_FAB2_LIB.BASEBOARD_FAB2(SCH_1):P3E_CPU0_PE1_PCH_TXP<3>
  C3P23    2      B  CAP_0402    I229
  U7C1   B51  PCIEUP_3_RXP  LBG_CORE_QAT_EXT_D   I9

P3E_CPU0_PE1_PCH_TXP<4>   @BASEBOARD_FAB2_LIB.BASEBOARD_FAB2(SCH_1):P3E_CPU0_PE1_PCH_TXP<4>
  C3P27    2      B  CAP_0402    I223
  U7C1   A52  PCIEUP_4_RXP  LBG_CORE_QAT_EXT_D   I9

P3E_CPU0_PE1_PCH_TXP<5>   @BASEBOARD_FAB2_LIB.BASEBOARD_FAB2(SCH_1):P3E_CPU0_PE1_PCH_TXP<5>
  C3P30    2      B  CAP_0402    I245
  U7C1   B53  PCIEUP_5_RXP  LBG_CORE_QAT_EXT_D   I9

P3E_CPU0_PE1_PCH_TXP<6>   @BASEBOARD_FAB2_LIB.BASEBOARD_FAB2(SCH_1):P3E_CPU0_PE1_PCH_TXP<6>
  C3P35    2      B  CAP_0402    I240
  U7C1   A54  PCIEUP_6_RXP  LBG_CORE_QAT_EXT_D   I9

P3E_CPU0_PE1_PCH_TXP<7>   @BASEBOARD_FAB2_LIB.BASEBOARD_FAB2(SCH_1):P3E_CPU0_PE1_PCH_TXP<7>
  C3P39    2      B  CAP_0402    I248
  U7C1   B55  PCIEUP_7_RXP  LBG_CORE_QAT_EXT_D   I9

P3E_CPU0_PE1_PCH_TXP<8>   @BASEBOARD_FAB2_LIB.BASEBOARD_FAB2(SCH_1):P3E_CPU0_PE1_PCH_TXP<8>
  C6B20    1      A  CAP_0402    I173
  U5D1   DR4  PE1_TX_DP<8>  SKX_EXT_B_BGA1  I84

P3E_CPU0_PE1_PCH_TXP<9>   @BASEBOARD_FAB2_LIB.BASEBOARD_FAB2(SCH_1):P3E_CPU0_PE1_PCH_TXP<9>
  C6B18    1      A  CAP_0402    I153
  U5D1   DU2  PE1_TX_DP<9>  SKX_EXT_B_BGA1  I84

P3E_CPU0_PE1_PCH_TXP<10>   @BASEBOARD_FAB2_LIB.BASEBOARD_FAB2(SCH_1):P3E_CPU0_PE1_PCH_TXP<10>
  C6B16    1      A  CAP_0402    I180
  U5D1   DU4  PE1_TX_DP<10>  SKX_EXT_B_BGA1  I84

P3E_CPU0_PE1_PCH_TXP<11>   @BASEBOARD_FAB2_LIB.BASEBOARD_FAB2(SCH_1):P3E_CPU0_PE1_PCH_TXP<11>
  C6B13    1      A  CAP_0402    I189
  U5D1   DV5  PE1_TX_DP<11>  SKX_EXT_B_BGA1  I84

P3E_CPU0_PE1_PCH_TXP<12>   @BASEBOARD_FAB2_LIB.BASEBOARD_FAB2(SCH_1):P3E_CPU0_PE1_PCH_TXP<12>
  C6B12    1      A  CAP_0402    I187
  U5D1   DT7  PE1_TX_DP<12>  SKX_EXT_B_BGA1  I84

P3E_CPU0_PE1_PCH_TXP<13>   @BASEBOARD_FAB2_LIB.BASEBOARD_FAB2(SCH_1):P3E_CPU0_PE1_PCH_TXP<13>
  C6B10    1      A  CAP_0402    I193
  U5D1   DW6  PE1_TX_DP<13>  SKX_EXT_B_BGA1  I84

P3E_CPU0_PE1_PCH_TXP<14>   @BASEBOARD_FAB2_LIB.BASEBOARD_FAB2(SCH_1):P3E_CPU0_PE1_PCH_TXP<14>
  C6B8     1      A  CAP_0402    I198
  U5D1   EB7  PE1_TX_DP<14>  SKX_EXT_B_BGA1  I84

P3E_CPU0_PE1_PCH_TXP<15>   @BASEBOARD_FAB2_LIB.BASEBOARD_FAB2(SCH_1):P3E_CPU0_PE1_PCH_TXP<15>
  C6B5     1      A  CAP_0402    I201
  U5D1   EC8  PE1_TX_DP<15>  SKX_EXT_B_BGA1  I84

P3E_CPU0_PE1_SS_C_TXN<0>   @BASEBOARD_FAB2_LIB.BASEBOARD_FAB2(SCH_1):P3E_CPU0_PE1_SS_C_TXN<0>
  C3P12    2      B  CAP_0402    I415
  J8G1    53   IO53  SCONN200_H68296001_SM  I258

P3E_CPU0_PE1_SS_C_TXN<1>   @BASEBOARD_FAB2_LIB.BASEBOARD_FAB2(SCH_1):P3E_CPU0_PE1_SS_C_TXN<1>
  C3P16    2      B  CAP_0402    I422
  J8G1    59   IO59  SCONN200_H68296001_SM  I258

P3E_CPU0_PE1_SS_C_TXN<2>   @BASEBOARD_FAB2_LIB.BASEBOARD_FAB2(SCH_1):P3E_CPU0_PE1_SS_C_TXN<2>
  C3P21    2      B  CAP_0402    I423
  J8G1    69   IO69  SCONN200_H68296001_SM  I258

P3E_CPU0_PE1_SS_C_TXN<3>   @BASEBOARD_FAB2_LIB.BASEBOARD_FAB2(SCH_1):P3E_CPU0_PE1_SS_C_TXN<3>
  C3P24    2      B  CAP_0402    I424
  J8G1    75   IO75  SCONN200_H68296001_SM  I258

P3E_CPU0_PE1_SS_C_TXN<4>   @BASEBOARD_FAB2_LIB.BASEBOARD_FAB2(SCH_1):P3E_CPU0_PE1_SS_C_TXN<4>
  C3P29    2      B  CAP_0402    I437
  J8G1    81   IO81  SCONN200_H68296001_SM  I258

P3E_CPU0_PE1_SS_C_TXN<5>   @BASEBOARD_FAB2_LIB.BASEBOARD_FAB2(SCH_1):P3E_CPU0_PE1_SS_C_TXN<5>
  C3P33    2      B  CAP_0402    I439
  J8G1    87   IO87  SCONN200_H68296001_SM  I258

P3E_CPU0_PE1_SS_C_TXN<6>   @BASEBOARD_FAB2_LIB.BASEBOARD_FAB2(SCH_1):P3E_CPU0_PE1_SS_C_TXN<6>
  C3P36    2      B  CAP_0402    I438
  J8G1    93   IO93  SCONN200_H68296001_SM  I258

P3E_CPU0_PE1_SS_C_TXN<7>   @BASEBOARD_FAB2_LIB.BASEBOARD_FAB2(SCH_1):P3E_CPU0_PE1_SS_C_TXN<7>
  C3P41    2      B  CAP_0402    I448
  J8G1    99   IO99  SCONN200_H68296001_SM  I258

P3E_CPU0_PE1_SS_C_TXP<0>   @BASEBOARD_FAB2_LIB.BASEBOARD_FAB2(SCH_1):P3E_CPU0_PE1_SS_C_TXP<0>
  C3P10    2      B  CAP_0402    I417
  J8G1    51   IO51  SCONN200_H68296001_SM  I258

P3E_CPU0_PE1_SS_C_TXP<1>   @BASEBOARD_FAB2_LIB.BASEBOARD_FAB2(SCH_1):P3E_CPU0_PE1_SS_C_TXP<1>
  C3P14    2      B  CAP_0402    I431
  J8G1    57   IO57  SCONN200_H68296001_SM  I258

P3E_CPU0_PE1_SS_C_TXP<2>   @BASEBOARD_FAB2_LIB.BASEBOARD_FAB2(SCH_1):P3E_CPU0_PE1_SS_C_TXP<2>
  C3P19    2      B  CAP_0402    I427
  J8G1    67   IO67  SCONN200_H68296001_SM  I258

P3E_CPU0_PE1_SS_C_TXP<3>   @BASEBOARD_FAB2_LIB.BASEBOARD_FAB2(SCH_1):P3E_CPU0_PE1_SS_C_TXP<3>
  C3P22    2      B  CAP_0402    I435
  J8G1    73   IO73  SCONN200_H68296001_SM  I258

P3E_CPU0_PE1_SS_C_TXP<4>   @BASEBOARD_FAB2_LIB.BASEBOARD_FAB2(SCH_1):P3E_CPU0_PE1_SS_C_TXP<4>
  C3P26    2      B  CAP_0402    I444
  J8G1    79   IO79  SCONN200_H68296001_SM  I258

P3E_CPU0_PE1_SS_C_TXP<5>   @BASEBOARD_FAB2_LIB.BASEBOARD_FAB2(SCH_1):P3E_CPU0_PE1_SS_C_TXP<5>
  C3P31    2      B  CAP_0402    I452
  J8G1    85   IO85  SCONN200_H68296001_SM  I258

P3E_CPU0_PE1_SS_C_TXP<6>   @BASEBOARD_FAB2_LIB.BASEBOARD_FAB2(SCH_1):P3E_CPU0_PE1_SS_C_TXP<6>
  C3P34    2      B  CAP_0402    I447
  J8G1    91   IO91  SCONN200_H68296001_SM  I258

P3E_CPU0_PE1_SS_C_TXP<7>   @BASEBOARD_FAB2_LIB.BASEBOARD_FAB2(SCH_1):P3E_CPU0_PE1_SS_C_TXP<7>
  C3P38    2      B  CAP_0402    I455
  J8G1    97   IO97  SCONN200_H68296001_SM  I258

P3E_CPU0_PE1_SS_RXN<0>   @BASEBOARD_FAB2_LIB.BASEBOARD_FAB2(SCH_1):P3E_CPU0_PE1_SS_RXN<0>
  C2U4     2      B  CAP_0402    I257
  R2U15    2      B  RES         I465
  U5D1   CW8  PE1_RX_DN<0>  SKX_EXT_B_BGA1  I84

P3E_CPU0_PE1_SS_RXN<1>   @BASEBOARD_FAB2_LIB.BASEBOARD_FAB2(SCH_1):P3E_CPU0_PE1_SS_RXN<1>
  C2U6     2      B  CAP_0402    I260
  R2U17    2      B  RES         I464
  U5D1   DA8  PE1_RX_DN<1>  SKX_EXT_B_BGA1  I84

P3E_CPU0_PE1_SS_RXN<2>   @BASEBOARD_FAB2_LIB.BASEBOARD_FAB2(SCH_1):P3E_CPU0_PE1_SS_RXN<2>
  C2U8     2      B  CAP_0402    I264
  R2U19    2      B  RES         I463
  U5D1   DC8  PE1_RX_DN<2>  SKX_EXT_B_BGA1  I84

P3E_CPU0_PE1_SS_RXN<3>   @BASEBOARD_FAB2_LIB.BASEBOARD_FAB2(SCH_1):P3E_CPU0_PE1_SS_RXN<3>
  C2U10    2      B  CAP_0402    I267
  R2U21    2      B  RES         I462
  U5D1   DC10  PE1_RX_DN<3>  SKX_EXT_B_BGA1  I84

P3E_CPU0_PE1_SS_RXN<4>   @BASEBOARD_FAB2_LIB.BASEBOARD_FAB2(SCH_1):P3E_CPU0_PE1_SS_RXN<4>
  C2U12    2      B  CAP_0402    I265
  R2U23    2      B  RES         I461
  U5D1   DE10  PE1_RX_DN<4>  SKX_EXT_B_BGA1  I84

P3E_CPU0_PE1_SS_RXN<5>   @BASEBOARD_FAB2_LIB.BASEBOARD_FAB2(SCH_1):P3E_CPU0_PE1_SS_RXN<5>
  C2U14    2      B  CAP_0402    I287
  R2U25    2      B  RES         I460
  U5D1   DH9  PE1_RX_DN<5>  SKX_EXT_B_BGA1  I84

P3E_CPU0_PE1_SS_RXN<6>   @BASEBOARD_FAB2_LIB.BASEBOARD_FAB2(SCH_1):P3E_CPU0_PE1_SS_RXN<6>
  C2U16    2      B  CAP_0402    I286
  R2U27    2      B  RES         I459
  U5D1   DK9  PE1_RX_DN<6>  SKX_EXT_B_BGA1  I84

P3E_CPU0_PE1_SS_RXN<7>   @BASEBOARD_FAB2_LIB.BASEBOARD_FAB2(SCH_1):P3E_CPU0_PE1_SS_RXN<7>
  C2U18    2      B  CAP_0402    I294
  R2U29    2      B  RES         I458
  U5D1   DM9  PE1_RX_DN<7>  SKX_EXT_B_BGA1  I84

P3E_CPU0_PE1_SS_RXP<0>   @BASEBOARD_FAB2_LIB.BASEBOARD_FAB2(SCH_1):P3E_CPU0_PE1_SS_RXP<0>
  C2U3     2      B  CAP_0402    I272
  R2U14    2      B  RES         I466
  U5D1   CU8  PE1_RX_DP<0>  SKX_EXT_B_BGA1  I84

P3E_CPU0_PE1_SS_RXP<1>   @BASEBOARD_FAB2_LIB.BASEBOARD_FAB2(SCH_1):P3E_CPU0_PE1_SS_RXP<1>
  C2U5     2      B  CAP_0402    I274
  R2U16    2      B  RES         I467
  U5D1   CY7  PE1_RX_DP<1>  SKX_EXT_B_BGA1  I84

P3E_CPU0_PE1_SS_RXP<2>   @BASEBOARD_FAB2_LIB.BASEBOARD_FAB2(SCH_1):P3E_CPU0_PE1_SS_RXP<2>
  C2U7     2      B  CAP_0402    I277
  R2U18    2      B  RES         I468
  U5D1   DB9  PE1_RX_DP<2>  SKX_EXT_B_BGA1  I84

P3E_CPU0_PE1_SS_RXP<3>   @BASEBOARD_FAB2_LIB.BASEBOARD_FAB2(SCH_1):P3E_CPU0_PE1_SS_RXP<3>
  C2U9     2      B  CAP_0402    I279
  R2U20    2      B  RES         I469
  U5D1   DA10  PE1_RX_DP<3>  SKX_EXT_B_BGA1  I84

P3E_CPU0_PE1_SS_RXP<4>   @BASEBOARD_FAB2_LIB.BASEBOARD_FAB2(SCH_1):P3E_CPU0_PE1_SS_RXP<4>
  C2U11    2      B  CAP_0402    I278
  R2U22    2      B  RES         I470
  U5D1   DD9  PE1_RX_DP<4>  SKX_EXT_B_BGA1  I84

P3E_CPU0_PE1_SS_RXP<5>   @BASEBOARD_FAB2_LIB.BASEBOARD_FAB2(SCH_1):P3E_CPU0_PE1_SS_RXP<5>
  C2U13    2      B  CAP_0402    I297
  R2U24    2      B  RES         I471
  U5D1   DF9  PE1_RX_DP<5>  SKX_EXT_B_BGA1  I84

P3E_CPU0_PE1_SS_RXP<6>   @BASEBOARD_FAB2_LIB.BASEBOARD_FAB2(SCH_1):P3E_CPU0_PE1_SS_RXP<6>
  C2U15    2      B  CAP_0402    I296
  R2U26    2      B  RES         I472
  U5D1   DJ8  PE1_RX_DP<6>  SKX_EXT_B_BGA1  I84

P3E_CPU0_PE1_SS_RXP<7>   @BASEBOARD_FAB2_LIB.BASEBOARD_FAB2(SCH_1):P3E_CPU0_PE1_SS_RXP<7>
  C2U17    2      B  CAP_0402    I300
  R2U28    2      B  RES         I473
  U5D1   DL10  PE1_RX_DP<7>  SKX_EXT_B_BGA1  I84

P3E_CPU0_PE1_SS_R_RXN<0>   @BASEBOARD_FAB2_LIB.BASEBOARD_FAB2(SCH_1):P3E_CPU0_PE1_SS_R_RXN<0>
  J8G1    56   IO56  SCONN200_H68296001_SM  I258
  R2U15    1      A  RES         I465

P3E_CPU0_PE1_SS_R_RXN<1>   @BASEBOARD_FAB2_LIB.BASEBOARD_FAB2(SCH_1):P3E_CPU0_PE1_SS_R_RXN<1>
  J8G1    62   IO62  SCONN200_H68296001_SM  I258
  R2U17    1      A  RES         I464

P3E_CPU0_PE1_SS_R_RXN<2>   @BASEBOARD_FAB2_LIB.BASEBOARD_FAB2(SCH_1):P3E_CPU0_PE1_SS_R_RXN<2>
  J8G1    72   IO72  SCONN200_H68296001_SM  I258
  R2U19    1      A  RES         I463

P3E_CPU0_PE1_SS_R_RXN<3>   @BASEBOARD_FAB2_LIB.BASEBOARD_FAB2(SCH_1):P3E_CPU0_PE1_SS_R_RXN<3>
  J8G1    78   IO78  SCONN200_H68296001_SM  I258
  R2U21    1      A  RES         I462

P3E_CPU0_PE1_SS_R_RXN<4>   @BASEBOARD_FAB2_LIB.BASEBOARD_FAB2(SCH_1):P3E_CPU0_PE1_SS_R_RXN<4>
  J8G1    84   IO84  SCONN200_H68296001_SM  I258
  R2U23    1      A  RES         I461

P3E_CPU0_PE1_SS_R_RXN<5>   @BASEBOARD_FAB2_LIB.BASEBOARD_FAB2(SCH_1):P3E_CPU0_PE1_SS_R_RXN<5>
  J8G1    90   IO90  SCONN200_H68296001_SM  I258
  R2U25    1      A  RES         I460

P3E_CPU0_PE1_SS_R_RXN<6>   @BASEBOARD_FAB2_LIB.BASEBOARD_FAB2(SCH_1):P3E_CPU0_PE1_SS_R_RXN<6>
  J8G1    96   IO96  SCONN200_H68296001_SM  I258
  R2U27    1      A  RES         I459

P3E_CPU0_PE1_SS_R_RXN<7>   @BASEBOARD_FAB2_LIB.BASEBOARD_FAB2(SCH_1):P3E_CPU0_PE1_SS_R_RXN<7>
  J8G1   102  IO102  SCONN200_H68296001_SM  I243
  R2U29    1      A  RES         I458

P3E_CPU0_PE1_SS_R_RXP<0>   @BASEBOARD_FAB2_LIB.BASEBOARD_FAB2(SCH_1):P3E_CPU0_PE1_SS_R_RXP<0>
  J8G1    54   IO54  SCONN200_H68296001_SM  I258
  R2U14    1      A  RES         I466

P3E_CPU0_PE1_SS_R_RXP<1>   @BASEBOARD_FAB2_LIB.BASEBOARD_FAB2(SCH_1):P3E_CPU0_PE1_SS_R_RXP<1>
  J8G1    60   IO60  SCONN200_H68296001_SM  I258
  R2U16    1      A  RES         I467

P3E_CPU0_PE1_SS_R_RXP<2>   @BASEBOARD_FAB2_LIB.BASEBOARD_FAB2(SCH_1):P3E_CPU0_PE1_SS_R_RXP<2>
  J8G1    70   IO70  SCONN200_H68296001_SM  I258
  R2U18    1      A  RES         I468

P3E_CPU0_PE1_SS_R_RXP<3>   @BASEBOARD_FAB2_LIB.BASEBOARD_FAB2(SCH_1):P3E_CPU0_PE1_SS_R_RXP<3>
  J8G1    76   IO76  SCONN200_H68296001_SM  I258
  R2U20    1      A  RES         I469

P3E_CPU0_PE1_SS_R_RXP<4>   @BASEBOARD_FAB2_LIB.BASEBOARD_FAB2(SCH_1):P3E_CPU0_PE1_SS_R_RXP<4>
  J8G1    82   IO82  SCONN200_H68296001_SM  I258
  R2U22    1      A  RES         I470

P3E_CPU0_PE1_SS_R_RXP<5>   @BASEBOARD_FAB2_LIB.BASEBOARD_FAB2(SCH_1):P3E_CPU0_PE1_SS_R_RXP<5>
  J8G1    88   IO88  SCONN200_H68296001_SM  I258
  R2U24    1      A  RES         I471

P3E_CPU0_PE1_SS_R_RXP<6>   @BASEBOARD_FAB2_LIB.BASEBOARD_FAB2(SCH_1):P3E_CPU0_PE1_SS_R_RXP<6>
  J8G1    94   IO94  SCONN200_H68296001_SM  I258
  R2U26    1      A  RES         I472

P3E_CPU0_PE1_SS_R_RXP<7>   @BASEBOARD_FAB2_LIB.BASEBOARD_FAB2(SCH_1):P3E_CPU0_PE1_SS_R_RXP<7>
  J8G1   100  IO100  SCONN200_H68296001_SM  I258
  R2U28    1      A  RES         I473

P3E_CPU0_PE1_SS_TXN<0>   @BASEBOARD_FAB2_LIB.BASEBOARD_FAB2(SCH_1):P3E_CPU0_PE1_SS_TXN<0>
  C3P12    1      A  CAP_0402    I415
  C3P13    1      A  CAP_0402    I207
  U5D1   DA2  PE1_TX_DN<0>  SKX_EXT_B_BGA1  I84

P3E_CPU0_PE1_SS_TXN<1>   @BASEBOARD_FAB2_LIB.BASEBOARD_FAB2(SCH_1):P3E_CPU0_PE1_SS_TXN<1>
  C3P16    1      A  CAP_0402    I422
  C3P17    1      A  CAP_0402    I208
  U5D1   DC2  PE1_TX_DN<1>  SKX_EXT_B_BGA1  I84

P3E_CPU0_PE1_SS_TXN<2>   @BASEBOARD_FAB2_LIB.BASEBOARD_FAB2(SCH_1):P3E_CPU0_PE1_SS_TXN<2>
  C3P20    1      A  CAP_0402    I215
  C3P21    1      A  CAP_0402    I423
  U5D1   DE2  PE1_TX_DN<2>  SKX_EXT_B_BGA1  I84

P3E_CPU0_PE1_SS_TXN<3>   @BASEBOARD_FAB2_LIB.BASEBOARD_FAB2(SCH_1):P3E_CPU0_PE1_SS_TXN<3>
  C3P24    1      A  CAP_0402    I424
  C3P25    1      A  CAP_0402    I216
  U5D1   DE4  PE1_TX_DN<3>  SKX_EXT_B_BGA1  I84

P3E_CPU0_PE1_SS_TXN<4>   @BASEBOARD_FAB2_LIB.BASEBOARD_FAB2(SCH_1):P3E_CPU0_PE1_SS_TXN<4>
  C3P28    1      A  CAP_0402    I232
  C3P29    1      A  CAP_0402    I437
  U5D1   DG4  PE1_TX_DN<4>  SKX_EXT_B_BGA1  I84

P3E_CPU0_PE1_SS_TXN<5>   @BASEBOARD_FAB2_LIB.BASEBOARD_FAB2(SCH_1):P3E_CPU0_PE1_SS_TXN<5>
  C3P32    1      A  CAP_0402    I234
  C3P33    1      A  CAP_0402    I439
  U5D1   DK3  PE1_TX_DN<5>  SKX_EXT_B_BGA1  I84

P3E_CPU0_PE1_SS_TXN<6>   @BASEBOARD_FAB2_LIB.BASEBOARD_FAB2(SCH_1):P3E_CPU0_PE1_SS_TXN<6>
  C3P36    1      A  CAP_0402    I438
  C3P37    1      A  CAP_0402    I235
  U5D1   DM3  PE1_TX_DN<6>  SKX_EXT_B_BGA1  I84

P3E_CPU0_PE1_SS_TXN<7>   @BASEBOARD_FAB2_LIB.BASEBOARD_FAB2(SCH_1):P3E_CPU0_PE1_SS_TXN<7>
  C3P40    1      A  CAP_0402    I241
  C3P41    1      A  CAP_0402    I448
  U5D1   DN4  PE1_TX_DN<7>  SKX_EXT_B_BGA1  I84

P3E_CPU0_PE1_SS_TXP<0>   @BASEBOARD_FAB2_LIB.BASEBOARD_FAB2(SCH_1):P3E_CPU0_PE1_SS_TXP<0>
  C3P10    1      A  CAP_0402    I417
  C3P11    1      A  CAP_0402    I212
  U5D1   CW2  PE1_TX_DP<0>  SKX_EXT_B_BGA1  I84

P3E_CPU0_PE1_SS_TXP<1>   @BASEBOARD_FAB2_LIB.BASEBOARD_FAB2(SCH_1):P3E_CPU0_PE1_SS_TXP<1>
  C3P14    1      A  CAP_0402    I431
  C3P15    1      A  CAP_0402    I226
  U5D1   DB1  PE1_TX_DP<1>  SKX_EXT_B_BGA1  I84

P3E_CPU0_PE1_SS_TXP<2>   @BASEBOARD_FAB2_LIB.BASEBOARD_FAB2(SCH_1):P3E_CPU0_PE1_SS_TXP<2>
  C3P18    1      A  CAP_0402    I219
  C3P19    1      A  CAP_0402    I427
  U5D1   DD3  PE1_TX_DP<2>  SKX_EXT_B_BGA1  I84

P3E_CPU0_PE1_SS_TXP<3>   @BASEBOARD_FAB2_LIB.BASEBOARD_FAB2(SCH_1):P3E_CPU0_PE1_SS_TXP<3>
  C3P22    1      A  CAP_0402    I435
  C3P23    1      A  CAP_0402    I229
  U5D1   DC4  PE1_TX_DP<3>  SKX_EXT_B_BGA1  I84

P3E_CPU0_PE1_SS_TXP<4>   @BASEBOARD_FAB2_LIB.BASEBOARD_FAB2(SCH_1):P3E_CPU0_PE1_SS_TXP<4>
  C3P26    1      A  CAP_0402    I444
  C3P27    1      A  CAP_0402    I223
  U5D1   DF3  PE1_TX_DP<4>  SKX_EXT_B_BGA1  I84

P3E_CPU0_PE1_SS_TXP<5>   @BASEBOARD_FAB2_LIB.BASEBOARD_FAB2(SCH_1):P3E_CPU0_PE1_SS_TXP<5>
  C3P30    1      A  CAP_0402    I245
  C3P31    1      A  CAP_0402    I452
  U5D1   DH3  PE1_TX_DP<5>  SKX_EXT_B_BGA1  I84

P3E_CPU0_PE1_SS_TXP<6>   @BASEBOARD_FAB2_LIB.BASEBOARD_FAB2(SCH_1):P3E_CPU0_PE1_SS_TXP<6>
  C3P34    1      A  CAP_0402    I447
  C3P35    1      A  CAP_0402    I240
  U5D1   DL2  PE1_TX_DP<6>  SKX_EXT_B_BGA1  I84

P3E_CPU0_PE1_SS_TXP<7>   @BASEBOARD_FAB2_LIB.BASEBOARD_FAB2(SCH_1):P3E_CPU0_PE1_SS_TXP<7>
  C3P38    1      A  CAP_0402    I455
  C3P39    1      A  CAP_0402    I248
  U5D1   DP3  PE1_TX_DP<7>  SKX_EXT_B_BGA1  I84

P3E_CPU0_PE2_SS_C_TXN<0>   @BASEBOARD_FAB2_LIB.BASEBOARD_FAB2(SCH_1):P3E_CPU0_PE2_SS_C_TXN<0>
  C8G10    2      B  CAP_0402    I96
  J8G1   103  IO103  SCONN200_H68296001_SM  I243

P3E_CPU0_PE2_SS_C_TXN<1>   @BASEBOARD_FAB2_LIB.BASEBOARD_FAB2(SCH_1):P3E_CPU0_PE2_SS_C_TXN<1>
  C8G7     2      B  CAP_0402    I62
  J8G1   111  IO111  SCONN200_H68296001_SM  I243

P3E_CPU0_PE2_SS_C_TXN<2>   @BASEBOARD_FAB2_LIB.BASEBOARD_FAB2(SCH_1):P3E_CPU0_PE2_SS_C_TXN<2>
  C8G6     2      B  CAP_0402    I61
  J8G1   115  IO115  SCONN200_H68296001_SM  I243

P3E_CPU0_PE2_SS_C_TXN<3>   @BASEBOARD_FAB2_LIB.BASEBOARD_FAB2(SCH_1):P3E_CPU0_PE2_SS_C_TXN<3>
  C8G4     2      B  CAP_0402    I56
  J8G1   121  IO121  SCONN200_H68296001_SM  I243

P3E_CPU0_PE2_SS_C_TXN<4>   @BASEBOARD_FAB2_LIB.BASEBOARD_FAB2(SCH_1):P3E_CPU0_PE2_SS_C_TXN<4>
  C8G2     2      B  CAP_0402    I58
  J8G1   127  IO127  SCONN200_H68296001_SM  I243

P3E_CPU0_PE2_SS_C_TXN<5>   @BASEBOARD_FAB2_LIB.BASEBOARD_FAB2(SCH_1):P3E_CPU0_PE2_SS_C_TXN<5>
  C7G26    2      B  CAP_0402    I55
  J8G1   133  IO133  SCONN200_H68296001_SM  I243

P3E_CPU0_PE2_SS_C_TXN<6>   @BASEBOARD_FAB2_LIB.BASEBOARD_FAB2(SCH_1):P3E_CPU0_PE2_SS_C_TXN<6>
  C7G24    2      B  CAP_0402     I1
  J8G1   139  IO139  SCONN200_H68296001_SM  I243

P3E_CPU0_PE2_SS_C_TXN<7>   @BASEBOARD_FAB2_LIB.BASEBOARD_FAB2(SCH_1):P3E_CPU0_PE2_SS_C_TXN<7>
  C7G22    2      B  CAP_0402    I37
  J8G1   145  IO145  SCONN200_H68296001_SM  I243

P3E_CPU0_PE2_SS_C_TXN<8>   @BASEBOARD_FAB2_LIB.BASEBOARD_FAB2(SCH_1):P3E_CPU0_PE2_SS_C_TXN<8>
  C7G20    2      B  CAP_0402    I34
  J8G1   151  IO151  SCONN200_H68296001_SM  I243

P3E_CPU0_PE2_SS_C_TXN<9>   @BASEBOARD_FAB2_LIB.BASEBOARD_FAB2(SCH_1):P3E_CPU0_PE2_SS_C_TXN<9>
  C7G18    2      B  CAP_0402    I32
  J8G1   157  IO157  SCONN200_H68296001_SM  I243

P3E_CPU0_PE2_SS_C_TXN<10>   @BASEBOARD_FAB2_LIB.BASEBOARD_FAB2(SCH_1):P3E_CPU0_PE2_SS_C_TXN<10>
  C7G16    2      B  CAP_0402    I31
  J8G1   163  IO163  SCONN200_H68296001_SM  I243

P3E_CPU0_PE2_SS_C_TXN<11>   @BASEBOARD_FAB2_LIB.BASEBOARD_FAB2(SCH_1):P3E_CPU0_PE2_SS_C_TXN<11>
  C7G13    2      B  CAP_0402    I13
  J8G1   171  IO171  SCONN200_H68296001_SM  I243

P3E_CPU0_PE2_SS_C_TXN<12>   @BASEBOARD_FAB2_LIB.BASEBOARD_FAB2(SCH_1):P3E_CPU0_PE2_SS_C_TXN<12>
  C7G12    2      B  CAP_0402    I12
  J8G1   175  IO175  SCONN200_H68296001_SM  I243

P3E_CPU0_PE2_SS_C_TXN<13>   @BASEBOARD_FAB2_LIB.BASEBOARD_FAB2(SCH_1):P3E_CPU0_PE2_SS_C_TXN<13>
  C7G10    2      B  CAP_0402     I8
  J8G1   181  IO181  SCONN200_H68296001_SM  I243

P3E_CPU0_PE2_SS_C_TXN<14>   @BASEBOARD_FAB2_LIB.BASEBOARD_FAB2(SCH_1):P3E_CPU0_PE2_SS_C_TXN<14>
  C7G7     2      B  CAP_0402     I7
  J8G1   189  IO189  SCONN200_H68296001_SM  I243

P3E_CPU0_PE2_SS_C_TXN<15>   @BASEBOARD_FAB2_LIB.BASEBOARD_FAB2(SCH_1):P3E_CPU0_PE2_SS_C_TXN<15>
  C7G6     2      B  CAP_0402     I6
  J8G1   193  IO193  SCONN200_H68296001_SM  I243

P3E_CPU0_PE2_SS_C_TXP<0>   @BASEBOARD_FAB2_LIB.BASEBOARD_FAB2(SCH_1):P3E_CPU0_PE2_SS_C_TXP<0>
  C8G9     2      B  CAP_0402    I93
  J8G1   105  IO105  SCONN200_H68296001_SM  I243

P3E_CPU0_PE2_SS_C_TXP<1>   @BASEBOARD_FAB2_LIB.BASEBOARD_FAB2(SCH_1):P3E_CPU0_PE2_SS_C_TXP<1>
  C8G8     2      B  CAP_0402    I76
  J8G1   109  IO109  SCONN200_H68296001_SM  I243

P3E_CPU0_PE2_SS_C_TXP<2>   @BASEBOARD_FAB2_LIB.BASEBOARD_FAB2(SCH_1):P3E_CPU0_PE2_SS_C_TXP<2>
  C8G5     2      B  CAP_0402    I75
  J8G1   117  IO117  SCONN200_H68296001_SM  I243

P3E_CPU0_PE2_SS_C_TXP<3>   @BASEBOARD_FAB2_LIB.BASEBOARD_FAB2(SCH_1):P3E_CPU0_PE2_SS_C_TXP<3>
  C8G3     2      B  CAP_0402    I71
  J8G1   123  IO123  SCONN200_H68296001_SM  I243

P3E_CPU0_PE2_SS_C_TXP<4>   @BASEBOARD_FAB2_LIB.BASEBOARD_FAB2(SCH_1):P3E_CPU0_PE2_SS_C_TXP<4>
  C8G1     2      B  CAP_0402    I70
  J8G1   129  IO129  SCONN200_H68296001_SM  I243

P3E_CPU0_PE2_SS_C_TXP<5>   @BASEBOARD_FAB2_LIB.BASEBOARD_FAB2(SCH_1):P3E_CPU0_PE2_SS_C_TXP<5>
  C7G25    2      B  CAP_0402    I69
  J8G1   135  IO135  SCONN200_H68296001_SM  I243

P3E_CPU0_PE2_SS_C_TXP<6>   @BASEBOARD_FAB2_LIB.BASEBOARD_FAB2(SCH_1):P3E_CPU0_PE2_SS_C_TXP<6>
  C7G23    2      B  CAP_0402    I52
  J8G1   141  IO141  SCONN200_H68296001_SM  I243

P3E_CPU0_PE2_SS_C_TXP<7>   @BASEBOARD_FAB2_LIB.BASEBOARD_FAB2(SCH_1):P3E_CPU0_PE2_SS_C_TXP<7>
  C7G21    2      B  CAP_0402    I51
  J8G1   147  IO147  SCONN200_H68296001_SM  I243

P3E_CPU0_PE2_SS_C_TXP<8>   @BASEBOARD_FAB2_LIB.BASEBOARD_FAB2(SCH_1):P3E_CPU0_PE2_SS_C_TXP<8>
  C7G19    2      B  CAP_0402    I46
  J8G1   153  IO153  SCONN200_H68296001_SM  I243

P3E_CPU0_PE2_SS_C_TXP<9>   @BASEBOARD_FAB2_LIB.BASEBOARD_FAB2(SCH_1):P3E_CPU0_PE2_SS_C_TXP<9>
  C7G17    2      B  CAP_0402    I44
  J8G1   159  IO159  SCONN200_H68296001_SM  I243

P3E_CPU0_PE2_SS_C_TXP<10>   @BASEBOARD_FAB2_LIB.BASEBOARD_FAB2(SCH_1):P3E_CPU0_PE2_SS_C_TXP<10>
  C7G15    2      B  CAP_0402    I45
  J8G1   165  IO165  SCONN200_H68296001_SM  I243

P3E_CPU0_PE2_SS_C_TXP<11>   @BASEBOARD_FAB2_LIB.BASEBOARD_FAB2(SCH_1):P3E_CPU0_PE2_SS_C_TXP<11>
  C7G14    2      B  CAP_0402    I28
  J8G1   169  IO169  SCONN200_H68296001_SM  I243

P3E_CPU0_PE2_SS_C_TXP<12>   @BASEBOARD_FAB2_LIB.BASEBOARD_FAB2(SCH_1):P3E_CPU0_PE2_SS_C_TXP<12>
  C7G11    2      B  CAP_0402    I27
  J8G1   177  IO177  SCONN200_H68296001_SM  I243

P3E_CPU0_PE2_SS_C_TXP<13>   @BASEBOARD_FAB2_LIB.BASEBOARD_FAB2(SCH_1):P3E_CPU0_PE2_SS_C_TXP<13>
  C7G9     2      B  CAP_0402    I21
  J8G1   183  IO183  SCONN200_H68296001_SM  I243

P3E_CPU0_PE2_SS_C_TXP<14>   @BASEBOARD_FAB2_LIB.BASEBOARD_FAB2(SCH_1):P3E_CPU0_PE2_SS_C_TXP<14>
  C7G8     2      B  CAP_0402    I22
  J8G1   187  IO187  SCONN200_H68296001_SM  I243

P3E_CPU0_PE2_SS_C_TXP<15>   @BASEBOARD_FAB2_LIB.BASEBOARD_FAB2(SCH_1):P3E_CPU0_PE2_SS_C_TXP<15>
  C7G5     2      B  CAP_0402    I20
  J8G1   195  IO195  SCONN200_H68296001_SM  I243

P3E_CPU0_PE2_SS_RXN<0>   @BASEBOARD_FAB2_LIB.BASEBOARD_FAB2(SCH_1):P3E_CPU0_PE2_SS_RXN<0>
  J8G1   106  IO106  SCONN200_H68296001_SM  I243
  U5D1   CT9  PE2_RX_DN<0>  SKX_EXT_B_BGA1  I106

P3E_CPU0_PE2_SS_RXN<1>   @BASEBOARD_FAB2_LIB.BASEBOARD_FAB2(SCH_1):P3E_CPU0_PE2_SS_RXN<1>
  J8G1   112  IO112  SCONN200_H68296001_SM  I243
  U5D1   CP9  PE2_RX_DN<1>  SKX_EXT_B_BGA1  I106

P3E_CPU0_PE2_SS_RXN<2>   @BASEBOARD_FAB2_LIB.BASEBOARD_FAB2(SCH_1):P3E_CPU0_PE2_SS_RXN<2>
  J8G1   118  IO118  SCONN200_H68296001_SM  I243
  U5D1   CP7  PE2_RX_DN<2>  SKX_EXT_B_BGA1  I106

P3E_CPU0_PE2_SS_RXN<3>   @BASEBOARD_FAB2_LIB.BASEBOARD_FAB2(SCH_1):P3E_CPU0_PE2_SS_RXN<3>
  J8G1   124  IO124  SCONN200_H68296001_SM  I243
  U5D1   CM7  PE2_RX_DN<3>  SKX_EXT_B_BGA1  I106

P3E_CPU0_PE2_SS_RXN<4>   @BASEBOARD_FAB2_LIB.BASEBOARD_FAB2(SCH_1):P3E_CPU0_PE2_SS_RXN<4>
  J8G1   130  IO130  SCONN200_H68296001_SM  I243
  U5D1   CK7  PE2_RX_DN<4>  SKX_EXT_B_BGA1  I106

P3E_CPU0_PE2_SS_RXN<5>   @BASEBOARD_FAB2_LIB.BASEBOARD_FAB2(SCH_1):P3E_CPU0_PE2_SS_RXN<5>
  J8G1   136  IO136  SCONN200_H68296001_SM  I243
  U5D1   CG8  PE2_RX_DN<5>  SKX_EXT_B_BGA1  I106

P3E_CPU0_PE2_SS_RXN<6>   @BASEBOARD_FAB2_LIB.BASEBOARD_FAB2(SCH_1):P3E_CPU0_PE2_SS_RXN<6>
  J8G1   144  IO144  SCONN200_H68296001_SM  I243
  U5D1   CE6  PE2_RX_DN<6>  SKX_EXT_B_BGA1  I106

P3E_CPU0_PE2_SS_RXN<7>   @BASEBOARD_FAB2_LIB.BASEBOARD_FAB2(SCH_1):P3E_CPU0_PE2_SS_RXN<7>
  J8G1   148  IO148  SCONN200_H68296001_SM  I243
  U5D1   CE8  PE2_RX_DN<7>  SKX_EXT_B_BGA1  I106

P3E_CPU0_PE2_SS_RXN<8>   @BASEBOARD_FAB2_LIB.BASEBOARD_FAB2(SCH_1):P3E_CPU0_PE2_SS_RXN<8>
  J8G1   154  IO154  SCONN200_H68296001_SM  I243
  U5D1   BY9  PE2_RX_DN<8>  SKX_EXT_B_BGA1  I106

P3E_CPU0_PE2_SS_RXN<9>   @BASEBOARD_FAB2_LIB.BASEBOARD_FAB2(SCH_1):P3E_CPU0_PE2_SS_RXN<9>
  J8G1   160  IO160  SCONN200_H68296001_SM  I243
  U5D1   BY7  PE2_RX_DN<9>  SKX_EXT_B_BGA1  I106

P3E_CPU0_PE2_SS_RXN<10>   @BASEBOARD_FAB2_LIB.BASEBOARD_FAB2(SCH_1):P3E_CPU0_PE2_SS_RXN<10>
  J8G1   166  IO166  SCONN200_H68296001_SM  I243
  U5D1   BV7  PE2_RX_DN<10>  SKX_EXT_B_BGA1  I106

P3E_CPU0_PE2_SS_RXN<11>   @BASEBOARD_FAB2_LIB.BASEBOARD_FAB2(SCH_1):P3E_CPU0_PE2_SS_RXN<11>
  J8G1   172  IO172  SCONN200_H68296001_SM  I243
  U5D1   BT7  PE2_RX_DN<11>  SKX_EXT_B_BGA1  I106

P3E_CPU0_PE2_SS_RXN<12>   @BASEBOARD_FAB2_LIB.BASEBOARD_FAB2(SCH_1):P3E_CPU0_PE2_SS_RXN<12>
  J8G1   178  IO178  SCONN200_H68296001_SM  I243
  U5D1   BR8  PE2_RX_DN<12>  SKX_EXT_B_BGA1  I106

P3E_CPU0_PE2_SS_RXN<13>   @BASEBOARD_FAB2_LIB.BASEBOARD_FAB2(SCH_1):P3E_CPU0_PE2_SS_RXN<13>
  J8G1   186  IO186  SCONN200_H68296001_SM  I243
  U5D1   BN8  PE2_RX_DN<13>  SKX_EXT_B_BGA1  I106

P3E_CPU0_PE2_SS_RXN<14>   @BASEBOARD_FAB2_LIB.BASEBOARD_FAB2(SCH_1):P3E_CPU0_PE2_SS_RXN<14>
  J8G1   190  IO190  SCONN200_H68296001_SM  I243
  U5D1   BL8  PE2_RX_DN<14>  SKX_EXT_B_BGA1  I106

P3E_CPU0_PE2_SS_RXN<15>   @BASEBOARD_FAB2_LIB.BASEBOARD_FAB2(SCH_1):P3E_CPU0_PE2_SS_RXN<15>
  J8G1   196  IO196  SCONN200_H68296001_SM  I243
  U5D1   BK9  PE2_RX_DN<15>  SKX_EXT_B_BGA1  I106

P3E_CPU0_PE2_SS_RXP<0>   @BASEBOARD_FAB2_LIB.BASEBOARD_FAB2(SCH_1):P3E_CPU0_PE2_SS_RXP<0>
  J8G1   108  IO108  SCONN200_H68296001_SM  I243
  U5D1   CR8  PE2_RX_DP<0>  SKX_EXT_B_BGA1  I106

P3E_CPU0_PE2_SS_RXP<1>   @BASEBOARD_FAB2_LIB.BASEBOARD_FAB2(SCH_1):P3E_CPU0_PE2_SS_RXP<1>
  J8G1   114  IO114  SCONN200_H68296001_SM  I243
  U5D1   CM9  PE2_RX_DP<1>  SKX_EXT_B_BGA1  I106

P3E_CPU0_PE2_SS_RXP<2>   @BASEBOARD_FAB2_LIB.BASEBOARD_FAB2(SCH_1):P3E_CPU0_PE2_SS_RXP<2>
  J8G1   120  IO120  SCONN200_H68296001_SM  I243
  U5D1   CN8  PE2_RX_DP<2>  SKX_EXT_B_BGA1  I106

P3E_CPU0_PE2_SS_RXP<3>   @BASEBOARD_FAB2_LIB.BASEBOARD_FAB2(SCH_1):P3E_CPU0_PE2_SS_RXP<3>
  J8G1   126  IO126  SCONN200_H68296001_SM  I243
  U5D1   CL6  PE2_RX_DP<3>  SKX_EXT_B_BGA1  I106

P3E_CPU0_PE2_SS_RXP<4>   @BASEBOARD_FAB2_LIB.BASEBOARD_FAB2(SCH_1):P3E_CPU0_PE2_SS_RXP<4>
  J8G1   132  IO132  SCONN200_H68296001_SM  I243
  U5D1   CH7  PE2_RX_DP<4>  SKX_EXT_B_BGA1  I106

P3E_CPU0_PE2_SS_RXP<5>   @BASEBOARD_FAB2_LIB.BASEBOARD_FAB2(SCH_1):P3E_CPU0_PE2_SS_RXP<5>
  J8G1   138  IO138  SCONN200_H68296001_SM  I243
  U5D1   CF7  PE2_RX_DP<5>  SKX_EXT_B_BGA1  I106

P3E_CPU0_PE2_SS_RXP<6>   @BASEBOARD_FAB2_LIB.BASEBOARD_FAB2(SCH_1):P3E_CPU0_PE2_SS_RXP<6>
  J8G1   142  IO142  SCONN200_H68296001_SM  I243
  U5D1   CD7  PE2_RX_DP<6>  SKX_EXT_B_BGA1  I106

P3E_CPU0_PE2_SS_RXP<7>   @BASEBOARD_FAB2_LIB.BASEBOARD_FAB2(SCH_1):P3E_CPU0_PE2_SS_RXP<7>
  J8G1   150  IO150  SCONN200_H68296001_SM  I243
  U5D1   CC8  PE2_RX_DP<7>  SKX_EXT_B_BGA1  I106

P3E_CPU0_PE2_SS_RXP<8>   @BASEBOARD_FAB2_LIB.BASEBOARD_FAB2(SCH_1):P3E_CPU0_PE2_SS_RXP<8>
  J8G1   156  IO156  SCONN200_H68296001_SM  I243
  U5D1   BV9  PE2_RX_DP<8>  SKX_EXT_B_BGA1  I106

P3E_CPU0_PE2_SS_RXP<9>   @BASEBOARD_FAB2_LIB.BASEBOARD_FAB2(SCH_1):P3E_CPU0_PE2_SS_RXP<9>
  J8G1   162  IO162  SCONN200_H68296001_SM  I243
  U5D1   BW8  PE2_RX_DP<9>  SKX_EXT_B_BGA1  I106

P3E_CPU0_PE2_SS_RXP<10>   @BASEBOARD_FAB2_LIB.BASEBOARD_FAB2(SCH_1):P3E_CPU0_PE2_SS_RXP<10>
  J8G1   168  IO168  SCONN200_H68296001_SM  I243
  U5D1   BU6  PE2_RX_DP<10>  SKX_EXT_B_BGA1  I106

P3E_CPU0_PE2_SS_RXP<11>   @BASEBOARD_FAB2_LIB.BASEBOARD_FAB2(SCH_1):P3E_CPU0_PE2_SS_RXP<11>
  J8G1   174  IO174  SCONN200_H68296001_SM  I243
  U5D1   BP7  PE2_RX_DP<11>  SKX_EXT_B_BGA1  I106

P3E_CPU0_PE2_SS_RXP<12>   @BASEBOARD_FAB2_LIB.BASEBOARD_FAB2(SCH_1):P3E_CPU0_PE2_SS_RXP<12>
  J8G1   180  IO180  SCONN200_H68296001_SM  I243
  U5D1   BP9  PE2_RX_DP<12>  SKX_EXT_B_BGA1  I106

P3E_CPU0_PE2_SS_RXP<13>   @BASEBOARD_FAB2_LIB.BASEBOARD_FAB2(SCH_1):P3E_CPU0_PE2_SS_RXP<13>
  J8G1   184  IO184  SCONN200_H68296001_SM  I243
  U5D1   BM7  PE2_RX_DP<13>  SKX_EXT_B_BGA1  I106

P3E_CPU0_PE2_SS_RXP<14>   @BASEBOARD_FAB2_LIB.BASEBOARD_FAB2(SCH_1):P3E_CPU0_PE2_SS_RXP<14>
  J8G1   192  IO192  SCONN200_H68296001_SM  I243
  U5D1   BJ8  PE2_RX_DP<14>  SKX_EXT_B_BGA1  I106

P3E_CPU0_PE2_SS_RXP<15>   @BASEBOARD_FAB2_LIB.BASEBOARD_FAB2(SCH_1):P3E_CPU0_PE2_SS_RXP<15>
  J8G1   198  IO198  SCONN200_H68296001_SM  I243
  U5D1   BJ10  PE2_RX_DP<15>  SKX_EXT_B_BGA1  I106

P3E_CPU0_PE2_SS_TXN<0>   @BASEBOARD_FAB2_LIB.BASEBOARD_FAB2(SCH_1):P3E_CPU0_PE2_SS_TXN<0>
  C8G10    1      A  CAP_0402    I96
  U5D1   CY3  PE2_TX_DN<0>  SKX_EXT_B_BGA1  I106

P3E_CPU0_PE2_SS_TXN<1>   @BASEBOARD_FAB2_LIB.BASEBOARD_FAB2(SCH_1):P3E_CPU0_PE2_SS_TXN<1>
  C8G7     1      A  CAP_0402    I62
  U5D1   CV3  PE2_TX_DN<1>  SKX_EXT_B_BGA1  I106

P3E_CPU0_PE2_SS_TXN<2>   @BASEBOARD_FAB2_LIB.BASEBOARD_FAB2(SCH_1):P3E_CPU0_PE2_SS_TXN<2>
  C8G6     1      A  CAP_0402    I61
  U5D1   CT1  PE2_TX_DN<2>  SKX_EXT_B_BGA1  I106

P3E_CPU0_PE2_SS_TXN<3>   @BASEBOARD_FAB2_LIB.BASEBOARD_FAB2(SCH_1):P3E_CPU0_PE2_SS_TXN<3>
  C8G4     1      A  CAP_0402    I56
  U5D1   CT3  PE2_TX_DN<3>  SKX_EXT_B_BGA1  I106

P3E_CPU0_PE2_SS_TXN<4>   @BASEBOARD_FAB2_LIB.BASEBOARD_FAB2(SCH_1):P3E_CPU0_PE2_SS_TXN<4>
  C8G2     1      A  CAP_0402    I58
  U5D1   CM1  PE2_TX_DN<4>  SKX_EXT_B_BGA1  I106

P3E_CPU0_PE2_SS_TXN<5>   @BASEBOARD_FAB2_LIB.BASEBOARD_FAB2(SCH_1):P3E_CPU0_PE2_SS_TXN<5>
  C7G26    1      A  CAP_0402    I55
  U5D1   CL2  PE2_TX_DN<5>  SKX_EXT_B_BGA1  I106

P3E_CPU0_PE2_SS_TXN<6>   @BASEBOARD_FAB2_LIB.BASEBOARD_FAB2(SCH_1):P3E_CPU0_PE2_SS_TXN<6>
  C7G24    1      A  CAP_0402     I1
  U5D1   CG2  PE2_TX_DN<6>  SKX_EXT_B_BGA1  I106

P3E_CPU0_PE2_SS_TXN<7>   @BASEBOARD_FAB2_LIB.BASEBOARD_FAB2(SCH_1):P3E_CPU0_PE2_SS_TXN<7>
  C7G22    1      A  CAP_0402    I37
  U5D1   CF3  PE2_TX_DN<7>  SKX_EXT_B_BGA1  I106

P3E_CPU0_PE2_SS_TXN<8>   @BASEBOARD_FAB2_LIB.BASEBOARD_FAB2(SCH_1):P3E_CPU0_PE2_SS_TXN<8>
  C7G20    1      A  CAP_0402    I34
  U5D1   CC2  PE2_TX_DN<8>  SKX_EXT_B_BGA1  I106

P3E_CPU0_PE2_SS_TXN<9>   @BASEBOARD_FAB2_LIB.BASEBOARD_FAB2(SCH_1):P3E_CPU0_PE2_SS_TXN<9>
  C7G18    1      A  CAP_0402    I32
  U5D1   CB3  PE2_TX_DN<9>  SKX_EXT_B_BGA1  I106

P3E_CPU0_PE2_SS_TXN<10>   @BASEBOARD_FAB2_LIB.BASEBOARD_FAB2(SCH_1):P3E_CPU0_PE2_SS_TXN<10>
  C7G16    1      A  CAP_0402    I31
  U5D1   CA4  PE2_TX_DN<10>  SKX_EXT_B_BGA1  I106

P3E_CPU0_PE2_SS_TXN<11>   @BASEBOARD_FAB2_LIB.BASEBOARD_FAB2(SCH_1):P3E_CPU0_PE2_SS_TXN<11>
  C7G13    1      A  CAP_0402    I13
  U5D1   BW4  PE2_TX_DN<11>  SKX_EXT_B_BGA1  I106

P3E_CPU0_PE2_SS_TXN<12>   @BASEBOARD_FAB2_LIB.BASEBOARD_FAB2(SCH_1):P3E_CPU0_PE2_SS_TXN<12>
  C7G12    1      A  CAP_0402    I12
  U5D1   BU4  PE2_TX_DN<12>  SKX_EXT_B_BGA1  I106

P3E_CPU0_PE2_SS_TXN<13>   @BASEBOARD_FAB2_LIB.BASEBOARD_FAB2(SCH_1):P3E_CPU0_PE2_SS_TXN<13>
  C7G10    1      A  CAP_0402     I8
  U5D1   BP5  PE2_TX_DN<13>  SKX_EXT_B_BGA1  I106

P3E_CPU0_PE2_SS_TXN<14>   @BASEBOARD_FAB2_LIB.BASEBOARD_FAB2(SCH_1):P3E_CPU0_PE2_SS_TXN<14>
  C7G7     1      A  CAP_0402     I7
  U5D1   BL4  PE2_TX_DN<14>  SKX_EXT_B_BGA1  I106

P3E_CPU0_PE2_SS_TXN<15>   @BASEBOARD_FAB2_LIB.BASEBOARD_FAB2(SCH_1):P3E_CPU0_PE2_SS_TXN<15>
  C7G6     1      A  CAP_0402     I6
  U5D1   BM5  PE2_TX_DN<15>  SKX_EXT_B_BGA1  I106

P3E_CPU0_PE2_SS_TXP<0>   @BASEBOARD_FAB2_LIB.BASEBOARD_FAB2(SCH_1):P3E_CPU0_PE2_SS_TXP<0>
  C8G9     1      A  CAP_0402    I93
  U5D1   CW4  PE2_TX_DP<0>  SKX_EXT_B_BGA1  I106

P3E_CPU0_PE2_SS_TXP<1>   @BASEBOARD_FAB2_LIB.BASEBOARD_FAB2(SCH_1):P3E_CPU0_PE2_SS_TXP<1>
  C8G8     1      A  CAP_0402    I76
  U5D1   CU2  PE2_TX_DP<1>  SKX_EXT_B_BGA1  I106

P3E_CPU0_PE2_SS_TXP<2>   @BASEBOARD_FAB2_LIB.BASEBOARD_FAB2(SCH_1):P3E_CPU0_PE2_SS_TXP<2>
  C8G5     1      A  CAP_0402    I75
  U5D1   CR2  PE2_TX_DP<2>  SKX_EXT_B_BGA1  I106

P3E_CPU0_PE2_SS_TXP<3>   @BASEBOARD_FAB2_LIB.BASEBOARD_FAB2(SCH_1):P3E_CPU0_PE2_SS_TXP<3>
  C8G3     1      A  CAP_0402    I71
  U5D1   CP3  PE2_TX_DP<3>  SKX_EXT_B_BGA1  I106

P3E_CPU0_PE2_SS_TXP<4>   @BASEBOARD_FAB2_LIB.BASEBOARD_FAB2(SCH_1):P3E_CPU0_PE2_SS_TXP<4>
  C8G1     1      A  CAP_0402    I70
  U5D1   CK1  PE2_TX_DP<4>  SKX_EXT_B_BGA1  I106

P3E_CPU0_PE2_SS_TXP<5>   @BASEBOARD_FAB2_LIB.BASEBOARD_FAB2(SCH_1):P3E_CPU0_PE2_SS_TXP<5>
  C7G25    1      A  CAP_0402    I69
  U5D1   CK3  PE2_TX_DP<5>  SKX_EXT_B_BGA1  I106

P3E_CPU0_PE2_SS_TXP<6>   @BASEBOARD_FAB2_LIB.BASEBOARD_FAB2(SCH_1):P3E_CPU0_PE2_SS_TXP<6>
  C7G23    1      A  CAP_0402    I52
  U5D1   CE2  PE2_TX_DP<6>  SKX_EXT_B_BGA1  I106

P3E_CPU0_PE2_SS_TXP<7>   @BASEBOARD_FAB2_LIB.BASEBOARD_FAB2(SCH_1):P3E_CPU0_PE2_SS_TXP<7>
  C7G21    1      A  CAP_0402    I51
  U5D1   CE4  PE2_TX_DP<7>  SKX_EXT_B_BGA1  I106

P3E_CPU0_PE2_SS_TXP<8>   @BASEBOARD_FAB2_LIB.BASEBOARD_FAB2(SCH_1):P3E_CPU0_PE2_SS_TXP<8>
  C7G19    1      A  CAP_0402    I46
  U5D1   CD3  PE2_TX_DP<8>  SKX_EXT_B_BGA1  I106

P3E_CPU0_PE2_SS_TXP<9>   @BASEBOARD_FAB2_LIB.BASEBOARD_FAB2(SCH_1):P3E_CPU0_PE2_SS_TXP<9>
  C7G17    1      A  CAP_0402    I44
  U5D1   BY3  PE2_TX_DP<9>  SKX_EXT_B_BGA1  I106

P3E_CPU0_PE2_SS_TXP<10>   @BASEBOARD_FAB2_LIB.BASEBOARD_FAB2(SCH_1):P3E_CPU0_PE2_SS_TXP<10>
  C7G15    1      A  CAP_0402    I45
  U5D1   BY5  PE2_TX_DP<10>  SKX_EXT_B_BGA1  I106

P3E_CPU0_PE2_SS_TXP<11>   @BASEBOARD_FAB2_LIB.BASEBOARD_FAB2(SCH_1):P3E_CPU0_PE2_SS_TXP<11>
  C7G14    1      A  CAP_0402    I28
  U5D1   BV3  PE2_TX_DP<11>  SKX_EXT_B_BGA1  I106

P3E_CPU0_PE2_SS_TXP<12>   @BASEBOARD_FAB2_LIB.BASEBOARD_FAB2(SCH_1):P3E_CPU0_PE2_SS_TXP<12>
  C7G11    1      A  CAP_0402    I27
  U5D1   BR4  PE2_TX_DP<12>  SKX_EXT_B_BGA1  I106

P3E_CPU0_PE2_SS_TXP<13>   @BASEBOARD_FAB2_LIB.BASEBOARD_FAB2(SCH_1):P3E_CPU0_PE2_SS_TXP<13>
  C7G9     1      A  CAP_0402    I21
  U5D1   BN4  PE2_TX_DP<13>  SKX_EXT_B_BGA1  I106

P3E_CPU0_PE2_SS_TXP<14>   @BASEBOARD_FAB2_LIB.BASEBOARD_FAB2(SCH_1):P3E_CPU0_PE2_SS_TXP<14>
  C7G8     1      A  CAP_0402    I22
  U5D1   BM3  PE2_TX_DP<14>  SKX_EXT_B_BGA1  I106

P3E_CPU0_PE2_SS_TXP<15>   @BASEBOARD_FAB2_LIB.BASEBOARD_FAB2(SCH_1):P3E_CPU0_PE2_SS_TXP<15>
  C7G5     1      A  CAP_0402    I20
  U5D1   BK5  PE2_TX_DP<15>  SKX_EXT_B_BGA1  I106

P3E_CPU0_PE3_OCP_RXN<0>   @BASEBOARD_FAB2_LIB.BASEBOARD_FAB2(SCH_1):P3E_CPU0_PE3_OCP_RXN<0>
  J8E3    63   IO63  SCONN80_E67482007_SM  I119
  U5D1   EA18  PE3_RX_DN<0>  SKX_EXT_B_BGA1  I89

P3E_CPU0_PE3_OCP_RXN<1>   @BASEBOARD_FAB2_LIB.BASEBOARD_FAB2(SCH_1):P3E_CPU0_PE3_OCP_RXN<1>
  J8E3    55   IO55  SCONN80_E67482007_SM  I119
  U5D1   DW18  PE3_RX_DN<1>  SKX_EXT_B_BGA1  I89

P3E_CPU0_PE3_OCP_RXN<2>   @BASEBOARD_FAB2_LIB.BASEBOARD_FAB2(SCH_1):P3E_CPU0_PE3_OCP_RXN<2>
  J8E3    47   IO47  SCONN80_E67482007_SM  I119
  U5D1   DW16  PE3_RX_DN<2>  SKX_EXT_B_BGA1  I89

P3E_CPU0_PE3_OCP_RXN<3>   @BASEBOARD_FAB2_LIB.BASEBOARD_FAB2(SCH_1):P3E_CPU0_PE3_OCP_RXN<3>
  J8E3    39   IO39  SCONN80_E67482007_SM  I119
  U5D1   DT19  PE3_RX_DN<3>  SKX_EXT_B_BGA1  I89

P3E_CPU0_PE3_OCP_RXN<4>   @BASEBOARD_FAB2_LIB.BASEBOARD_FAB2(SCH_1):P3E_CPU0_PE3_OCP_RXN<4>
  J8E3    29   IO29  SCONN80_E67482007_SM  I119
  U5D1   DR16  PE3_RX_DN<4>  SKX_EXT_B_BGA1  I89

P3E_CPU0_PE3_OCP_RXN<5>   @BASEBOARD_FAB2_LIB.BASEBOARD_FAB2(SCH_1):P3E_CPU0_PE3_OCP_RXN<5>
  J8E3    21   IO21  SCONN80_E67482007_SM  I119
  U5D1   DR14  PE3_RX_DN<5>  SKX_EXT_B_BGA1  I89

P3E_CPU0_PE3_OCP_RXN<6>   @BASEBOARD_FAB2_LIB.BASEBOARD_FAB2(SCH_1):P3E_CPU0_PE3_OCP_RXN<6>
  J8E3    13   IO13  SCONN80_E67482007_SM  I119
  U5D1   DN14  PE3_RX_DN<6>  SKX_EXT_B_BGA1  I89

P3E_CPU0_PE3_OCP_RXN<7>   @BASEBOARD_FAB2_LIB.BASEBOARD_FAB2(SCH_1):P3E_CPU0_PE3_OCP_RXN<7>
  J8E3     7    IO7  SCONN80_E67482007_SM  I119
  U5D1   DL14  PE3_RX_DN<7>  SKX_EXT_B_BGA1  I89

P3E_CPU0_PE3_OCP_RXN<8>   @BASEBOARD_FAB2_LIB.BASEBOARD_FAB2(SCH_1):P3E_CPU0_PE3_OCP_RXN<8>
  J9B3   117  IO117  SCONN120_A28699018_SM  I336
  U5D1   DL12  PE3_RX_DN<8>  SKX_EXT_B_BGA1  I89

P3E_CPU0_PE3_OCP_RXN<9>   @BASEBOARD_FAB2_LIB.BASEBOARD_FAB2(SCH_1):P3E_CPU0_PE3_OCP_RXN<9>
  J9B3   109  IO109  SCONN120_A28699018_SM  I336
  U5D1   DJ12  PE3_RX_DN<9>  SKX_EXT_B_BGA1  I89

P3E_CPU0_PE3_OCP_RXN<10>   @BASEBOARD_FAB2_LIB.BASEBOARD_FAB2(SCH_1):P3E_CPU0_PE3_OCP_RXN<10>
  J9B3   101  IO101  SCONN120_A28699018_SM  I336
  U5D1   DG12  PE3_RX_DN<10>  SKX_EXT_B_BGA1  I89

P3E_CPU0_PE3_OCP_RXN<11>   @BASEBOARD_FAB2_LIB.BASEBOARD_FAB2(SCH_1):P3E_CPU0_PE3_OCP_RXN<11>
  J9B3    93   IO93  SCONN120_A28699018_SM  I336
  U5D1   DG10  PE3_RX_DN<11>  SKX_EXT_B_BGA1  I89

P3E_CPU0_PE3_OCP_RXN<12>   @BASEBOARD_FAB2_LIB.BASEBOARD_FAB2(SCH_1):P3E_CPU0_PE3_OCP_RXN<12>
  J9B3    85   IO85  SCONN120_A28699018_SM  I336
  U5D1   DD13  PE3_RX_DN<12>  SKX_EXT_B_BGA1  I89

P3E_CPU0_PE3_OCP_RXN<13>   @BASEBOARD_FAB2_LIB.BASEBOARD_FAB2(SCH_1):P3E_CPU0_PE3_OCP_RXN<13>
  J9B3    77   IO77  SCONN120_A28699018_SM  I336
  U5D1   DB11  PE3_RX_DN<13>  SKX_EXT_B_BGA1  I89

P3E_CPU0_PE3_OCP_RXN<14>   @BASEBOARD_FAB2_LIB.BASEBOARD_FAB2(SCH_1):P3E_CPU0_PE3_OCP_RXN<14>
  J9B3    69   IO69  SCONN120_A28699018_SM  I336
  U5D1   CY11  PE3_RX_DN<14>  SKX_EXT_B_BGA1  I89

P3E_CPU0_PE3_OCP_RXN<15>   @BASEBOARD_FAB2_LIB.BASEBOARD_FAB2(SCH_1):P3E_CPU0_PE3_OCP_RXN<15>
  J9B3    61   IO61  SCONN120_A28699018_SM  I336
  U5D1   CV9  PE3_RX_DN<15>  SKX_EXT_B_BGA1  I89

P3E_CPU0_PE3_OCP_RXP<0>   @BASEBOARD_FAB2_LIB.BASEBOARD_FAB2(SCH_1):P3E_CPU0_PE3_OCP_RXP<0>
  J8E3    61   IO61  SCONN80_E67482007_SM  I119
  U5D1   DY17  PE3_RX_DP<0>  SKX_EXT_B_BGA1  I89

P3E_CPU0_PE3_OCP_RXP<1>   @BASEBOARD_FAB2_LIB.BASEBOARD_FAB2(SCH_1):P3E_CPU0_PE3_OCP_RXP<1>
  J8E3    53   IO53  SCONN80_E67482007_SM  I119
  U5D1   DU18  PE3_RX_DP<1>  SKX_EXT_B_BGA1  I89

P3E_CPU0_PE3_OCP_RXP<2>   @BASEBOARD_FAB2_LIB.BASEBOARD_FAB2(SCH_1):P3E_CPU0_PE3_OCP_RXP<2>
  J8E3    45   IO45  SCONN80_E67482007_SM  I119
  U5D1   DV17  PE3_RX_DP<2>  SKX_EXT_B_BGA1  I89

P3E_CPU0_PE3_OCP_RXP<3>   @BASEBOARD_FAB2_LIB.BASEBOARD_FAB2(SCH_1):P3E_CPU0_PE3_OCP_RXP<3>
  J8E3    37   IO37  SCONN80_E67482007_SM  I119
  U5D1   DR18  PE3_RX_DP<3>  SKX_EXT_B_BGA1  I89

P3E_CPU0_PE3_OCP_RXP<4>   @BASEBOARD_FAB2_LIB.BASEBOARD_FAB2(SCH_1):P3E_CPU0_PE3_OCP_RXP<4>
  J8E3    31   IO31  SCONN80_E67482007_SM  I119
  U5D1   DN16  PE3_RX_DP<4>  SKX_EXT_B_BGA1  I89

P3E_CPU0_PE3_OCP_RXP<5>   @BASEBOARD_FAB2_LIB.BASEBOARD_FAB2(SCH_1):P3E_CPU0_PE3_OCP_RXP<5>
  J8E3    23   IO23  SCONN80_E67482007_SM  I119
  U5D1   DP15  PE3_RX_DP<5>  SKX_EXT_B_BGA1  I89

P3E_CPU0_PE3_OCP_RXP<6>   @BASEBOARD_FAB2_LIB.BASEBOARD_FAB2(SCH_1):P3E_CPU0_PE3_OCP_RXP<6>
  J8E3    15   IO15  SCONN80_E67482007_SM  I119
  U5D1   DM13  PE3_RX_DP<6>  SKX_EXT_B_BGA1  I89

P3E_CPU0_PE3_OCP_RXP<7>   @BASEBOARD_FAB2_LIB.BASEBOARD_FAB2(SCH_1):P3E_CPU0_PE3_OCP_RXP<7>
  J8E3     5    IO5  SCONN80_E67482007_SM  I119
  U5D1   DJ14  PE3_RX_DP<7>  SKX_EXT_B_BGA1  I89

P3E_CPU0_PE3_OCP_RXP<8>   @BASEBOARD_FAB2_LIB.BASEBOARD_FAB2(SCH_1):P3E_CPU0_PE3_OCP_RXP<8>
  J9B3   115  IO115  SCONN120_A28699018_SM  I336
  U5D1   DK13  PE3_RX_DP<8>  SKX_EXT_B_BGA1  I89

P3E_CPU0_PE3_OCP_RXP<9>   @BASEBOARD_FAB2_LIB.BASEBOARD_FAB2(SCH_1):P3E_CPU0_PE3_OCP_RXP<9>
  J9B3   107  IO107  SCONN120_A28699018_SM  I336
  U5D1   DH11  PE3_RX_DP<9>  SKX_EXT_B_BGA1  I89

P3E_CPU0_PE3_OCP_RXP<10>   @BASEBOARD_FAB2_LIB.BASEBOARD_FAB2(SCH_1):P3E_CPU0_PE3_OCP_RXP<10>
  J9B3    99   IO99  SCONN120_A28699018_SM  I336
  U5D1   DE12  PE3_RX_DP<10>  SKX_EXT_B_BGA1  I89

P3E_CPU0_PE3_OCP_RXP<11>   @BASEBOARD_FAB2_LIB.BASEBOARD_FAB2(SCH_1):P3E_CPU0_PE3_OCP_RXP<11>
  J9B3    91   IO91  SCONN120_A28699018_SM  I336
  U5D1   DF11  PE3_RX_DP<11>  SKX_EXT_B_BGA1  I89

P3E_CPU0_PE3_OCP_RXP<12>   @BASEBOARD_FAB2_LIB.BASEBOARD_FAB2(SCH_1):P3E_CPU0_PE3_OCP_RXP<12>
  J9B3    83   IO83  SCONN120_A28699018_SM  I336
  U5D1   DC12  PE3_RX_DP<12>  SKX_EXT_B_BGA1  I89

P3E_CPU0_PE3_OCP_RXP<13>   @BASEBOARD_FAB2_LIB.BASEBOARD_FAB2(SCH_1):P3E_CPU0_PE3_OCP_RXP<13>
  J9B3    75   IO75  SCONN120_A28699018_SM  I336
  U5D1   DA12  PE3_RX_DP<13>  SKX_EXT_B_BGA1  I89

P3E_CPU0_PE3_OCP_RXP<14>   @BASEBOARD_FAB2_LIB.BASEBOARD_FAB2(SCH_1):P3E_CPU0_PE3_OCP_RXP<14>
  J9B3    67   IO67  SCONN120_A28699018_SM  I336
  U5D1   CW10  PE3_RX_DP<14>  SKX_EXT_B_BGA1  I89

P3E_CPU0_PE3_OCP_RXP<15>   @BASEBOARD_FAB2_LIB.BASEBOARD_FAB2(SCH_1):P3E_CPU0_PE3_OCP_RXP<15>
  J9B3    59   IO59  SCONN120_A28699018_SM  I336
  U5D1   CU10  PE3_RX_DP<15>  SKX_EXT_B_BGA1  I89

P3E_CPU0_PE3_OCP_TXN<0>   @BASEBOARD_FAB2_LIB.BASEBOARD_FAB2(SCH_1):P3E_CPU0_PE3_OCP_TXN<0>
  C1R1     1      A  CAP_0402    I29
  U5D1   EE14  PE3_TX_DN<0>  SKX_EXT_B_BGA1  I89

P3E_CPU0_PE3_OCP_TXN<1>   @BASEBOARD_FAB2_LIB.BASEBOARD_FAB2(SCH_1):P3E_CPU0_PE3_OCP_TXN<1>
  C1R3     1      A  CAP_0402    I37
  U5D1   EE12  PE3_TX_DN<1>  SKX_EXT_B_BGA1  I89

P3E_CPU0_PE3_OCP_TXN<2>   @BASEBOARD_FAB2_LIB.BASEBOARD_FAB2(SCH_1):P3E_CPU0_PE3_OCP_TXN<2>
  C1R5     1      A  CAP_0402    I59
  U5D1   EC12  PE3_TX_DN<2>  SKX_EXT_B_BGA1  I89

P3E_CPU0_PE3_OCP_TXN<3>   @BASEBOARD_FAB2_LIB.BASEBOARD_FAB2(SCH_1):P3E_CPU0_PE3_OCP_TXN<3>
  C1R7     1      A  CAP_0402    I70
  U5D1   DY11  PE3_TX_DN<3>  SKX_EXT_B_BGA1  I89

P3E_CPU0_PE3_OCP_TXN<4>   @BASEBOARD_FAB2_LIB.BASEBOARD_FAB2(SCH_1):P3E_CPU0_PE3_OCP_TXN<4>
  C1R9     1      A  CAP_0402    I134
  U5D1   EB9  PE3_TX_DN<4>  SKX_EXT_B_BGA1  I89

P3E_CPU0_PE3_OCP_TXN<5>   @BASEBOARD_FAB2_LIB.BASEBOARD_FAB2(SCH_1):P3E_CPU0_PE3_OCP_TXN<5>
  C2R13    1      A  CAP_0402    I137
  U5D1   DW10  PE3_TX_DN<5>  SKX_EXT_B_BGA1  I89

P3E_CPU0_PE3_OCP_TXN<6>   @BASEBOARD_FAB2_LIB.BASEBOARD_FAB2(SCH_1):P3E_CPU0_PE3_OCP_TXN<6>
  C2R7     1      A  CAP_0402    I123
  U5D1   DU8  PE3_TX_DN<6>  SKX_EXT_B_BGA1  I89

P3E_CPU0_PE3_OCP_TXN<7>   @BASEBOARD_FAB2_LIB.BASEBOARD_FAB2(SCH_1):P3E_CPU0_PE3_OCP_TXN<7>
  C2R9     1      A  CAP_0402    I147
  U5D1   DR8  PE3_TX_DN<7>  SKX_EXT_B_BGA1  I89

P3E_CPU0_PE3_OCP_TXN<8>   @BASEBOARD_FAB2_LIB.BASEBOARD_FAB2(SCH_1):P3E_CPU0_PE3_OCP_TXN<8>
  C2M15    1      A  CAP_0402    I86
  U5D1   DM7  PE3_TX_DN<8>  SKX_EXT_B_BGA1  I89

P3E_CPU0_PE3_OCP_TXN<9>   @BASEBOARD_FAB2_LIB.BASEBOARD_FAB2(SCH_1):P3E_CPU0_PE3_OCP_TXN<9>
  C1M19    1      A  CAP_0402    I90
  U5D1   DP5  PE3_TX_DN<9>  SKX_EXT_B_BGA1  I89

P3E_CPU0_PE3_OCP_TXN<10>   @BASEBOARD_FAB2_LIB.BASEBOARD_FAB2(SCH_1):P3E_CPU0_PE3_OCP_TXN<10>
  C1M17    1      A  CAP_0402    I92
  U5D1   DL6  PE3_TX_DN<10>  SKX_EXT_B_BGA1  I89

P3E_CPU0_PE3_OCP_TXN<11>   @BASEBOARD_FAB2_LIB.BASEBOARD_FAB2(SCH_1):P3E_CPU0_PE3_OCP_TXN<11>
  C1M15    1      A  CAP_0402    I95
  U5D1   DJ4  PE3_TX_DN<11>  SKX_EXT_B_BGA1  I89

P3E_CPU0_PE3_OCP_TXN<12>   @BASEBOARD_FAB2_LIB.BASEBOARD_FAB2(SCH_1):P3E_CPU0_PE3_OCP_TXN<12>
  C1M13    1      A  CAP_0402    I111
  U5D1   DJ6  PE3_TX_DN<12>  SKX_EXT_B_BGA1  I89

P3E_CPU0_PE3_OCP_TXN<13>   @BASEBOARD_FAB2_LIB.BASEBOARD_FAB2(SCH_1):P3E_CPU0_PE3_OCP_TXN<13>
  C1M11    1      A  CAP_0402    I117
  U5D1   DD5  PE3_TX_DN<13>  SKX_EXT_B_BGA1  I89

P3E_CPU0_PE3_OCP_TXN<14>   @BASEBOARD_FAB2_LIB.BASEBOARD_FAB2(SCH_1):P3E_CPU0_PE3_OCP_TXN<14>
  C1M9     1      A  CAP_0402    I114
  U5D1   DB5  PE3_TX_DN<14>  SKX_EXT_B_BGA1  I89

P3E_CPU0_PE3_OCP_TXN<15>   @BASEBOARD_FAB2_LIB.BASEBOARD_FAB2(SCH_1):P3E_CPU0_PE3_OCP_TXN<15>
  C1M7     1      A  CAP_0402    I122
  U5D1   CY5  PE3_TX_DN<15>  SKX_EXT_B_BGA1  I89

P3E_CPU0_PE3_OCP_TXP<0>   @BASEBOARD_FAB2_LIB.BASEBOARD_FAB2(SCH_1):P3E_CPU0_PE3_OCP_TXP<0>
  C1R2     1      A  CAP_0402    I10
  U5D1   EC14  PE3_TX_DP<0>  SKX_EXT_B_BGA1  I89

P3E_CPU0_PE3_OCP_TXP<1>   @BASEBOARD_FAB2_LIB.BASEBOARD_FAB2(SCH_1):P3E_CPU0_PE3_OCP_TXP<1>
  C1R4     1      A  CAP_0402    I26
  U5D1   ED13  PE3_TX_DP<1>  SKX_EXT_B_BGA1  I89

P3E_CPU0_PE3_OCP_TXP<2>   @BASEBOARD_FAB2_LIB.BASEBOARD_FAB2(SCH_1):P3E_CPU0_PE3_OCP_TXP<2>
  C1R6     1      A  CAP_0402    I40
  U5D1   EB11  PE3_TX_DP<2>  SKX_EXT_B_BGA1  I89

P3E_CPU0_PE3_OCP_TXP<3>   @BASEBOARD_FAB2_LIB.BASEBOARD_FAB2(SCH_1):P3E_CPU0_PE3_OCP_TXP<3>
  C1R8     1      A  CAP_0402    I55
  U5D1   EA10  PE3_TX_DP<3>  SKX_EXT_B_BGA1  I89

P3E_CPU0_PE3_OCP_TXP<4>   @BASEBOARD_FAB2_LIB.BASEBOARD_FAB2(SCH_1):P3E_CPU0_PE3_OCP_TXP<4>
  C1R10    1      A  CAP_0402    I128
  U5D1   DY9  PE3_TX_DP<4>  SKX_EXT_B_BGA1  I89

P3E_CPU0_PE3_OCP_TXP<5>   @BASEBOARD_FAB2_LIB.BASEBOARD_FAB2(SCH_1):P3E_CPU0_PE3_OCP_TXP<5>
  C2R14    1      A  CAP_0402    I130
  U5D1   DV9  PE3_TX_DP<5>  SKX_EXT_B_BGA1  I89

P3E_CPU0_PE3_OCP_TXP<6>   @BASEBOARD_FAB2_LIB.BASEBOARD_FAB2(SCH_1):P3E_CPU0_PE3_OCP_TXP<6>
  C2R8     1      A  CAP_0402    I141
  U5D1   DT9  PE3_TX_DP<6>  SKX_EXT_B_BGA1  I89

P3E_CPU0_PE3_OCP_TXP<7>   @BASEBOARD_FAB2_LIB.BASEBOARD_FAB2(SCH_1):P3E_CPU0_PE3_OCP_TXP<7>
  C2R10    1      A  CAP_0402    I142
  U5D1   DP7  PE3_TX_DP<7>  SKX_EXT_B_BGA1  I89

P3E_CPU0_PE3_OCP_TXP<8>   @BASEBOARD_FAB2_LIB.BASEBOARD_FAB2(SCH_1):P3E_CPU0_PE3_OCP_TXP<8>
  C2M14    1      A  CAP_0402    I76
  U5D1   DN6  PE3_TX_DP<8>  SKX_EXT_B_BGA1  I89

P3E_CPU0_PE3_OCP_TXP<9>   @BASEBOARD_FAB2_LIB.BASEBOARD_FAB2(SCH_1):P3E_CPU0_PE3_OCP_TXP<9>
  C1M18    1      A  CAP_0402    I78
  U5D1   DM5  PE3_TX_DP<9>  SKX_EXT_B_BGA1  I89

P3E_CPU0_PE3_OCP_TXP<10>   @BASEBOARD_FAB2_LIB.BASEBOARD_FAB2(SCH_1):P3E_CPU0_PE3_OCP_TXP<10>
  C1M16    1      A  CAP_0402    I82
  U5D1   DK5  PE3_TX_DP<10>  SKX_EXT_B_BGA1  I89

P3E_CPU0_PE3_OCP_TXP<11>   @BASEBOARD_FAB2_LIB.BASEBOARD_FAB2(SCH_1):P3E_CPU0_PE3_OCP_TXP<11>
  C1M14    1      A  CAP_0402    I85
  U5D1   DH5  PE3_TX_DP<11>  SKX_EXT_B_BGA1  I89

P3E_CPU0_PE3_OCP_TXP<12>   @BASEBOARD_FAB2_LIB.BASEBOARD_FAB2(SCH_1):P3E_CPU0_PE3_OCP_TXP<12>
  C1M12    1      A  CAP_0402    I100
  U5D1   DG6  PE3_TX_DP<12>  SKX_EXT_B_BGA1  I89

P3E_CPU0_PE3_OCP_TXP<13>   @BASEBOARD_FAB2_LIB.BASEBOARD_FAB2(SCH_1):P3E_CPU0_PE3_OCP_TXP<13>
  C1M10    1      A  CAP_0402    I102
  U5D1   DC6  PE3_TX_DP<13>  SKX_EXT_B_BGA1  I89

P3E_CPU0_PE3_OCP_TXP<14>   @BASEBOARD_FAB2_LIB.BASEBOARD_FAB2(SCH_1):P3E_CPU0_PE3_OCP_TXP<14>
  C1M8     1      A  CAP_0402    I105
  U5D1   DA4  PE3_TX_DP<14>  SKX_EXT_B_BGA1  I89

P3E_CPU0_PE3_OCP_TXP<15>   @BASEBOARD_FAB2_LIB.BASEBOARD_FAB2(SCH_1):P3E_CPU0_PE3_OCP_TXP<15>
  C1M6     1      A  CAP_0402    I109
  U5D1   CV5  PE3_TX_DP<15>  SKX_EXT_B_BGA1  I89

P3E_CPU1_PE3_MP_C_TXN<0>   @BASEBOARD_FAB2_LIB.BASEBOARD_FAB2(SCH_1):P3E_CPU1_PE3_MP_C_TXN<0>
  C1F20    1      A  CAP_0402    I166
  J1F1    B8   IOB8  CONN76_H22707001_THMT1  I111

P3E_CPU1_PE3_MP_C_TXN<1>   @BASEBOARD_FAB2_LIB.BASEBOARD_FAB2(SCH_1):P3E_CPU1_PE3_MP_C_TXN<1>
  C1F16    1      A  CAP_0402    I172
  J1F1    E8   IOE8  CONN76_H22707001_THMT1  I111

P3E_CPU1_PE3_MP_C_TXN<2>   @BASEBOARD_FAB2_LIB.BASEBOARD_FAB2(SCH_1):P3E_CPU1_PE3_MP_C_TXN<2>
  C1F15    1      A  CAP_0402    I174
  J1F1    H8   IOH8  CONN76_H22707001_THMT1  I111

P3E_CPU1_PE3_MP_C_TXN<3>   @BASEBOARD_FAB2_LIB.BASEBOARD_FAB2(SCH_1):P3E_CPU1_PE3_MP_C_TXN<3>
  C1F13    1      A  CAP_0402    I163
  J1F1    A7   IOA7  CONN76_H22707001_THMT1  I111

P3E_CPU1_PE3_MP_C_TXN<4>   @BASEBOARD_FAB2_LIB.BASEBOARD_FAB2(SCH_1):P3E_CPU1_PE3_MP_C_TXN<4>
  C1F10    1      A  CAP_0402    I164
  J1F1    D7   IOD7  CONN76_H22707001_THMT1  I111

P3E_CPU1_PE3_MP_C_TXN<5>   @BASEBOARD_FAB2_LIB.BASEBOARD_FAB2(SCH_1):P3E_CPU1_PE3_MP_C_TXN<5>
  C1F8     1      A  CAP_0402    I170
  J1F1    H7   IOH7  CONN76_H22707001_THMT1  I111

P3E_CPU1_PE3_MP_C_TXN<6>   @BASEBOARD_FAB2_LIB.BASEBOARD_FAB2(SCH_1):P3E_CPU1_PE3_MP_C_TXN<6>
  C1F4     1      A  CAP_0402    I160
  J1F1    E6   IOE6  CONN76_H22707001_THMT1  I111

P3E_CPU1_PE3_MP_C_TXN<7>   @BASEBOARD_FAB2_LIB.BASEBOARD_FAB2(SCH_1):P3E_CPU1_PE3_MP_C_TXN<7>
  C1F3     1      A  CAP_0402    I167
  J1F1    I6   IOI6  CONN76_H22707001_THMT1  I111

P3E_CPU1_PE3_MP_C_TXN<8>   @BASEBOARD_FAB2_LIB.BASEBOARD_FAB2(SCH_1):P3E_CPU1_PE3_MP_C_TXN<8>
  C9N18    1      A  CAP_0402     I9
  J1C1    B8   IOB8  CONN76_H22707001_THMT1  I18

P3E_CPU1_PE3_MP_C_TXN<9>   @BASEBOARD_FAB2_LIB.BASEBOARD_FAB2(SCH_1):P3E_CPU1_PE3_MP_C_TXN<9>
  C9N15    1      A  CAP_0402    I13
  J1C1    E8   IOE8  CONN76_H22707001_THMT1  I18

P3E_CPU1_PE3_MP_C_TXN<10>   @BASEBOARD_FAB2_LIB.BASEBOARD_FAB2(SCH_1):P3E_CPU1_PE3_MP_C_TXN<10>
  C9N2     1      A  CAP_0402    I15
  J1C1    I8   IOI8  CONN76_H22707001_THMT1  I18

P3E_CPU1_PE3_MP_C_TXN<11>   @BASEBOARD_FAB2_LIB.BASEBOARD_FAB2(SCH_1):P3E_CPU1_PE3_MP_C_TXN<11>
  C9N3     1      A  CAP_0402    I51
  J1C1    A7   IOA7  CONN76_H22707001_THMT1  I18

P3E_CPU1_PE3_MP_C_TXN<12>   @BASEBOARD_FAB2_LIB.BASEBOARD_FAB2(SCH_1):P3E_CPU1_PE3_MP_C_TXN<12>
  C9N16    1      A  CAP_0402    I52
  J1C1    D7   IOD7  CONN76_H22707001_THMT1  I18

P3E_CPU1_PE3_MP_C_TXN<13>   @BASEBOARD_FAB2_LIB.BASEBOARD_FAB2(SCH_1):P3E_CPU1_PE3_MP_C_TXN<13>
  C9N6     1      A  CAP_0402    I81
  J1C1    G7   IOG7  CONN76_H22707001_THMT1  I18

P3E_CPU1_PE3_MP_C_TXN<14>   @BASEBOARD_FAB2_LIB.BASEBOARD_FAB2(SCH_1):P3E_CPU1_PE3_MP_C_TXN<14>
  C9N8     1      A  CAP_0402    I50
  J1C1    E6   IOE6  CONN76_H22707001_THMT1  I18

P3E_CPU1_PE3_MP_C_TXN<15>   @BASEBOARD_FAB2_LIB.BASEBOARD_FAB2(SCH_1):P3E_CPU1_PE3_MP_C_TXN<15>
  C9N9     1      A  CAP_0402    I49
  J1C1    H6   IOH6  CONN76_H22707001_THMT1  I18

P3E_CPU1_PE3_MP_C_TXP<0>   @BASEBOARD_FAB2_LIB.BASEBOARD_FAB2(SCH_1):P3E_CPU1_PE3_MP_C_TXP<0>
  C1F18    1      A  CAP_0402    I171
  J1F1    C8   IOC8  CONN76_H22707001_THMT1  I111

P3E_CPU1_PE3_MP_C_TXP<1>   @BASEBOARD_FAB2_LIB.BASEBOARD_FAB2(SCH_1):P3E_CPU1_PE3_MP_C_TXP<1>
  C1F17    1      A  CAP_0402    I173
  J1F1    F8   IOF8  CONN76_H22707001_THMT1  I111

P3E_CPU1_PE3_MP_C_TXP<2>   @BASEBOARD_FAB2_LIB.BASEBOARD_FAB2(SCH_1):P3E_CPU1_PE3_MP_C_TXP<2>
  C1F14    1      A  CAP_0402    I175
  J1F1    I8   IOI8  CONN76_H22707001_THMT1  I111

P3E_CPU1_PE3_MP_C_TXP<3>   @BASEBOARD_FAB2_LIB.BASEBOARD_FAB2(SCH_1):P3E_CPU1_PE3_MP_C_TXP<3>
  C1F12    1      A  CAP_0402    I168
  J1F1    B7   IOB7  CONN76_H22707001_THMT1  I111

P3E_CPU1_PE3_MP_C_TXP<4>   @BASEBOARD_FAB2_LIB.BASEBOARD_FAB2(SCH_1):P3E_CPU1_PE3_MP_C_TXP<4>
  C1F11    1      A  CAP_0402    I169
  J1F1    E7   IOE7  CONN76_H22707001_THMT1  I111

P3E_CPU1_PE3_MP_C_TXP<5>   @BASEBOARD_FAB2_LIB.BASEBOARD_FAB2(SCH_1):P3E_CPU1_PE3_MP_C_TXP<5>
  C1F6     1      A  CAP_0402    I165
  J1F1    G7   IOG7  CONN76_H22707001_THMT1  I111

P3E_CPU1_PE3_MP_C_TXP<6>   @BASEBOARD_FAB2_LIB.BASEBOARD_FAB2(SCH_1):P3E_CPU1_PE3_MP_C_TXP<6>
  C1F5     1      A  CAP_0402    I161
  J1F1    F6   IOF6  CONN76_H22707001_THMT1  I111

P3E_CPU1_PE3_MP_C_TXP<7>   @BASEBOARD_FAB2_LIB.BASEBOARD_FAB2(SCH_1):P3E_CPU1_PE3_MP_C_TXP<7>
  C1F2     1      A  CAP_0402    I162
  J1F1    H6   IOH6  CONN76_H22707001_THMT1  I111

P3E_CPU1_PE3_MP_C_TXP<8>   @BASEBOARD_FAB2_LIB.BASEBOARD_FAB2(SCH_1):P3E_CPU1_PE3_MP_C_TXP<8>
  C9N17    1      A  CAP_0402    I12
  J1C1    C8   IOC8  CONN76_H22707001_THMT1  I18

P3E_CPU1_PE3_MP_C_TXP<9>   @BASEBOARD_FAB2_LIB.BASEBOARD_FAB2(SCH_1):P3E_CPU1_PE3_MP_C_TXP<9>
  C9N12    1      A  CAP_0402    I16
  J1C1    F8   IOF8  CONN76_H22707001_THMT1  I18

P3E_CPU1_PE3_MP_C_TXP<10>   @BASEBOARD_FAB2_LIB.BASEBOARD_FAB2(SCH_1):P3E_CPU1_PE3_MP_C_TXP<10>
  C9N1     1      A  CAP_0402    I14
  J1C1    H8   IOH8  CONN76_H22707001_THMT1  I18

P3E_CPU1_PE3_MP_C_TXP<11>   @BASEBOARD_FAB2_LIB.BASEBOARD_FAB2(SCH_1):P3E_CPU1_PE3_MP_C_TXP<11>
  C9N4     1      A  CAP_0402    I55
  J1C1    B7   IOB7  CONN76_H22707001_THMT1  I18

P3E_CPU1_PE3_MP_C_TXP<12>   @BASEBOARD_FAB2_LIB.BASEBOARD_FAB2(SCH_1):P3E_CPU1_PE3_MP_C_TXP<12>
  C9N14    1      A  CAP_0402    I56
  J1C1    E7   IOE7  CONN76_H22707001_THMT1  I18

P3E_CPU1_PE3_MP_C_TXP<13>   @BASEBOARD_FAB2_LIB.BASEBOARD_FAB2(SCH_1):P3E_CPU1_PE3_MP_C_TXP<13>
  C9N5     1      A  CAP_0402    I83
  J1C1    H7   IOH7  CONN76_H22707001_THMT1  I18

P3E_CPU1_PE3_MP_C_TXP<14>   @BASEBOARD_FAB2_LIB.BASEBOARD_FAB2(SCH_1):P3E_CPU1_PE3_MP_C_TXP<14>
  C9N10    1      A  CAP_0402    I53
  J1C1    F6   IOF6  CONN76_H22707001_THMT1  I18

P3E_CPU1_PE3_MP_C_TXP<15>   @BASEBOARD_FAB2_LIB.BASEBOARD_FAB2(SCH_1):P3E_CPU1_PE3_MP_C_TXP<15>
  C9N7     1      A  CAP_0402    I54
  J1C1    I6   IOI6  CONN76_H22707001_THMT1  I18

P3E_CPU1_PE3_MP_RXN<0>   @BASEBOARD_FAB2_LIB.BASEBOARD_FAB2(SCH_1):P3E_CPU1_PE3_MP_RXN<0>
  J1F1    A1   IOA1  CONN76_H22707001_THMT1  I111
  U2D1   EA18  PE3_RX_DN<0>  SKX_EXT_B_BGA1  I84

P3E_CPU1_PE3_MP_RXN<1>   @BASEBOARD_FAB2_LIB.BASEBOARD_FAB2(SCH_1):P3E_CPU1_PE3_MP_RXN<1>
  J1F1    D1   IOD1  CONN76_H22707001_THMT1  I111
  U2D1   DW18  PE3_RX_DN<1>  SKX_EXT_B_BGA1  I84

P3E_CPU1_PE3_MP_RXN<2>   @BASEBOARD_FAB2_LIB.BASEBOARD_FAB2(SCH_1):P3E_CPU1_PE3_MP_RXN<2>
  J1F1    H1   IOH1  CONN76_H22707001_THMT1  I111
  U2D1   DW16  PE3_RX_DN<2>  SKX_EXT_B_BGA1  I84

P3E_CPU1_PE3_MP_RXN<3>   @BASEBOARD_FAB2_LIB.BASEBOARD_FAB2(SCH_1):P3E_CPU1_PE3_MP_RXN<3>
  J1F1    B2   IOB2  CONN76_H22707001_THMT1  I111
  U2D1   DT19  PE3_RX_DN<3>  SKX_EXT_B_BGA1  I84

P3E_CPU1_PE3_MP_RXN<4>   @BASEBOARD_FAB2_LIB.BASEBOARD_FAB2(SCH_1):P3E_CPU1_PE3_MP_RXN<4>
  J1F1    E2   IOE2  CONN76_H22707001_THMT1  I111
  U2D1   DR16  PE3_RX_DN<4>  SKX_EXT_B_BGA1  I84

P3E_CPU1_PE3_MP_RXN<5>   @BASEBOARD_FAB2_LIB.BASEBOARD_FAB2(SCH_1):P3E_CPU1_PE3_MP_RXN<5>
  J1F1    I2   IOI2  CONN76_H22707001_THMT1  I111
  U2D1   DR14  PE3_RX_DN<5>  SKX_EXT_B_BGA1  I84

P3E_CPU1_PE3_MP_RXN<6>   @BASEBOARD_FAB2_LIB.BASEBOARD_FAB2(SCH_1):P3E_CPU1_PE3_MP_RXN<6>
  J1F1    B3   IOB3  CONN76_H22707001_THMT1  I111
  U2D1   DN14  PE3_RX_DN<6>  SKX_EXT_B_BGA1  I84

P3E_CPU1_PE3_MP_RXN<7>   @BASEBOARD_FAB2_LIB.BASEBOARD_FAB2(SCH_1):P3E_CPU1_PE3_MP_RXN<7>
  J1F1    D3   IOD3  CONN76_H22707001_THMT1  I111
  U2D1   DL14  PE3_RX_DN<7>  SKX_EXT_B_BGA1  I84

P3E_CPU1_PE3_MP_RXN<8>   @BASEBOARD_FAB2_LIB.BASEBOARD_FAB2(SCH_1):P3E_CPU1_PE3_MP_RXN<8>
  J1C1    A1   IOA1  CONN76_H22707001_THMT1  I18
  U2D1   DL12  PE3_RX_DN<8>  SKX_EXT_B_BGA1  I84

P3E_CPU1_PE3_MP_RXN<9>   @BASEBOARD_FAB2_LIB.BASEBOARD_FAB2(SCH_1):P3E_CPU1_PE3_MP_RXN<9>
  J1C1    D1   IOD1  CONN76_H22707001_THMT1  I18
  U2D1   DJ12  PE3_RX_DN<9>  SKX_EXT_B_BGA1  I84

P3E_CPU1_PE3_MP_RXN<10>   @BASEBOARD_FAB2_LIB.BASEBOARD_FAB2(SCH_1):P3E_CPU1_PE3_MP_RXN<10>
  J1C1    H1   IOH1  CONN76_H22707001_THMT1  I18
  U2D1   DG12  PE3_RX_DN<10>  SKX_EXT_B_BGA1  I84

P3E_CPU1_PE3_MP_RXN<11>   @BASEBOARD_FAB2_LIB.BASEBOARD_FAB2(SCH_1):P3E_CPU1_PE3_MP_RXN<11>
  J1C1    B2   IOB2  CONN76_H22707001_THMT1  I18
  U2D1   DG10  PE3_RX_DN<11>  SKX_EXT_B_BGA1  I84

P3E_CPU1_PE3_MP_RXN<12>   @BASEBOARD_FAB2_LIB.BASEBOARD_FAB2(SCH_1):P3E_CPU1_PE3_MP_RXN<12>
  J1C1    E2   IOE2  CONN76_H22707001_THMT1  I18
  U2D1   DC12  PE3_RX_DP<12>  SKX_EXT_B_BGA1  I84

P3E_CPU1_PE3_MP_RXN<13>   @BASEBOARD_FAB2_LIB.BASEBOARD_FAB2(SCH_1):P3E_CPU1_PE3_MP_RXN<13>
  J1C1    I2   IOI2  CONN76_H22707001_THMT1  I18
  U2D1   DB11  PE3_RX_DN<13>  SKX_EXT_B_BGA1  I84

P3E_CPU1_PE3_MP_RXN<14>   @BASEBOARD_FAB2_LIB.BASEBOARD_FAB2(SCH_1):P3E_CPU1_PE3_MP_RXN<14>
  J1C1    B3   IOB3  CONN76_H22707001_THMT1  I18
  U2D1   CY11  PE3_RX_DN<14>  SKX_EXT_B_BGA1  I84

P3E_CPU1_PE3_MP_RXN<15>   @BASEBOARD_FAB2_LIB.BASEBOARD_FAB2(SCH_1):P3E_CPU1_PE3_MP_RXN<15>
  J1C1    D3   IOD3  CONN76_H22707001_THMT1  I18
  U2D1   CV9  PE3_RX_DN<15>  SKX_EXT_B_BGA1  I84

P3E_CPU1_PE3_MP_RXP<0>   @BASEBOARD_FAB2_LIB.BASEBOARD_FAB2(SCH_1):P3E_CPU1_PE3_MP_RXP<0>
  J1F1    B1   IOB1  CONN76_H22707001_THMT1  I111
  U2D1   DY17  PE3_RX_DP<0>  SKX_EXT_B_BGA1  I84

P3E_CPU1_PE3_MP_RXP<1>   @BASEBOARD_FAB2_LIB.BASEBOARD_FAB2(SCH_1):P3E_CPU1_PE3_MP_RXP<1>
  J1F1    E1   IOE1  CONN76_H22707001_THMT1  I111
  U2D1   DU18  PE3_RX_DP<1>  SKX_EXT_B_BGA1  I84

P3E_CPU1_PE3_MP_RXP<2>   @BASEBOARD_FAB2_LIB.BASEBOARD_FAB2(SCH_1):P3E_CPU1_PE3_MP_RXP<2>
  J1F1    G1   IOG1  CONN76_H22707001_THMT1  I111
  U2D1   DV17  PE3_RX_DP<2>  SKX_EXT_B_BGA1  I84

P3E_CPU1_PE3_MP_RXP<3>   @BASEBOARD_FAB2_LIB.BASEBOARD_FAB2(SCH_1):P3E_CPU1_PE3_MP_RXP<3>
  J1F1    C2   IOC2  CONN76_H22707001_THMT1  I111
  U2D1   DR18  PE3_RX_DP<3>  SKX_EXT_B_BGA1  I84

P3E_CPU1_PE3_MP_RXP<4>   @BASEBOARD_FAB2_LIB.BASEBOARD_FAB2(SCH_1):P3E_CPU1_PE3_MP_RXP<4>
  J1F1    F2   IOF2  CONN76_H22707001_THMT1  I111
  U2D1   DN16  PE3_RX_DP<4>  SKX_EXT_B_BGA1  I84

P3E_CPU1_PE3_MP_RXP<5>   @BASEBOARD_FAB2_LIB.BASEBOARD_FAB2(SCH_1):P3E_CPU1_PE3_MP_RXP<5>
  J1F1    H2   IOH2  CONN76_H22707001_THMT1  I111
  U2D1   DP15  PE3_RX_DP<5>  SKX_EXT_B_BGA1  I84

P3E_CPU1_PE3_MP_RXP<6>   @BASEBOARD_FAB2_LIB.BASEBOARD_FAB2(SCH_1):P3E_CPU1_PE3_MP_RXP<6>
  J1F1    A3   IOA3  CONN76_H22707001_THMT1  I111
  U2D1   DM13  PE3_RX_DP<6>  SKX_EXT_B_BGA1  I84

P3E_CPU1_PE3_MP_RXP<7>   @BASEBOARD_FAB2_LIB.BASEBOARD_FAB2(SCH_1):P3E_CPU1_PE3_MP_RXP<7>
  J1F1    E3   IOE3  CONN76_H22707001_THMT1  I111
  U2D1   DJ14  PE3_RX_DP<7>  SKX_EXT_B_BGA1  I84

P3E_CPU1_PE3_MP_RXP<8>   @BASEBOARD_FAB2_LIB.BASEBOARD_FAB2(SCH_1):P3E_CPU1_PE3_MP_RXP<8>
  J1C1    B1   IOB1  CONN76_H22707001_THMT1  I18
  U2D1   DK13  PE3_RX_DP<8>  SKX_EXT_B_BGA1  I84

P3E_CPU1_PE3_MP_RXP<9>   @BASEBOARD_FAB2_LIB.BASEBOARD_FAB2(SCH_1):P3E_CPU1_PE3_MP_RXP<9>
  J1C1    E1   IOE1  CONN76_H22707001_THMT1  I18
  U2D1   DH11  PE3_RX_DP<9>  SKX_EXT_B_BGA1  I84

P3E_CPU1_PE3_MP_RXP<10>   @BASEBOARD_FAB2_LIB.BASEBOARD_FAB2(SCH_1):P3E_CPU1_PE3_MP_RXP<10>
  J1C1    G1   IOG1  CONN76_H22707001_THMT1  I18
  U2D1   DE12  PE3_RX_DP<10>  SKX_EXT_B_BGA1  I84

P3E_CPU1_PE3_MP_RXP<11>   @BASEBOARD_FAB2_LIB.BASEBOARD_FAB2(SCH_1):P3E_CPU1_PE3_MP_RXP<11>
  J1C1    C2   IOC2  CONN76_H22707001_THMT1  I18
  U2D1   DF11  PE3_RX_DP<11>  SKX_EXT_B_BGA1  I84

P3E_CPU1_PE3_MP_RXP<12>   @BASEBOARD_FAB2_LIB.BASEBOARD_FAB2(SCH_1):P3E_CPU1_PE3_MP_RXP<12>
  J1C1    F2   IOF2  CONN76_H22707001_THMT1  I18
  U2D1   DD13  PE3_RX_DN<12>  SKX_EXT_B_BGA1  I84

P3E_CPU1_PE3_MP_RXP<13>   @BASEBOARD_FAB2_LIB.BASEBOARD_FAB2(SCH_1):P3E_CPU1_PE3_MP_RXP<13>
  J1C1    H2   IOH2  CONN76_H22707001_THMT1  I18
  U2D1   DA12  PE3_RX_DP<13>  SKX_EXT_B_BGA1  I84

P3E_CPU1_PE3_MP_RXP<14>   @BASEBOARD_FAB2_LIB.BASEBOARD_FAB2(SCH_1):P3E_CPU1_PE3_MP_RXP<14>
  J1C1    A3   IOA3  CONN76_H22707001_THMT1  I18
  U2D1   CW10  PE3_RX_DP<14>  SKX_EXT_B_BGA1  I84

P3E_CPU1_PE3_MP_RXP<15>   @BASEBOARD_FAB2_LIB.BASEBOARD_FAB2(SCH_1):P3E_CPU1_PE3_MP_RXP<15>
  J1C1    E3   IOE3  CONN76_H22707001_THMT1  I18
  U2D1   CU10  PE3_RX_DP<15>  SKX_EXT_B_BGA1  I84

P3E_CPU1_PE3_MP_TXN<0>   @BASEBOARD_FAB2_LIB.BASEBOARD_FAB2(SCH_1):P3E_CPU1_PE3_MP_TXN<0>
  C1F20    2      B  CAP_0402    I166
  U2D1   EE14  PE3_TX_DN<0>  SKX_EXT_B_BGA1  I84

P3E_CPU1_PE3_MP_TXN<1>   @BASEBOARD_FAB2_LIB.BASEBOARD_FAB2(SCH_1):P3E_CPU1_PE3_MP_TXN<1>
  C1F16    2      B  CAP_0402    I172
  U2D1   EE12  PE3_TX_DN<1>  SKX_EXT_B_BGA1  I84

P3E_CPU1_PE3_MP_TXN<2>   @BASEBOARD_FAB2_LIB.BASEBOARD_FAB2(SCH_1):P3E_CPU1_PE3_MP_TXN<2>
  C1F15    2      B  CAP_0402    I174
  U2D1   EC12  PE3_TX_DN<2>  SKX_EXT_B_BGA1  I84

P3E_CPU1_PE3_MP_TXN<3>   @BASEBOARD_FAB2_LIB.BASEBOARD_FAB2(SCH_1):P3E_CPU1_PE3_MP_TXN<3>
  C1F13    2      B  CAP_0402    I163
  U2D1   DY11  PE3_TX_DN<3>  SKX_EXT_B_BGA1  I84

P3E_CPU1_PE3_MP_TXN<4>   @BASEBOARD_FAB2_LIB.BASEBOARD_FAB2(SCH_1):P3E_CPU1_PE3_MP_TXN<4>
  C1F10    2      B  CAP_0402    I164
  U2D1   EB9  PE3_TX_DN<4>  SKX_EXT_B_BGA1  I84

P3E_CPU1_PE3_MP_TXN<5>   @BASEBOARD_FAB2_LIB.BASEBOARD_FAB2(SCH_1):P3E_CPU1_PE3_MP_TXN<5>
  C1F8     2      B  CAP_0402    I170
  U2D1   DW10  PE3_TX_DN<5>  SKX_EXT_B_BGA1  I84

P3E_CPU1_PE3_MP_TXN<6>   @BASEBOARD_FAB2_LIB.BASEBOARD_FAB2(SCH_1):P3E_CPU1_PE3_MP_TXN<6>
  C1F4     2      B  CAP_0402    I160
  U2D1   DU8  PE3_TX_DN<6>  SKX_EXT_B_BGA1  I84

P3E_CPU1_PE3_MP_TXN<7>   @BASEBOARD_FAB2_LIB.BASEBOARD_FAB2(SCH_1):P3E_CPU1_PE3_MP_TXN<7>
  C1F3     2      B  CAP_0402    I167
  U2D1   DR8  PE3_TX_DN<7>  SKX_EXT_B_BGA1  I84

P3E_CPU1_PE3_MP_TXN<8>   @BASEBOARD_FAB2_LIB.BASEBOARD_FAB2(SCH_1):P3E_CPU1_PE3_MP_TXN<8>
  C9N18    2      B  CAP_0402     I9
  U2D1   DM7  PE3_TX_DN<8>  SKX_EXT_B_BGA1  I84

P3E_CPU1_PE3_MP_TXN<9>   @BASEBOARD_FAB2_LIB.BASEBOARD_FAB2(SCH_1):P3E_CPU1_PE3_MP_TXN<9>
  C9N15    2      B  CAP_0402    I13
  U2D1   DP5  PE3_TX_DN<9>  SKX_EXT_B_BGA1  I84

P3E_CPU1_PE3_MP_TXN<10>   @BASEBOARD_FAB2_LIB.BASEBOARD_FAB2(SCH_1):P3E_CPU1_PE3_MP_TXN<10>
  C9N2     2      B  CAP_0402    I15
  U2D1   DL6  PE3_TX_DN<10>  SKX_EXT_B_BGA1  I84

P3E_CPU1_PE3_MP_TXN<11>   @BASEBOARD_FAB2_LIB.BASEBOARD_FAB2(SCH_1):P3E_CPU1_PE3_MP_TXN<11>
  C9N3     2      B  CAP_0402    I51
  U2D1   DJ4  PE3_TX_DN<11>  SKX_EXT_B_BGA1  I84

P3E_CPU1_PE3_MP_TXN<12>   @BASEBOARD_FAB2_LIB.BASEBOARD_FAB2(SCH_1):P3E_CPU1_PE3_MP_TXN<12>
  C9N16    2      B  CAP_0402    I52
  U2D1   DJ6  PE3_TX_DN<12>  SKX_EXT_B_BGA1  I84

P3E_CPU1_PE3_MP_TXN<13>   @BASEBOARD_FAB2_LIB.BASEBOARD_FAB2(SCH_1):P3E_CPU1_PE3_MP_TXN<13>
  C9N6     2      B  CAP_0402    I81
  U2D1   DD5  PE3_TX_DN<13>  SKX_EXT_B_BGA1  I84

P3E_CPU1_PE3_MP_TXN<14>   @BASEBOARD_FAB2_LIB.BASEBOARD_FAB2(SCH_1):P3E_CPU1_PE3_MP_TXN<14>
  C9N8     2      B  CAP_0402    I50
  U2D1   DB5  PE3_TX_DN<14>  SKX_EXT_B_BGA1  I84

P3E_CPU1_PE3_MP_TXN<15>   @BASEBOARD_FAB2_LIB.BASEBOARD_FAB2(SCH_1):P3E_CPU1_PE3_MP_TXN<15>
  C9N9     2      B  CAP_0402    I49
  U2D1   CY5  PE3_TX_DN<15>  SKX_EXT_B_BGA1  I84

P3E_CPU1_PE3_MP_TXP<0>   @BASEBOARD_FAB2_LIB.BASEBOARD_FAB2(SCH_1):P3E_CPU1_PE3_MP_TXP<0>
  C1F18    2      B  CAP_0402    I171
  U2D1   EC14  PE3_TX_DP<0>  SKX_EXT_B_BGA1  I84

P3E_CPU1_PE3_MP_TXP<1>   @BASEBOARD_FAB2_LIB.BASEBOARD_FAB2(SCH_1):P3E_CPU1_PE3_MP_TXP<1>
  C1F17    2      B  CAP_0402    I173
  U2D1   ED13  PE3_TX_DP<1>  SKX_EXT_B_BGA1  I84

P3E_CPU1_PE3_MP_TXP<2>   @BASEBOARD_FAB2_LIB.BASEBOARD_FAB2(SCH_1):P3E_CPU1_PE3_MP_TXP<2>
  C1F14    2      B  CAP_0402    I175
  U2D1   EB11  PE3_TX_DP<2>  SKX_EXT_B_BGA1  I84

P3E_CPU1_PE3_MP_TXP<3>   @BASEBOARD_FAB2_LIB.BASEBOARD_FAB2(SCH_1):P3E_CPU1_PE3_MP_TXP<3>
  C1F12    2      B  CAP_0402    I168
  U2D1   EA10  PE3_TX_DP<3>  SKX_EXT_B_BGA1  I84

P3E_CPU1_PE3_MP_TXP<4>   @BASEBOARD_FAB2_LIB.BASEBOARD_FAB2(SCH_1):P3E_CPU1_PE3_MP_TXP<4>
  C1F11    2      B  CAP_0402    I169
  U2D1   DY9  PE3_TX_DP<4>  SKX_EXT_B_BGA1  I84

P3E_CPU1_PE3_MP_TXP<5>   @BASEBOARD_FAB2_LIB.BASEBOARD_FAB2(SCH_1):P3E_CPU1_PE3_MP_TXP<5>
  C1F6     2      B  CAP_0402    I165
  U2D1   DV9  PE3_TX_DP<5>  SKX_EXT_B_BGA1  I84

P3E_CPU1_PE3_MP_TXP<6>   @BASEBOARD_FAB2_LIB.BASEBOARD_FAB2(SCH_1):P3E_CPU1_PE3_MP_TXP<6>
  C1F5     2      B  CAP_0402    I161
  U2D1   DT9  PE3_TX_DP<6>  SKX_EXT_B_BGA1  I84

P3E_CPU1_PE3_MP_TXP<7>   @BASEBOARD_FAB2_LIB.BASEBOARD_FAB2(SCH_1):P3E_CPU1_PE3_MP_TXP<7>
  C1F2     2      B  CAP_0402    I162
  U2D1   DP7  PE3_TX_DP<7>  SKX_EXT_B_BGA1  I84

P3E_CPU1_PE3_MP_TXP<8>   @BASEBOARD_FAB2_LIB.BASEBOARD_FAB2(SCH_1):P3E_CPU1_PE3_MP_TXP<8>
  C9N17    2      B  CAP_0402    I12
  U2D1   DN6  PE3_TX_DP<8>  SKX_EXT_B_BGA1  I84

P3E_CPU1_PE3_MP_TXP<9>   @BASEBOARD_FAB2_LIB.BASEBOARD_FAB2(SCH_1):P3E_CPU1_PE3_MP_TXP<9>
  C9N12    2      B  CAP_0402    I16
  U2D1   DM5  PE3_TX_DP<9>  SKX_EXT_B_BGA1  I84

P3E_CPU1_PE3_MP_TXP<10>   @BASEBOARD_FAB2_LIB.BASEBOARD_FAB2(SCH_1):P3E_CPU1_PE3_MP_TXP<10>
  C9N1     2      B  CAP_0402    I14
  U2D1   DK5  PE3_TX_DP<10>  SKX_EXT_B_BGA1  I84

P3E_CPU1_PE3_MP_TXP<11>   @BASEBOARD_FAB2_LIB.BASEBOARD_FAB2(SCH_1):P3E_CPU1_PE3_MP_TXP<11>
  C9N4     2      B  CAP_0402    I55
  U2D1   DH5  PE3_TX_DP<11>  SKX_EXT_B_BGA1  I84

P3E_CPU1_PE3_MP_TXP<12>   @BASEBOARD_FAB2_LIB.BASEBOARD_FAB2(SCH_1):P3E_CPU1_PE3_MP_TXP<12>
  C9N14    2      B  CAP_0402    I56
  U2D1   DG6  PE3_TX_DP<12>  SKX_EXT_B_BGA1  I84

P3E_CPU1_PE3_MP_TXP<13>   @BASEBOARD_FAB2_LIB.BASEBOARD_FAB2(SCH_1):P3E_CPU1_PE3_MP_TXP<13>
  C9N5     2      B  CAP_0402    I83
  U2D1   DC6  PE3_TX_DP<13>  SKX_EXT_B_BGA1  I84

P3E_CPU1_PE3_MP_TXP<14>   @BASEBOARD_FAB2_LIB.BASEBOARD_FAB2(SCH_1):P3E_CPU1_PE3_MP_TXP<14>
  C9N10    2      B  CAP_0402    I53
  U2D1   DA4  PE3_TX_DP<14>  SKX_EXT_B_BGA1  I84

P3E_CPU1_PE3_MP_TXP<15>   @BASEBOARD_FAB2_LIB.BASEBOARD_FAB2(SCH_1):P3E_CPU1_PE3_MP_TXP<15>
  C9N7     2      B  CAP_0402    I54
  U2D1   CV5  PE3_TX_DP<15>  SKX_EXT_B_BGA1  I84

P3E_OCP_CPU0_PE3_C_TXN<0>   @BASEBOARD_FAB2_LIB.BASEBOARD_FAB2(SCH_1):P3E_OCP_CPU0_PE3_C_TXN<0>
  C1R1     2      B  CAP_0402    I29
  J8E3    68   IO68  SCONN80_E67482007_SM  I119

P3E_OCP_CPU0_PE3_C_TXN<1>   @BASEBOARD_FAB2_LIB.BASEBOARD_FAB2(SCH_1):P3E_OCP_CPU0_PE3_C_TXN<1>
  C1R3     2      B  CAP_0402    I37
  J8E3    60   IO60  SCONN80_E67482007_SM  I119

P3E_OCP_CPU0_PE3_C_TXN<2>   @BASEBOARD_FAB2_LIB.BASEBOARD_FAB2(SCH_1):P3E_OCP_CPU0_PE3_C_TXN<2>
  C1R5     2      B  CAP_0402    I59
  J8E3    52   IO52  SCONN80_E67482007_SM  I119

P3E_OCP_CPU0_PE3_C_TXN<3>   @BASEBOARD_FAB2_LIB.BASEBOARD_FAB2(SCH_1):P3E_OCP_CPU0_PE3_C_TXN<3>
  C1R7     2      B  CAP_0402    I70
  J8E3    44   IO44  SCONN80_E67482007_SM  I119

P3E_OCP_CPU0_PE3_C_TXN<4>   @BASEBOARD_FAB2_LIB.BASEBOARD_FAB2(SCH_1):P3E_OCP_CPU0_PE3_C_TXN<4>
  C1R9     2      B  CAP_0402    I134
  J8E3    36   IO36  SCONN80_E67482007_SM  I119

P3E_OCP_CPU0_PE3_C_TXN<5>   @BASEBOARD_FAB2_LIB.BASEBOARD_FAB2(SCH_1):P3E_OCP_CPU0_PE3_C_TXN<5>
  C2R13    2      B  CAP_0402    I137
  J8E3    28   IO28  SCONN80_E67482007_SM  I119

P3E_OCP_CPU0_PE3_C_TXN<6>   @BASEBOARD_FAB2_LIB.BASEBOARD_FAB2(SCH_1):P3E_OCP_CPU0_PE3_C_TXN<6>
  C2R7     2      B  CAP_0402    I123
  J8E3    20   IO20  SCONN80_E67482007_SM  I119

P3E_OCP_CPU0_PE3_C_TXN<7>   @BASEBOARD_FAB2_LIB.BASEBOARD_FAB2(SCH_1):P3E_OCP_CPU0_PE3_C_TXN<7>
  C2R9     2      B  CAP_0402    I147
  J8E3    12   IO12  SCONN80_E67482007_SM  I119

P3E_OCP_CPU0_PE3_C_TXN<8>   @BASEBOARD_FAB2_LIB.BASEBOARD_FAB2(SCH_1):P3E_OCP_CPU0_PE3_C_TXN<8>
  C2M15    2      B  CAP_0402    I86
  J9B3   114  IO114  SCONN120_A28699018_SM  I336

P3E_OCP_CPU0_PE3_C_TXN<9>   @BASEBOARD_FAB2_LIB.BASEBOARD_FAB2(SCH_1):P3E_OCP_CPU0_PE3_C_TXN<9>
  C1M19    2      B  CAP_0402    I90
  J9B3   106  IO106  SCONN120_A28699018_SM  I336

P3E_OCP_CPU0_PE3_C_TXN<10>   @BASEBOARD_FAB2_LIB.BASEBOARD_FAB2(SCH_1):P3E_OCP_CPU0_PE3_C_TXN<10>
  C1M17    2      B  CAP_0402    I92
  J9B3    98   IO98  SCONN120_A28699018_SM  I336

P3E_OCP_CPU0_PE3_C_TXN<11>   @BASEBOARD_FAB2_LIB.BASEBOARD_FAB2(SCH_1):P3E_OCP_CPU0_PE3_C_TXN<11>
  C1M15    2      B  CAP_0402    I95
  J9B3    90   IO90  SCONN120_A28699018_SM  I336

P3E_OCP_CPU0_PE3_C_TXN<12>   @BASEBOARD_FAB2_LIB.BASEBOARD_FAB2(SCH_1):P3E_OCP_CPU0_PE3_C_TXN<12>
  C1M13    2      B  CAP_0402    I111
  J9B3    82   IO82  SCONN120_A28699018_SM  I336

P3E_OCP_CPU0_PE3_C_TXN<13>   @BASEBOARD_FAB2_LIB.BASEBOARD_FAB2(SCH_1):P3E_OCP_CPU0_PE3_C_TXN<13>
  C1M11    2      B  CAP_0402    I117
  J9B3    74   IO74  SCONN120_A28699018_SM  I336

P3E_OCP_CPU0_PE3_C_TXN<14>   @BASEBOARD_FAB2_LIB.BASEBOARD_FAB2(SCH_1):P3E_OCP_CPU0_PE3_C_TXN<14>
  C1M9     2      B  CAP_0402    I114
  J9B3    66   IO66  SCONN120_A28699018_SM  I336

P3E_OCP_CPU0_PE3_C_TXN<15>   @BASEBOARD_FAB2_LIB.BASEBOARD_FAB2(SCH_1):P3E_OCP_CPU0_PE3_C_TXN<15>
  C1M7     2      B  CAP_0402    I122
  J9B3    58   IO58  SCONN120_A28699018_SM  I336

P3E_OCP_CPU0_PE3_C_TXP<0>   @BASEBOARD_FAB2_LIB.BASEBOARD_FAB2(SCH_1):P3E_OCP_CPU0_PE3_C_TXP<0>
  C1R2     2      B  CAP_0402    I10
  J8E3    66   IO66  SCONN80_E67482007_SM  I119

P3E_OCP_CPU0_PE3_C_TXP<1>   @BASEBOARD_FAB2_LIB.BASEBOARD_FAB2(SCH_1):P3E_OCP_CPU0_PE3_C_TXP<1>
  C1R4     2      B  CAP_0402    I26
  J8E3    58   IO58  SCONN80_E67482007_SM  I119

P3E_OCP_CPU0_PE3_C_TXP<2>   @BASEBOARD_FAB2_LIB.BASEBOARD_FAB2(SCH_1):P3E_OCP_CPU0_PE3_C_TXP<2>
  C1R6     2      B  CAP_0402    I40
  J8E3    50   IO50  SCONN80_E67482007_SM  I119

P3E_OCP_CPU0_PE3_C_TXP<3>   @BASEBOARD_FAB2_LIB.BASEBOARD_FAB2(SCH_1):P3E_OCP_CPU0_PE3_C_TXP<3>
  C1R8     2      B  CAP_0402    I55
  J8E3    42   IO42  SCONN80_E67482007_SM  I119

P3E_OCP_CPU0_PE3_C_TXP<4>   @BASEBOARD_FAB2_LIB.BASEBOARD_FAB2(SCH_1):P3E_OCP_CPU0_PE3_C_TXP<4>
  C1R10    2      B  CAP_0402    I128
  J8E3    34   IO34  SCONN80_E67482007_SM  I119

P3E_OCP_CPU0_PE3_C_TXP<5>   @BASEBOARD_FAB2_LIB.BASEBOARD_FAB2(SCH_1):P3E_OCP_CPU0_PE3_C_TXP<5>
  C2R14    2      B  CAP_0402    I130
  J8E3    26   IO26  SCONN80_E67482007_SM  I119

P3E_OCP_CPU0_PE3_C_TXP<6>   @BASEBOARD_FAB2_LIB.BASEBOARD_FAB2(SCH_1):P3E_OCP_CPU0_PE3_C_TXP<6>
  C2R8     2      B  CAP_0402    I141
  J8E3    18   IO18  SCONN80_E67482007_SM  I119

P3E_OCP_CPU0_PE3_C_TXP<7>   @BASEBOARD_FAB2_LIB.BASEBOARD_FAB2(SCH_1):P3E_OCP_CPU0_PE3_C_TXP<7>
  C2R10    2      B  CAP_0402    I142
  J8E3    10   IO10  SCONN80_E67482007_SM  I119

P3E_OCP_CPU0_PE3_C_TXP<8>   @BASEBOARD_FAB2_LIB.BASEBOARD_FAB2(SCH_1):P3E_OCP_CPU0_PE3_C_TXP<8>
  C2M14    2      B  CAP_0402    I76
  J9B3   112  IO112  SCONN120_A28699018_SM  I336

P3E_OCP_CPU0_PE3_C_TXP<9>   @BASEBOARD_FAB2_LIB.BASEBOARD_FAB2(SCH_1):P3E_OCP_CPU0_PE3_C_TXP<9>
  C1M18    2      B  CAP_0402    I78
  J9B3   104  IO104  SCONN120_A28699018_SM  I336

P3E_OCP_CPU0_PE3_C_TXP<10>   @BASEBOARD_FAB2_LIB.BASEBOARD_FAB2(SCH_1):P3E_OCP_CPU0_PE3_C_TXP<10>
  C1M16    2      B  CAP_0402    I82
  J9B3    96   IO96  SCONN120_A28699018_SM  I336

P3E_OCP_CPU0_PE3_C_TXP<11>   @BASEBOARD_FAB2_LIB.BASEBOARD_FAB2(SCH_1):P3E_OCP_CPU0_PE3_C_TXP<11>
  C1M14    2      B  CAP_0402    I85
  J9B3    88   IO88  SCONN120_A28699018_SM  I336

P3E_OCP_CPU0_PE3_C_TXP<12>   @BASEBOARD_FAB2_LIB.BASEBOARD_FAB2(SCH_1):P3E_OCP_CPU0_PE3_C_TXP<12>
  C1M12    2      B  CAP_0402    I100
  J9B3    80   IO80  SCONN120_A28699018_SM  I336

P3E_OCP_CPU0_PE3_C_TXP<13>   @BASEBOARD_FAB2_LIB.BASEBOARD_FAB2(SCH_1):P3E_OCP_CPU0_PE3_C_TXP<13>
  C1M10    2      B  CAP_0402    I102
  J9B3    72   IO72  SCONN120_A28699018_SM  I336

P3E_OCP_CPU0_PE3_C_TXP<14>   @BASEBOARD_FAB2_LIB.BASEBOARD_FAB2(SCH_1):P3E_OCP_CPU0_PE3_C_TXP<14>
  C1M8     2      B  CAP_0402    I105
  J9B3    64   IO64  SCONN120_A28699018_SM  I336

P3E_OCP_CPU0_PE3_C_TXP<15>   @BASEBOARD_FAB2_LIB.BASEBOARD_FAB2(SCH_1):P3E_OCP_CPU0_PE3_C_TXP<15>
  C1M6     2      B  CAP_0402    I109
  J9B3    56   IO56  SCONN120_A28699018_SM  I336

P3E_PCH_M2_RX_DN<1>   @BASEBOARD_FAB2_LIB.BASEBOARD_FAB2(SCH_1):P3E_PCH_M2_RX_DN<1>
  J8F1    29  PERN1  SCONN75K_H17033002_SMT1  I53
  U7C1   AY72  USB3_8_PCIE1_RXN  LBG_CORE_QAT_EXT_D  I220

P3E_PCH_M2_RX_DN<2>   @BASEBOARD_FAB2_LIB.BASEBOARD_FAB2(SCH_1):P3E_PCH_M2_RX_DN<2>
  J8F1    17  PERN2  SCONN75K_H17033002_SMT1  I53
  U7C1   AW71  USB3_9_PCIE2_RXN  LBG_CORE_QAT_EXT_D  I220

P3E_PCH_M2_RX_DN<3>   @BASEBOARD_FAB2_LIB.BASEBOARD_FAB2(SCH_1):P3E_PCH_M2_RX_DN<3>
  J8F1     5  PERN3  SCONN75K_H17033002_SMT1  I53
  U7C1   AV72  USB3_10_PCIE3_GBE_RXN  LBG_CORE_QAT_EXT_D  I220

P3E_PCH_M2_RX_DP<1>   @BASEBOARD_FAB2_LIB.BASEBOARD_FAB2(SCH_1):P3E_PCH_M2_RX_DP<1>
  J8F1    31  PERP1  SCONN75K_H17033002_SMT1  I53
  U7C1   AY70  USB3_8_PCIE1_RXP  LBG_CORE_QAT_EXT_D  I220

P3E_PCH_M2_RX_DP<2>   @BASEBOARD_FAB2_LIB.BASEBOARD_FAB2(SCH_1):P3E_PCH_M2_RX_DP<2>
  J8F1    19  PERP2  SCONN75K_H17033002_SMT1  I53
  U7C1   AW69  USB3_9_PCIE2_RXP  LBG_CORE_QAT_EXT_D  I220

P3E_PCH_M2_RX_DP<3>   @BASEBOARD_FAB2_LIB.BASEBOARD_FAB2(SCH_1):P3E_PCH_M2_RX_DP<3>
  J8F1     7  PERP3  SCONN75K_H17033002_SMT1  I53
  U7C1   AV70  USB3_10_PCIE3_GBE_RXP  LBG_CORE_QAT_EXT_D  I220

P3E_PCH_M2_SATA6G_RX_R_DN   @BASEBOARD_FAB2_LIB.BASEBOARD_FAB2(SCH_1):P3E_PCH_M2_SATA6G_RX_R_DN
  C8F15    2      B  CAP_A       I90
  J8F1    43  PERP0_SATA_BN  SCONN75K_H17033002_SMT1  I53
  R8F21    2      B  RES         I106

P3E_PCH_M2_SATA6G_RX_R_DP   @BASEBOARD_FAB2_LIB.BASEBOARD_FAB2(SCH_1):P3E_PCH_M2_SATA6G_RX_R_DP
  C8F13    2      B  CAP_A       I99
  J8F1    41  PERN0_SATA_BP  SCONN75K_H17033002_SMT1  I53
  R8F18    2      B  RES         I105

P3E_PCH_M2_SATA6G_TX_R_DN   @BASEBOARD_FAB2_LIB.BASEBOARD_FAB2(SCH_1):P3E_PCH_M2_SATA6G_TX_R_DN
  C8F11    2      B  CAP_A       I97
  C8F12    2      B  CAP_0402    I98
  J8F1    47  PETN0_SATA_AN  SCONN75K_H17033002_SMT1  I53

P3E_PCH_M2_SATA6G_TX_R_DP   @BASEBOARD_FAB2_LIB.BASEBOARD_FAB2(SCH_1):P3E_PCH_M2_SATA6G_TX_R_DP
  C8F6     2      B  CAP_A       I95
  C8F7     2      B  CAP_0402    I96
  J8F1    49  PETP0_SATA_AP  SCONN75K_H17033002_SMT1  I53

P3E_PCH_M2_TX_C_DN<1>   @BASEBOARD_FAB2_LIB.BASEBOARD_FAB2(SCH_1):P3E_PCH_M2_TX_C_DN<1>
  C2T11    1      A  CAP_0402    I62
  J8F1    35  PETN1  SCONN75K_H17033002_SMT1  I53

P3E_PCH_M2_TX_C_DN<2>   @BASEBOARD_FAB2_LIB.BASEBOARD_FAB2(SCH_1):P3E_PCH_M2_TX_C_DN<2>
  C2T14    1      A  CAP_0402    I65
  J8F1    23  PETN2  SCONN75K_H17033002_SMT1  I53

P3E_PCH_M2_TX_C_DN<3>   @BASEBOARD_FAB2_LIB.BASEBOARD_FAB2(SCH_1):P3E_PCH_M2_TX_C_DN<3>
  C2T23    1      A  CAP_0402    I67
  J8F1    11  PETN3  SCONN75K_H17033002_SMT1  I53

P3E_PCH_M2_TX_C_DP<1>   @BASEBOARD_FAB2_LIB.BASEBOARD_FAB2(SCH_1):P3E_PCH_M2_TX_C_DP<1>
  C2T10    1      A  CAP_0402    I63
  J8F1    37  PETP1  SCONN75K_H17033002_SMT1  I53

P3E_PCH_M2_TX_C_DP<2>   @BASEBOARD_FAB2_LIB.BASEBOARD_FAB2(SCH_1):P3E_PCH_M2_TX_C_DP<2>
  C2T13    1      A  CAP_0402    I64
  J8F1    25  PETP2  SCONN75K_H17033002_SMT1  I53

P3E_PCH_M2_TX_C_DP<3>   @BASEBOARD_FAB2_LIB.BASEBOARD_FAB2(SCH_1):P3E_PCH_M2_TX_C_DP<3>
  C2T20    1      A  CAP_0402    I66
  J8F1    13  PETP3  SCONN75K_H17033002_SMT1  I53

P3E_PCH_M2_TX_DN<1>   @BASEBOARD_FAB2_LIB.BASEBOARD_FAB2(SCH_1):P3E_PCH_M2_TX_DN<1>
  C2T11    2      B  CAP_0402    I62
  U7C1   BM65  USB3_8_PCIE1_TXN  LBG_CORE_QAT_EXT_D  I220

P3E_PCH_M2_TX_DN<2>   @BASEBOARD_FAB2_LIB.BASEBOARD_FAB2(SCH_1):P3E_PCH_M2_TX_DN<2>
  C2T14    2      B  CAP_0402    I65
  U7C1   BK65  USB3_9_PCIE2_TXN  LBG_CORE_QAT_EXT_D  I220

P3E_PCH_M2_TX_DN<3>   @BASEBOARD_FAB2_LIB.BASEBOARD_FAB2(SCH_1):P3E_PCH_M2_TX_DN<3>
  C2T23    2      B  CAP_0402    I67
  U7C1   BH61  USB3_10_PCIE3_GBE_TXN  LBG_CORE_QAT_EXT_D  I220

P3E_PCH_M2_TX_DP<1>   @BASEBOARD_FAB2_LIB.BASEBOARD_FAB2(SCH_1):P3E_PCH_M2_TX_DP<1>
  C2T10    2      B  CAP_0402    I63
  U7C1   BR65  USB3_8_PCIE1_TXP  LBG_CORE_QAT_EXT_D  I220

P3E_PCH_M2_TX_DP<2>   @BASEBOARD_FAB2_LIB.BASEBOARD_FAB2(SCH_1):P3E_PCH_M2_TX_DP<2>
  C2T13    2      B  CAP_0402    I64
  U7C1   BL66  USB3_9_PCIE2_TXP  LBG_CORE_QAT_EXT_D  I220

P3E_PCH_M2_TX_DP<3>   @BASEBOARD_FAB2_LIB.BASEBOARD_FAB2(SCH_1):P3E_PCH_M2_TX_DP<3>
  C2T20    2      B  CAP_0402    I66
  U7C1   BK61  USB3_10_PCIE3_GBE_TXP  LBG_CORE_QAT_EXT_D  I220

P3E_PCH_RX_0_DN   @BASEBOARD_FAB2_LIB.BASEBOARD_FAB2(SCH_1):P3E_PCH_RX_0_DN
  R8F21    1      A  RES         I106
  U7C1   BA71  USB3_7_PCIE0_RXN  LBG_CORE_QAT_EXT_D  I220

P3E_PCH_RX_0_DP   @BASEBOARD_FAB2_LIB.BASEBOARD_FAB2(SCH_1):P3E_PCH_RX_0_DP
  R8F18    1      A  RES         I105
  U7C1   BA69  USB3_7_PCIE0_RXP  LBG_CORE_QAT_EXT_D  I220

P3E_PCH_TX_0_DN   @BASEBOARD_FAB2_LIB.BASEBOARD_FAB2(SCH_1):P3E_PCH_TX_0_DN
  C8F12    1      A  CAP_0402    I98
  U7C1   BR61  USB3_7_PCIE0_TXN  LBG_CORE_QAT_EXT_D  I220

P3E_PCH_TX_0_DP   @BASEBOARD_FAB2_LIB.BASEBOARD_FAB2(SCH_1):P3E_PCH_TX_0_DP
  C8F7     1      A  CAP_0402    I96
  U7C1   BN63  USB3_7_PCIE0_TXP  LBG_CORE_QAT_EXT_D  I220

P3V3            @BASEBOARD_FAB2_LIB.BASEBOARD_FAB2(SCH_1):P3V3
  C1L16    1      A  CAP_A       I81
  C1M3     1      A  CAP_A       I20
  C1M21    1      A  CAP_A       I334
  C1M24    1      A  CAP_A       I10
  C1U19    1      A  CAP_0402    I18
  C2T2     1      A  CAP_A       I131
  C2T4     1      A  CAP_A       I132
  C2T5     1      A  CAP_A       I135
  C2T15    1      A  CAP_A       I127
  C2T16    1      A  CAP_A       I126
  C2T21    1      A  CAP_A       I124
  C2T24    1      A  CAP_A       I129
  C2T26    1      A  CAP_A       I123
  C2T29    1      A  CAP_A       I120
  C2T33    1      A  CAP_A       I72
  C2U2     1      A  CAP         I47
  C2U19    1      A  CAP_A       I46
  C2U21    1      A  CAP_A        I5
  C2U25    1      A  CAP_A        I7
  C3F2     1      A  CAP_A       I34
  C3P50    1      A  CAP_0402    I84
  C6F1     1      A  CAP_A       I25
  C7D4     1      A  CAP_0402    I79
  EU2T1    6      S  SLG55021_SM   I1
  FB6P1    1      A  FERRITE      I8
  J4B2    D1   IOD1  SCONN120_H61426002_SM  I46
  J6B1    D1   IOD1  SCONN120_H61426002_SM  I56
  J8B1    18   IO18  SCONN24_H46321001_SM   I1
  J8B1    20   IO20  SCONN24_H46321001_SM   I1
  J8F1     2  3_3V<0>  SCONN75K_H17033002_SMT1  I53
  J8F1     4  3_3V<1>  SCONN75K_H17033002_SMT1  I53
  J8F1    12  3_3V<2>  SCONN75K_H17033002_SMT1  I53
  J8F1    14  3_3V<3>  SCONN75K_H17033002_SMT1  I53
  J8F1    16  3_3V<4>  SCONN75K_H17033002_SMT1  I53
  J8F1    18  3_3V<5>  SCONN75K_H17033002_SMT1  I53
  J8F1    70  3_3V<6>  SCONN75K_H17033002_SMT1  I53
  J8F1    72  3_3V<7>  SCONN75K_H17033002_SMT1  I53
  J8F1    74  3_3V<8>  SCONN75K_H17033002_SMT1  I53
  J8G1    21   IO21  SCONN200_H68296001_SM  I258
  J8G1    22   IO22  SCONN200_H68296001_SM  I258
  J8G1    23   IO23  SCONN200_H68296001_SM  I258
  J8G1    24   IO24  SCONN200_H68296001_SM  I258
  J9B3    18   IO18  SCONN120_A28699018_SM  I336
  J9B3    19   IO19  SCONN120_A28699018_SM  I336
  J9B3    20   IO20  SCONN120_A28699018_SM  I336
  J9B3    21   IO21  SCONN120_A28699018_SM  I336
  J9B3    22   IO22  SCONN120_A28699018_SM  I336
  J9B3    23   IO23  SCONN120_A28699018_SM  I336
  J9B3    24   IO24  SCONN120_A28699018_SM  I336
  J9B3    25   IO25  SCONN120_A28699018_SM  I336
  Q8G1     1    SRC  MOSFET_N_LCC3  I85
  Q9A1     3   C<0>  NPN_DUAL    I94
  R1L1     1      A  RES         I25
  R1L21    1      A  RES         I43
  R1M11    1      A  RES          I9
  R1M12    1      A  RES          I8
  R1U26    1      A  RES         I148
  R2L21    1      A  RES         I263
  R2L23    1      A  RES         I261
  R2N27    1      A  RES         I97
  R2P15    1      A  RES         I111
  R3R4     1      A  RES         I66
  R3R10    1      A  RES         I79
  R4A5     1      A  RES         I17
  R4D69    1      A  RES         I93
  R4D70    1      A  RES         I94
  R4G17    1      A  RES         I14
  R4G18    1      A  RES         I45
  R6L4     1      A  RES         I37
  R6L5     1      A  RES         I37
  R6L8     1      A  RES         I30
  R6L9     1      A  RES         I19
  R6L11    1      A  RES         I30
  R6M4     1      A  RES         I82
  R6P48    1      A  RES         I91
  R6U3     1      A  RES         I34
  R6U4     1      A  RES         I28
  R6U7     1      A  RES         I32
  R6U15    1      A  RES         I37
  R7E7     1      A  RES         I106
  R7E10    1      A  RES         I62
  R7E11    1      A  RES         I72
  R7E21    1      A  RES         I343
  R7G7     1      A  RES         I51
  R8F36    1      A  RES         I136
  R9A1     1      A  RES         I95
  U1L3     3    VCC  ADM809      I80
  U2T4    14    VCC  GTL2014_SM  I30
  U3P2    14    VCC  GTL2014_SM   I1
  U7D2    14    VCC  GTL2014_SM  I32
  U9G1    14    VCC  GTL2014_SM   I1
  Y3F1     6    VCC  OSC_C_6P10  I72
  Y6F1     6    VCC  OSC_C_6P10  I71

P3V3_DB1200     @BASEBOARD_FAB2_LIB.BASEBOARD_FAB2(SCH_1):P3V3_DB1200
  C3D22    1      A  CAP         I10
  C6P4     1      A  CAP_A       I11
  C6P5     1      A  CAP_A       I14
  C6P6     1      A  CAP_A       I12
  C6P9     1      A  CAP_A       I79
  C6P10    1      A  CAP_A       I13
  C6P11    1      A  CAP_A       I16
  C6P12    1      A  CAP_A       I15
  EU4D2   24  VDD<0>  NB3W1200L_LCC   I1
  EU4D2   25  VDDIO<0>  NB3W1200L_LCC   I1
  EU4D2   32  VDDIO<1>  NB3W1200L_LCC   I1
  EU4D2   40  VDD<1>  NB3W1200L_LCC   I1
  EU4D2   49  VDDIO<2>  NB3W1200L_LCC   I1
  EU4D2   56  VDDIO<3>  NB3W1200L_LCC   I1
  EU4D2   57  VDD<2>  NB3W1200L_LCC   I1
  FB6P1    2      B  FERRITE      I8
  R3D14    1      A  RES         I21
  R4D35    1      A  RES         I38
  R4D38    1      A  RES         I37
  R4D40    1      A  RES         I45
  R4D41    1      A  RES         I53
  R6P25    1      A  RES         I26

P3V3_DB1200_A   @BASEBOARD_FAB2_LIB.BASEBOARD_FAB2(SCH_1):P3V3_DB1200_A
  C4D23    1      A  CAP_A       I19
  C4D24    1      A  CAP_A       I18
  EU4D2    1   VDDA  NB3W1200L_LCC   I1
  R3D14    2      B  RES         I21

P3V3_DB1200_R   @BASEBOARD_FAB2_LIB.BASEBOARD_FAB2(SCH_1):P3V3_DB1200_R
  C4D22    1      A  CAP_A       I28
  C4D27    1      A  CAP_A       I30
  EU4D2    8   VDDR  NB3W1200L_LCC   I1
  R6P25    2      B  RES         I26

P3V3_FB_ADC128_VCC   @BASEBOARD_FAB2_LIB.BASEBOARD_FAB2(SCH_1):P3V3_FB_ADC128_VCC
  C1U20    1      A  CAP         I67
  C9G19    1      A  CAP_A       I61
  EU9G1    5     VP  ADC128D818_SM  I52
  FB1U2    2      B  FERRITE     I79

P3V3_RTC_STBY   @BASEBOARD_FAB2_LIB.BASEBOARD_FAB2(SCH_1):P3V3_RTC_STBY
  C2U26    1      A  CAP_A       I102
  CR2U1    3      C  DIODE2A_DUAL  I53
  R3N4     1      A  RES         I19
  R7C10    1      A  RES         I13
  U7C1   AJ27  VCCPRTC  LBG_CORE_QAT_EXT_D  I63

P3V3_STBY       @BASEBOARD_FAB2_LIB.BASEBOARD_FAB2(SCH_1):P3V3_STBY
  C1E22    1      A  CAP_A       I113
  C1L1     1      A  CAP_0402    I136
  C1L9     1      A  CAP_A       I38
  C1L11    1      A  CAP_A       I87
  C1L17    1      A  CAP_A       I37
  C1L19    1      A  CAP_0402    I140
  C1L20    1      A  CAP_A       I267
  C1M20    1      A  CAP_A       I270
  C1M25    1      A  CAP_A       I335
  C1M28    1      A  CAP_A       I119
  C1M30    1      A  CAP_A       I131
  C1M31    1      A  CAP_A       I116
  C1M32    1      A  CAP_A       I117
  C1M34    1      A  CAP_A       I265
  C1M35    1      A  CAP_A       I266
  C1M36    1      A  CAP_A       I42
  C1M37    1      A  CAP_A       I47
  C1R13    1      A  CAP         I142
  C1R14    1      A  CAP_A       I145
  C1R20    1      A  CAP_A       I143
  C1R21    1      A  CAP_A       I146
  C1R22    1      A  CAP         I136
  C1R25    1      A  CAP_A        I3
  C1R27    1      A  CAP_A       I30
  C1R28    1      A  CAP_A       I49
  C1T3     1      A  CAP_A       I144
  C1T7     1      A  CAP         I22
  C1T8     1      A  CAP_A       I44
  C1T9     1      A  CAP         I75
  C1T10    1      A  CAP_A       I70
  C1T11    1      A  CAP_A       I97
  C1T12    1      A  CAP_A        I8
  C1T13    1      A  CAP         I74
  C1T14    1      A  CAP_A       I49
  C1T22    1      A  CAP_A       I43
  C1T25    1      A  CAP_A       I42
  C1T26    1      A  CAP_A       I46
  C1T29    1      A  CAP_A        I5
  C1T30    1      A  CAP_A        I6
  C1T38    1      A  CAP_A       I22
  C1T43    1      A  CAP_A       I20
  C1T44    1      A  CAP         I25
  C1T45    1      A  CAP_A       I21
  C1T47    1      A  CAP_A       I24
  C1T50    1      A  CAP_A       I41
  C1T52    1      A  CAP_A        I1
  C1T56    1      A  CAP_A       I184
  C1U2     1      A  CAP         I26
  C1U3     1      A  CAP_A        I4
  C1U4     1      A  CAP_A       I18
  C1U5     1      A  CAP_A       I17
  C1U8     1      A  CAP_A       I19
  C1U9     1      A  CAP_A       I23
  C1U11    1      A  CAP_A       I25
  C2M16    1      A  CAP_A       I37
  C2N14    1      A  CAP         I25
  C2N17    1      A  CAP         I28
  C2N18    1      A  CAP_A       I29
  C2N19    1      A  CAP_A        I7
  C2N20    1      A  CAP_A       I12
  C2N21    1      A  CAP         I15
  C2N22    1      A  CAP          I9
  C2N23    1      A  CAP         I24
  C2N24    1      A  CAP          I8
  C2N25    1      A  CAP_A       I34
  C2N26    1      A  CAP_A        I4
  C2P1     1      A  CAP_A        I8
  C2P2     1      A  CAP_A        I9
  C2P3     1      A  CAP_A       I22
  C2P4     1      A  CAP_A       I16
  C2P5     1      A  CAP_A        I3
  C2P6     1      A  CAP_A       I18
  C2P7     1      A  CAP_A       I20
  C2P8     1      A  CAP_A        I1
  C2P9     1      A  CAP_A       I117
  C2R1     1      A  CAP_A        I8
  C2R2     1      A  CAP_A       I28
  C2R3     1      A  CAP_A       I19
  C2R4     1      A  CAP_A       I21
  C2R5     1      A  CAP_A       I15
  C2T1     1      A  CAP_A       I94
  C2T3     1      A  CAP_A       I370
  C2T6     1      A  CAP         I160
  C2T7     1      A  CAP         I158
  C2T8     1      A  CAP_A       I135
  C2T9     1      A  CAP         I174
  C2T12    1      A  CAP_A       I132
  C2T28    1      A  CAP_A       I116
  C2T35    1      A  CAP_A       I273
  C2T36    1      A  CAP_A       I43
  C2U1     1      A  CAP         I44
  C2U22    1      A  CAP_A       I318
  C2U23    1      A  CAP_A       I315
  C2U27    1      A  CAP_A       I90
  C2U28    1      A  CAP_A       I93
  C3N23    1      A  CAP_A       I42
  C3P42    1      A  CAP_A       I73
  C3P43    1      A  CAP_A        I6
  C3P44    1      A  CAP_A       I23
  C3P46    1      A  CAP_A       I72
  C3P47    1      A  CAP_A       I12
  C3P48    1      A  CAP_A       I25
  C3P51    1      A  CAP_A       I11
  C3P52    1      A  CAP_A       I17
  C3R1     1      A  CAP_A        I4
  C3R2     1      A  CAP_A       I10
  C3R3     1      A  CAP_A        I7
  C3T4     1      A  CAP_A       I138
  C3T5     1      A  CAP_A       I136
  C4C3     1      A  CAP_A       I75
  C7D1     1      A  CAP_A       I136
  C7D2     1      A  CAP          I2
  C7E3     1      A  CAP_A       I92
  C7E4     1      A  CAP_A       I115
  C7F1     1      A  CAP_A       I131
  C7F2     1      A  CAP_A       I130
  C8A4     1      A  CAP         I31
  C8A6     1      A  CAP         I29
  C8C3     1      A  CAP         I19
  C8C4     1      A  CAP         I20
  C8C5     1      A  CAP         I21
  C8C6     1      A  CAP         I22
  C8D1     1      A  CAP_A       I376
  C8D2     1      A  CAP_A       I33
  C8D4     1      A  CAP_A       I105
  C8E1     1      A  CAP_A       I253
  C8E2     1      A  CAP_A       I40
  C8E5     1      A  CAP_A       I20
  C8E8     1      A  CAP_A       I128
  C8E18    1      A  CAP_A       I14
  C8F4     1      A  CAP_A       I30
  C8F5     1      A  CAP_A       I28
  C8F8     1      A  CAPP        I155
  C8F14    1      A  CAPP        I154
  C8F16    1      A  CAP_A       I275
  C9A3     1      A  CAP_A       I40
  C9B7     1      A  CAP_A       I39
  C9E11    1      A  CAP_0402    I39
  C9F2     1      A  CAP         I140
  C9F5     1      A  CAP_A       I71
  C9F11    1      A  CAP_A       I90
  C9F19    1      A  CAP_A        I7
  C9F23    1      A  CAP_A       I258
  C9G2     1      A  CAP         I36
  C9G7     1      A  CAP_A       I33
  C9M7     1      A  CAP_A       I12
  C9P11    1      A  CAP_A       I201
  C9R13    1      A  CAP_A       I42
  C9R14    1      A  CAP_A       I41
  CR2U1    1     A1  DIODE2A_DUAL  I53
  CR3U1    2      A  DIODE_SMLF  I49
  EU2T1    5      D  SLG55021_SM   I1
  EU8A2    7  VIN<0>  RT9059_DFN  I86
  EU8A2    8  VIN<1>  RT9059_DFN  I86
  EU8A2    9  VIN<2>  RT9059_DFN  I86
  EU8A2   10    VDD  RT9059_DFN  I86
  EU9E1   10  VDD3P3<4>  SPRINGVILLE_SM1  I72
  EU9E1   27  VDD3P3<3>  SPRINGVILLE_SM1  I72
  EU9E1   41  VDD3P3<2>  SPRINGVILLE_SM1  I72
  EU9E1   64  VDD3P3<0>  SPRINGVILLE_SM1  I72
  EU9F1   10    VDD  RT9059_DFN  I40
  EU9F2    7  VIN<0>  RT9059_DFN  I70
  EU9F2    8  VIN<1>  RT9059_DFN  I70
  EU9F2    9  VIN<2>  RT9059_DFN  I70
  EU9F2   10    VDD  RT9059_DFN  I70
  EU9F3   29    VDD  PI7C9X1172_QFN   I1
  FB1T2    1      A  FERRITE     I122
  FB1U1    1      A  FERRITE     I140
  FB1U2    1      A  FERRITE     I79
  FB2T2    1      A  FERRITE     I114
  J1F3     1    IO1  CONN8_H62179001_PIP  I189
  J4B2   A11  IOA11  SCONN120_H61426002_SM  I46
  J4B2   B11  IOB11  SCONN120_H61426002_SM  I46
  J4B2   C11  IOC11  SCONN120_H61426002_SM  I46
  J6B1   A11  IOA11  SCONN120_H61426002_SM  I56
  J6B1   B11  IOB11  SCONN120_H61426002_SM  I56
  J6B1   C11  IOC11  SCONN120_H61426002_SM  I56
  J8E1     7    IO7  SCONN11_H67026001_SM  I87
  J8G1    25   IO25  SCONN200_H68296001_SM  I258
  J9B3    12   IO12  SCONN120_A28699018_SM  I336
  J9B3    13   IO13  SCONN120_A28699018_SM  I336
  JA9G1   L2     L2  CONN17_H71061002_PIP1  I109
  L8F1     2    INB  INDUCTOR    I173
  Q8G1     5    DRN  MOSFET_N_LCC3  I85
  R1B1     1      A  RES         I79
  R1B2     1      A  RES         I17
  R1B13    1      A  RES         I13
  R1B21    1      A  RES         I70
  R1B24    1      A  RES         I126
  R1C14    1      A  RES         I46
  R1C18    1      A  RES         I34
  R1C28    1      A  RES         I35
  R1C34    1      A  RES         I320
  R1C35    1      A  RES         I336
  R1D6     1      A  RES          I6
  R1D7     1      A  RES          I7
  R1D8     1      A  RES         I36
  R1D10    1      A  RES         I189
  R1D21    1      A  RES         I204
  R1D22    1      A  RES         I158
  R1D23    1      A  RES         I191
  R1D35    1      A  RES         I12
  R1D53    1      A  RES         I33
  R1E9     1      A  RES         I34
  R1E10    1      A  RES         I38
  R1E11    1      A  RES         I120
  R1F1     1      A  RES         I45
  R1G6     1      A  RES         I13
  R1G11    1      A  RES         I79
  R1G16    1      A  RES         I17
  R1L5     1      A  RES         I10
  R1L7     1      A  RES         I382
  R1L13    2      B  RES          I6
  R1L19    1      A  RES         I24
  R1L23    2      B  RES         I13
  R1L27    1      A  RES          I5
  R1L28    1      A  RES         I66
  R1L33    2      B  RES         I45
  R1L36    1      A  RES         I11
  R1L38    1      A  RES         I22
  R1L43    2      B  RES         I131
  R1L44    2      B  RES         I136
  R1M24    1      A  RES         I105
  R1R3     1      A  RES         I11
  R1R4     1      A  RES         I119
  R1R5     1      A  RES         I73
  R1R7     1      A  RES         I12
  R1R9     1      A  RES         I10
  R1R10    1      A  RES         I108
  R1R11    2      B  RES         I66
  R1R13    1      A  RES         I109
  R1R16    1      A  RES         I93
  R1R17    1      A  RES         I94
  R1R18    1      A  RES         I88
  R1R19    1      A  RES         I89
  R1R20    1      A  RES         I91
  R1R21    1      A  RES         I90
  R1R22    1      A  RES         I92
  R1R23    1      A  RES         I95
  R1T2     1      A  RES         I49
  R1T3     1      A  RES         I46
  R1T4     1      A  RES         I14
  R1T5     1      A  RES         I11
  R1T6     1      A  RES         I13
  R1T13    2      B  RES         I43
  R1T14    2      B  RES         I54
  R1T16    2      B  RES         I61
  R1T17    2      B  RES         I112
  R1T18    2      B  RES         I48
  R1T19    2      B  RES         I57
  R1T20    2      B  RES         I49
  R1T21    2      B  RES         I53
  R1T22    2      B  RES         I50
  R1T34    1      A  RES         I239
  R1U21    1      A  RES         I24
  R1U22    1      A  RES         I27
  R1U23    1      A  RES         I28
  R1U24    1      A  RES         I25
  R1U39    1      A  RES         I88
  R1U49    1      A  RES         I163
  R1U52    1      A  RES         I557
  R2L4     1      A  RES         I18
  R2L5     1      A  RES         I20
  R2L6     1      A  RES         I17
  R2L11    1      A  RES         I13
  R2L12    1      A  RES          I2
  R2L14    1      A  RES         I159
  R2L15    1      A  RES         I12
  R2L24    1      A  RES         I148
  R2L25    1      A  RES         I235
  R2L26    1      A  RES         I236
  R2M2     1      A  RES         I346
  R2M4     1      A  RES         I284
  R2M5     1      A  RES         I348
  R2M8     1      A  RES         I349
  R2N5     1      A  RES         I90
  R2N6     1      A  RES         I128
  R2N7     1      A  RES         I309
  R2N8     1      A  RES         I89
  R2N9     1      A  RES         I267
  R2N10    1      A  RES         I10
  R2N14    1      A  RES         I83
  R2N16    1      A  RES         I247
  R2N17    1      A  RES         I29
  R2N23    1      A  RES         I112
  R2N28    1      A  RES         I147
  R2N29    1      A  RES         I352
  R2N32    1      A  RES         I341
  R2P3     1      A  RES          I2
  R2P5     1      A  RES         I56
  R2P8     1      A  RES         I52
  R2P13    1      A  RES         I61
  R2P16    1      A  RES         I113
  R2P17    1      A  RES          I3
  R2P18    1      A  RES         I121
  R2P19    1      A  RES         I107
  R2P21    1      A  RES         I122
  R2P22    1      A  RES         I360
  R2R1     1      A  RES         I34
  R2R3     1      A  RES         I41
  R2R5     1      A  RES         I258
  R2R7     1      A  RES         I172
  R2T3     1      A  RES         I54
  R2T4     1      A  RES         I152
  R2T5     1      A  RES         I326
  R2T6     1      A  RES         I127
  R2T7     1      A  RES         I327
  R2T8     1      A  RES         I106
  R2T11    1      A  RES         I105
  R2T22    1      A  RES         I210
  R2T29    1      A  RES         I298
  R2T34    1      A  RES         I206
  R2T35    1      A  RES         I207
  R2T53    1      A  RES         I83
  R2T54    1      A  RES         I84
  R2U2     1      A  RES         I265
  R2U3     1      A  RES         I98
  R2U4     1      A  RES         I367
  R2U5     1      A  RES         I214
  R2U11    1      A  RES         I97
  R2U13    1      A  RES         I216
  R2U30    1      A  RES         I76
  R2U38    1      A  RES         I80
  R2U39    1      A  RES         I83
  R2U48    1      A  RES         I213
  R3M1     1      A  RES         I34
  R3M5     1      A  RES         I35
  R3N2     1      A  RES         I72
  R3N10    1      A  RES         I37
  R3N11    1      A  RES         I344
  R3N12    1      A  RES         I342
  R3N13    1      A  RES         I71
  R3N17    1      A  RES         I78
  R3N23    1      A  RES         I60
  R3P18    1      A  RES         I64
  R3P21    1      A  RES         I88
  R3P22    1      A  RES         I24
  R3P25    1      A  RES         I56
  R3P36    1      A  RES         I36
  R3P44    1      A  RES         I59
  R3P50    1      A  RES         I71
  R3P54    1      A  RES         I331
  R3P61    1      A  RES         I201
  R3P62    1      A  RES         I22
  R3R15    1      A  RES         I44
  R3T3     1      A  RES         I150
  R3T4     1      A  RES         I174
  R3T5     1      A  RES         I152
  R3T12    1      A  RES         I178
  R3T13    1      A  RES         I313
  R4B10    1      A  RES         I143
  R4C8     1      A  RES         I55
  R4D26    1      A  RES         I40
  R4D31    1      A  RES         I22
  R4D42    1      A  RES         I15
  R4D47    1      A  RES         I25
  R4D49    1      A  RES         I63
  R4D58    1      A  RES         I25
  R4E3     1      A  RES         I111
  R4E4     1      A  RES         I19
  R4E5     1      A  RES         I27
  R4E20    1      A  RES         I116
  R4G14    1      A  RES         I185
  R4R5     1      A  RES         I258
  R4U1     1      A  RES         I91
  R5N1     1      A  RES         I238
  R5N2     1      A  RES         I227
  R5N3     1      A  RES         I240
  R5N4     1      A  RES         I241
  R5N5     1      A  RES         I239
  R6P32    1      A  RES         I102
  R6P37    1      A  RES         I103
  R6P39    1      A  RES         I181
  R6P40    1      A  RES         I91
  R6P49    1      A  RES         I14
  R7A9     1      A  RES         I14
  R7B4     1      A  RES         I17
  R7B5     1      A  RES         I16
  R7B6     1      A  RES         I295
  R7B17    1      A  RES         I210
  R7C5     1      A  RES         I297
  R7C8     1      A  RES         I296
  R7C13    1      A  RES         I67
  R7C23    1      A  RES         I144
  R7D2     1      A  RES         I332
  R7D3     1      A  RES         I243
  R7D4     1      A  RES         I245
  R7D5     1      A  RES         I199
  R7D6     1      A  RES         I306
  R7D7     1      A  RES         I331
  R7D8     1      A  RES         I200
  R7D9     1      A  RES         I200
  R7D10    1      A  RES         I202
  R7D12    1      A  RES         I237
  R7D13    1      A  RES         I60
  R7D30    1      A  RES         I121
  R7D42    1      A  RES         I193
  R7E5     1      A  RES         I38
  R7E6     1      A  RES         I33
  R7E18    1      A  RES         I55
  R7E19    1      A  RES         I57
  R7F5     1      A  RES         I94
  R7F6     1      A  RES         I90
  R7F19    1      A  RES         I143
  R7F20    1      A  RES         I315
  R7F22    1      A  RES         I301
  R7F27    1      A  RES         I303
  R7F28    1      A  RES         I168
  R7F32    1      A  RES         I140
  R7F36    1      A  RES         I300
  R7G22    1      A  RES         I53
  R7G23    1      A  RES         I51
  R7G26    1      A  RES         I101
  R7G27    1      A  RES         I155
  R7G31    1      A  RES         I139
  R8A5     1      A  RES         I216
  R8A6     1      A  RES         I149
  R8A7     1      A  RES         I222
  R8A10    1      A  RES          I3
  R8B23    1      A  RES         I280
  R8B24    1      A  RES         I95
  R8B25    1      A  RES         I140
  R8B26    1      A  RES         I96
  R8B30    1      A  RES         I282
  R8B31    1      A  RES         I307
  R8C1     1      A  RES         I326
  R8C2     1      A  RES         I304
  R8C4     1      A  RES         I286
  R8C6     1      A  RES         I303
  R8C7     1      A  RES         I327
  R8C9     1      A  RES         I20
  R8C15    1      A  RES         I92
  R8C16    1      A  RES         I91
  R8C18    1      A  RES         I40
  R8C25    1      A  RES         I333
  R8D13    1      A  RES         I52
  R8D14    1      A  RES         I301
  R8D15    1      A  RES         I88
  R8D16    1      A  RES         I71
  R8D17    1      A  RES         I87
  R8D21    1      A  RES         I120
  R8D25    1      A  RES         I335
  R8D26    1      A  RES         I71
  R8D28    1      A  RES         I70
  R8D29    1      A  RES         I26
  R8D31    1      A  RES         I27
  R8D41    1      A  RES         I120
  R8D44    1      A  RES         I362
  R8E3     1      A  RES         I355
  R8E6     1      A  RES         I21
  R8E12    1      A  RES         I78
  R8E14    1      A  RES         I133
  R8E19    1      A  RES         I361
  R8E22    1      A  RES         I215
  R8E23    2      B  RES          I3
  R8E25    1      A  RES         I144
  R8E30    1      A  RES         I23
  R8E32    1      A  RES         I385
  R8E36    1      A  RES         I28
  R8E40    1      A  RES         I177
  R8F5     1      A  RES         I117
  R8F13    1      A  RES         I23
  R8F14    1      A  RES          I9
  R8F16    1      A  RES          I8
  R8F23    1      A  RES         I296
  R8F24    1      A  RES         I316
  R8F26    1      A  RES         I211
  R8F32    1      A  RES         I118
  R8F34    1      A  RES         I22
  R8G2     1      A  RES         I267
  R8G3     1      A  RES         I210
  R8G6     1      A  RES         I212
  R8G20    1      A  RES         I50
  R8N1     1      A  RES         I157
  R8N2     1      A  RES         I161
  R8N3     1      A  RES         I159
  R8N4     1      A  RES         I158
  R8N5     1      A  RES         I160
  R9A7     1      A  RES         I80
  R9A12    2      B  RES         I117
  R9A14    2      B  RES         I11
  R9A16    2      B  RES         I129
  R9A18    1      A  RES         I183
  R9A20    2      B  RES         I178
  R9A21    1      A  RES         I186
  R9B6     1      A  RES         I35
  R9E1     1      A  RES         I179
  R9E2     1      A  RES         I177
  R9E3     1      A  RES         I178
  R9E4     1      A  RES         I200
  R9E7     1      A  RES         I193
  R9E21    1      A  RES         I137
  R9E22    2      B  RES         I181
  R9E24    2      B  RES         I57
  R9F3     1      A  RES         I65
  R9F5     1      A  RES         I173
  R9F9     2      B  RES         I52
  R9F10    2      B  RES         I60
  R9F12    1      A  RES          I6
  R9F13    1      A  RES         I21
  R9F14    2      B  RES         I47
  R9F15    2      B  RES         I111
  R9F16    2      B  RES         I56
  R9F17    2      B  RES         I46
  R9F18    2      B  RES         I62
  R9F19    2      B  RES         I63
  R9F28    1      A  RES         I72
  R9F30    1      A  RES         I76
  R9F35    2      B  RES         I51
  R9F36    2      B  RES         I44
  R9F37    2      B  RES         I55
  R9F38    2      B  RES         I59
  R9F39    2      B  RES         I64
  R9F40    2      B  RES         I65
  R9F47    1      A  RES          I4
  R9F48    1      A  RES         I13
  R9F49    1      A  RES         I14
  R9F52    1      A  RES         I82
  R9F55    1      A  RES         I30
  R9F61    1      A  RES         I252
  R9G4     2      B  RES         I56
  R9G21    1      A  RES         I69
  R9G23    1      A  RES         I57
  R9G25    1      A  RES         I58
  R9G35    1      A  RES         I164
  R9M3     1      A  RES         I30
  R9M5     1      A  RES         I85
  R9M16    1      A  RES         I16
  R9M17    1      A  RES         I15
  R9P4     1      A  RES         I210
  R9P5     1      A  RES         I215
  R9P6     1      A  RES         I149
  R9P10    1      A  RES         I192
  R9P20    1      A  RES         I86
  R9T5     1      A  RES         I135
  R9U8     1      A  RES         I85
  R9U10    1      A  RES         I30
  U1B2     8   VCCB  PCA9517_SM   I1
  U1E1     8     VP  TMP421_TSSOP  I30
  U1M2     5    VCC  NC7SB3157   I107
  U1M7     5    VCC  NC7SB3157   I40
  U2D1   CY55  VCC33  SKX_EXT_B_BGA1  I33
  U2M1     5    VCC  NC7SB3157   I255
  U2T1    16    VCC  PI3B3257A_TSSOPLF  I75
  U3P1    14    VCC  GTL2014_SM  I42
  U3T1     2    VCC  W25Q256_XSOI  I165
  U4C2    14    VCC  GTL2014_SM  I46
  U5D1   CY55  VCC33  SKX_EXT_B_BGA1  I34
  U7C1   AD24  VCCP_3P3<2>  LBG_CORE_QAT_EXT_D  I63
  U7C1   AG29  VCCPRTCPRIM_3P3  LBG_CORE_QAT_EXT_D  I63
  U7C1   AH24  VCCPDSW_3P3  LBG_CORE_QAT_EXT_D  I63
  U7C1   AN24  VCCP_3P3<5>  LBG_CORE_QAT_EXT_D  I63
  U7C1   AR24  VCCPSPI  LBG_CORE_QAT_EXT_D  I63
  U7C1   AU24  VCCPGPPK  LBG_CORE_QAT_EXT_D  I63
  U7C1   AU27  VCCPGPPF  LBG_CORE_QAT_EXT_D  I63
  U7C1   AW24  VCCPGPPA  LBG_CORE_QAT_EXT_D  I63
  U7C1   BA24  VCCPGPPH  LBG_CORE_QAT_EXT_D  I63
  U7C1   BA26  VCCPGPPG  LBG_CORE_QAT_EXT_D  I63
  U7C1   BA43  VCCPGPPD  LBG_CORE_QAT_EXT_D  I63
  U7C1   BA45  VCCP_3P3<1>  LBG_CORE_QAT_EXT_D  I63
  U7C1   BA46  VCCP_3P3<0>  LBG_CORE_QAT_EXT_D  I63
  U7C1   BA48  VCCPUSBDSW_3P3  LBG_CORE_QAT_EXT_D  I63
  U7C1   BB26  VCCPGPPJ  LBG_CORE_QAT_EXT_D  I63
  U7C1   BE26  VCCPGPPB  LBG_CORE_QAT_EXT_D  I63
  U7C1   BE40  VCCPGPPC  LBG_CORE_QAT_EXT_D  I63
  U7C1   BE44  VCCPGPPE  LBG_CORE_QAT_EXT_D  I63
  U7D3     6    VCC  ADM1085_SMT  I70
  U7F1     2    VCC  W25Q256_XSOI  I146
  U8D7    A1  VCC<0>  LCMXO2_A_256BGA  I14
  U8D7   A16  VCC<1>  LCMXO2_A_256BGA  I14
  U8D7    D5  VCCIO0<3>  LCMXO2_A_256BGA  I14
  U8D7   D12  VCCIO0<1>  LCMXO2_A_256BGA  I14
  U8D7    E4  VCCIO5<0>  LCMXO2_A_256BGA  I14
  U8D7   E13  VCCIO1<0>  LCMXO2_A_256BGA  I14
  U8D7    G7  VCC<4>  LCMXO2_A_256BGA  I14
  U8D7    G8  VCCIO0<0>  LCMXO2_A_256BGA  I14
  U8D7    G9  VCCIO0<2>  LCMXO2_A_256BGA  I14
  U8D7   G10  VCC<5>  LCMXO2_A_256BGA  I14
  U8D7    H7  VCCIO4<1>  LCMXO2_A_256BGA  I14
  U8D7   H10  VCCIO1<1>  LCMXO2_A_256BGA  I14
  U8D7    J7  VCCIO4<0>  LCMXO2_A_256BGA  I14
  U8D7   J10  VCCIO1<2>  LCMXO2_A_256BGA  I14
  U8D7    K7  VCC<6>  LCMXO2_A_256BGA  I14
  U8D7    K8  VCCIO2<2>  LCMXO2_A_256BGA  I14
  U8D7    K9  VCCIO2<0>  LCMXO2_A_256BGA  I14
  U8D7   K10  VCC<7>  LCMXO2_A_256BGA  I14
  U8D7    M4  VCCIO3<0>  LCMXO2_A_256BGA  I14
  U8D7   M13  VCCIO1<3>  LCMXO2_A_256BGA  I14
  U8D7    N5  VCCIO2<3>  LCMXO2_A_256BGA  I14
  U8D7   N12  VCCIO2<1>  LCMXO2_A_256BGA  I14
  U8D7    T1  VCC<2>  LCMXO2_A_256BGA  I14
  U8D7   T16  VCC<3>  LCMXO2_A_256BGA  I14
  U8D8     2    VDD  TPS3700_SM  I104
  U8F1    16    VCC  PI3B3257A_TSSOPLF  I74
  U8F2     2    VCC  W25Q128_SKT16  I32
  U9B4     8     VP  TMP421_TSSOP   I1
  U9E1     8    VCC  M25PE16_SM   I1
  U9F1     8    VCC  FSA3357_SM  I75
  U9F2     8    VCC  FSA3357_SM  I74
  U9F4    F8  R2VDD<0>  AST1250_BGA  I11
  U9F4    F9  R2VDD<1>  AST1250_BGA  I11
  U9F4   F10  R1VDD<0>  AST1250_BGA  I11
  U9F4   F11  R1VDD<1>  AST1250_BGA  I11
  U9F4   F12  PV33D<0>  AST1250_BGA  I11
  U9F4   F13  PV33D<1>  AST1250_BGA  I11
  U9F4    H6  PV33D<2>  AST1250_BGA  I11
  U9F4   H17  PV33D<3>  AST1250_BGA  I11
  U9F4    J6  PV33D<4>  AST1250_BGA  I11
  U9F4   J17  PEAV33  AST1250_BGA  I11
  U9F4    M6  PV33D<5>  AST1250_BGA  I11
  U9F4   M17  PV33D<6>  AST1250_BGA  I11
  U9F4    N6  PV33D<7>  AST1250_BGA  I11
  U9F4   N17  PV33D<8>  AST1250_BGA  I11
  U9F4    P1  DACAV33  AST1250_BGA  I11
  U9F4    T3  DACDV33  AST1250_BGA  I11
  U9F4    U8  PV33D<9>  AST1250_BGA  I11
  U9F4    U9  PV33D<10>  AST1250_BGA  I11
  U9F4   W18  USB2AV33  AST1250_BGA  I11
  U9P2     2    VDD  TPS3700_SM  I200
  Y9F2     4    VDD  OSC_C_SM4   I250

P3V3_STBY_BMC_ADCAV33   @BASEBOARD_FAB2_LIB.BASEBOARD_FAB2(SCH_1):P3V3_STBY_BMC_ADCAV33
  C1U17    1      A  CAP         I142
  C1U18    1      A  CAP_A       I141
  C9G11    1      A  CAP_A       I76
  FB1U1    2      B  FERRITE     I140
  U9F4    P3  ADCAV33  AST1250_BGA  I11

P3V3_STBY_BMC_ADCVREFN   @BASEBOARD_FAB2_LIB.BASEBOARD_FAB2(SCH_1):P3V3_STBY_BMC_ADCVREFN
  C9G8     2      B  CAP_A       I75
  C9G10    2      B  CAP_A       I79
  U9F4    K2  ADCVREFN  AST1250_BGA   I1

P3V3_STBY_BMC_ADCVREFP   @BASEBOARD_FAB2_LIB.BASEBOARD_FAB2(SCH_1):P3V3_STBY_BMC_ADCVREFP
  C9G8     1      A  CAP_A       I75
  C9G11    2      B  CAP_A       I76
  U9F4    K1  ADCVREFP  AST1250_BGA   I1

P3V3_STBY_BMC_HPLLAV33   @BASEBOARD_FAB2_LIB.BASEBOARD_FAB2(SCH_1):P3V3_STBY_BMC_HPLLAV33
  C1T19    1      A  CAP_A       I121
  C1T20    1      A  CAP         I119
  C1T23    1      A  CAP_A       I147
  FB1T2    2      B  FERRITE     I122
  U9F4   AB19  MPLLAV33  AST1250_BGA  I11
  U9F4   V17  HPLLAV33  AST1250_BGA  I11

P3V3_STBY_MNG   @BASEBOARD_FAB2_LIB.BASEBOARD_FAB2(SCH_1):P3V3_STBY_MNG
  C2T17    1      A  CAP_A       I112
  C2T22    1      A  CAP         I113
  C2T25    1      A  CAP_A       I111
  C2T30    1      A  CAP_A       I110
  C2T34    1      A  CAP_A       I109
  EU8F2    2  VDD96  ICS9FGP204_MLFP  I34
  EU8F2   12  VDD32K  ICS9FGP204_MLFP  I34
  EU8F2   15  VDDREF  ICS9FGP204_MLFP  I34
  EU8F2   23  VDD33  ICS9FGP204_MLFP  I34
  FB2T2    2      B  FERRITE     I114
  R2T21    1      A  RES         I105
  R2T23    1      A  RES         I94
  R2T52    1      A  RES         I95

P3V3_STBY_MNG_CPU   @BASEBOARD_FAB2_LIB.BASEBOARD_FAB2(SCH_1):P3V3_STBY_MNG_CPU
  C2T18    1      A  CAP_A       I104
  C2T19    1      A  CAP_A       I106
  EU8F2    9  VDDCPU  ICS9FGP204_MLFP  I34
  R2T21    2      B  RES         I105

P3V3_STBY_MNG_RGMII   @BASEBOARD_FAB2_LIB.BASEBOARD_FAB2(SCH_1):P3V3_STBY_MNG_RGMII
  C2T27    1      A  CAP_A       I90
  C2T31    1      A  CAP_A       I89
  EU8F2   34  VDD_RGMII  ICS9FGP204_MLFP  I34
  R2T23    2      B  RES         I94

P3V3_STBY_MNG_RMII   @BASEBOARD_FAB2_LIB.BASEBOARD_FAB2(SCH_1):P3V3_STBY_MNG_RMII
  C2T37    1      A  CAP_A       I99
  C2T38    1      A  CAP_A       I97
  EU8F2   26  VDDRMII<0>  ICS9FGP204_MLFP  I34
  EU8F2   31  VDDRMII<1>  ICS9FGP204_MLFP  I34
  R2T52    2      B  RES         I95

P3V3_STBY_P1V5_LAN_I210   @BASEBOARD_FAB2_LIB.BASEBOARD_FAB2(SCH_1):P3V3_STBY_P1V5_LAN_I210
  EU9E1   51  VDD3P3<1>  SPRINGVILLE_SM1  I72
  R1T33    2      B  RES         I240
  R1T34    2      B  RES         I239

P3V3_STBY_PLD_D   @BASEBOARD_FAB2_LIB.BASEBOARD_FAB2(SCH_1):P3V3_STBY_PLD_D
  CR3U1    1      C  DIODE_SMLF  I49
  J7G2     1    IO1  CONN8_C77962004  I47

P3V3_SWITCH_G   @BASEBOARD_FAB2_LIB.BASEBOARD_FAB2(SCH_1):P3V3_SWITCH_G
  EU2T1    7      G  SLG55021_SM   I1
  Q8G1     4   GATE  MOSFET_N_LCC3  I85

P3V_BAT_SOURCE   @BASEBOARD_FAB2_LIB.BASEBOARD_FAB2(SCH_1):P3V_BAT_SOURCE
  R2U43    1      A  RES         I46
  XBT8G1    1     P1  VERT_BATT_3PIN_PIP  I51
  XBT8G1    2     P2  VERT_BATT_3PIN_PIP  I51

P3V_BAT_SOURCE_R   @BASEBOARD_FAB2_LIB.BASEBOARD_FAB2(SCH_1):P3V_BAT_SOURCE_R
  Q9G1     3  DRAIN<0>  FET_N_DUAL_SMLF  I157
  R1U50    2      B  RES         I126

P5V             @BASEBOARD_FAB2_LIB.BASEBOARD_FAB2(SCH_1):P5V
  C1M38    1      A  CAP_A       I108
  C8B6     1      A  CAP         I40
  C8B7     1      A  CAP_A       I41
  EU8B1    6      S  SLG55021_SM  I13
  F8B1     1   A<0>  FUSE        I41
  Q8B1     1    SRC  MOSFET_N_LCC3  I87
  R1U29    1      A  RES         I141
  R8D39    1      A  RES         I114
  U1M3     5     IN  TPS2061_SM  I100

P5V_HDD_SATA    @BASEBOARD_FAB2_LIB.BASEBOARD_FAB2(SCH_1):P5V_HDD_SATA
  C9B1     1      A  CAP         I39
  F8B1     2   B<0>  FUSE        I41
  J2L1     1    IO1  CONN4_H73295001_PIP  I53
  J8A4     1    IO1  CONN4_H73295001_PIP  I25

P5V_STBY        @BASEBOARD_FAB2_LIB.BASEBOARD_FAB2(SCH_1):P5V_STBY
  C1A2     1      A  CAP_A       I53
  C1A11    1      A  CAP_A       I73
  C1A13    1      A  CAP_0402    I72
  C1B21    1      A  CAP_0402    I54
  C1C3     1      A  CAP_A       I23
  C1C4     1      A  CAP_0402    I22
  C1C18    1      A  CAP_A       I21
  C1D5     1      A  CAP_A       I47
  C1D6     1      A  CAP_0402    I46
  C1D15    1      A  CAP_A       I39
  C1D16    1      A  CAP_0402    I38
  C1D33    1      A  CAP_0402    I22
  C1E6     1      A  CAP_A       I29
  C1E7     1      A  CAP_0402    I28
  C1E23    1      A  CAP_A       I37
  C1E25    1      A  CAP_0402    I36
  C1F21    1      A  CAP_A       I73
  C1G4     1      A  CAP_A       I53
  C1G5     1      A  CAP_0402    I54
  C1G29    1      A  CAP_0402    I72
  C1L4     1      A  CAP_A       I64
  C2R11    1      A  CAP         I109
  C3L1     1      A  CAP_A       I17
  C3L29    1      A  CAP_A       I38
  C4C4     1      A  CAP_A       I18
  C4C5     1      A  CAP_0402    I16
  C4C14    1      A  CAP_A       I19
  C4D5     1      A  CAP_0402    I48
  C4D6     1      A  CAP_A       I49
  C4D13    1      A  CAP_0402    I40
  C4D14    1      A  CAP_A       I41
  C4D47    1      A  CAP_0402    I18
  C4E5     1      A  CAP_0402    I18
  C4E6     1      A  CAP_A       I19
  C4E23    1      A  CAP_0402    I73
  C4E25    1      A  CAP_A       I25
  C4E27    1      A  CAP_0402    I24
  C4E28    1      A  CAP_A       I74
  C7A8     1      A  CAP_0402    I16
  C7A17    1      A  CAP_0402    I54
  C7A18    1      A  CAP_A       I53
  C7A25    1      A  CAP_0402    I72
  C7A26    1      A  CAP_A       I73
  C7A41    1      A  CAP_0402    I39
  C7C18    1      A  CAP_0402    I33
  C7C20    1      A  CAP_A       I34
  C7G34    1      A  CAP_0402    I54
  C7G35    1      A  CAP_A       I53
  C7G41    1      A  CAP_0402    I72
  C7G42    1      A  CAP_A       I73
  C8B5     1      A  CAP_A       I37
  C8B8     1      A  CAP_A       I26
  C8B12    1      A  CAP         I38
  C8E4     1      A  CAPP         I8
  C8E7     1      A  CAP          I3
  C8E9     1      A  CAP          I2
  C8E19    1      A  CAP_A       I28
  C8F17    1      A  CAP_A       I24
  C9B9     1      A  CAP_A       I347
  C9B10    1      A  CAP_A       I345
  C9M6     1      A  CAP_A       I67
  CR1B1    1      C  DIODE_SM    I64
  CR1E1    1      C  DIODE_SM    I50
  EU1A1    4   VDRV  IR354XX_SM  I102
  EU1A1   35     EN  IR354XX_SM  I102
  EU1A2    4   VDRV  IR354XX_SM  I101
  EU1A2   35     EN  IR354XX_SM  I101
  EU1C1    4   VDRV  IR354XX_SM  I51
  EU1C1   35     EN  IR354XX_SM  I51
  EU1C3    4   VDRV  IR354XX_SM  I56
  EU1C3   35     EN  IR354XX_SM  I56
  EU1D1    4   VDRV  IR354XX_SM  I71
  EU1D1   35     EN  IR354XX_SM  I71
  EU1D3    4   VDRV  IR354XX_SM  I27
  EU1D3   35     EN  IR354XX_SM  I27
  EU1D4    4   VDRV  IR354XX_SM  I24
  EU1D4   35     EN  IR354XX_SM  I24
  EU1E2    4   VDRV  IR354XX_SM  I20
  EU1E2   35     EN  IR354XX_SM  I20
  EU1F1    4   VDRV  IR354XX_SM  I111
  EU1F1   35     EN  IR354XX_SM  I111
  EU1G1    4   VDRV  IR354XX_SM  I110
  EU1G1   35     EN  IR354XX_SM  I110
  EU2T1    1    VCC  SLG55021_SM   I1
  EU2T1    3  SHDN_N  SLG55021_SM   I1
  EU4C1    4   VDRV  IR354XX_SM  I46
  EU4C1   35     EN  IR354XX_SM  I46
  EU4C2    4   VDRV  IR354XX_SM  I71
  EU4C2   35     EN  IR354XX_SM  I71
  EU4D1    4   VDRV  IR354XX_SM  I71
  EU4D1   35     EN  IR354XX_SM  I71
  EU4D3    4   VDRV  IR354XX_SM  I70
  EU4D3   35     EN  IR354XX_SM  I70
  EU4D6    4   VDRV  IR354XX_SM  I64
  EU4D6   35     EN  IR354XX_SM  I64
  EU4E1    4   VDRV  IR354XX_SM  I63
  EU4E1   35     EN  IR354XX_SM  I63
  EU4E2    4   VDRV  IR354XX_SM  I126
  EU4E2   35     EN  IR354XX_SM  I126
  EU7A1    4   VDRV  IR354XX_SM  I106
  EU7A1   35     EN  IR354XX_SM  I106
  EU7A2    4   VDRV  IR354XX_SM  I117
  EU7A2   35     EN  IR354XX_SM  I117
  EU7A3    4   VDRV  IR354XX_SM  I116
  EU7A3   35     EN  IR354XX_SM  I116
  EU7A4    4   VDRV  IR354XX_SM  I107
  EU7A4   35     EN  IR354XX_SM  I107
  EU7C1    4   VDRV  IR354XX_SM  I101
  EU7C1   35     EN  IR354XX_SM  I101
  EU7E1    1    VCC  SLG55021_SM  I19
  EU7E1    3  SHDN_N  SLG55021_SM  I19
  EU7G2    4   VDRV  IR354XX_SM  I102
  EU7G2   35     EN  IR354XX_SM  I102
  EU7G3    4   VDRV  IR354XX_SM  I103
  EU7G3   35     EN  IR354XX_SM  I103
  EU8B1    1    VCC  SLG55021_SM  I13
  EU8B1    3  SHDN_N  SLG55021_SM  I13
  EU8B1    5      D  SLG55021_SM  I13
  EU8F1    5    VCC  RT8240_QFN  I125
  EU9M1    1    VCC  SLG55021_SM  I69
  EU9M1    3  SHDN_N  SLG55021_SM  I69
  J4B2   A13  IOA13  SCONN120_H61426002_SM  I46
  J4B2   B13  IOB13  SCONN120_H61426002_SM  I46
  J4B2   C13  IOC13  SCONN120_H61426002_SM  I46
  J6B1   A13  IOA13  SCONN120_H61426002_SM  I56
  J6B1   B13  IOB13  SCONN120_H61426002_SM  I56
  J6B1   C13  IOC13  SCONN120_H61426002_SM  I56
  J9B3     3    IO3  SCONN120_A28699018_SM  I336
  J9B3     5    IO5  SCONN120_A28699018_SM  I336
  J9B3     7    IO7  SCONN120_A28699018_SM  I336
  L8E1     2    INB  INDUCTOR    I90
  Q1L2     6  DRAIN<0>  FET_N_DUAL_SMLF  I188
  Q8B1     5    DRN  MOSFET_N_LCC3  I87
  R1E12    1      A  RES         I51
  R1L8     1      A  RES         I58
  R1L37    1      A  RES         I33
  R1U47    1      A  RES         I115
  R3L1     2      B  RES         I14
  R3L4     2      B  RES         I41
  R3L6     2      B  RES         I52
  R3L8     2      B  RES         I76
  R3N7     2      B  RES         I32
  R3U6     2      B  RES         I52
  R3U9     2      B  RES         I76
  R6N3     2      B  RES         I19
  R6P10    2      B  RES         I50
  R6P19    2      B  RES         I38
  R6P47    2      B  RES         I33
  R6R2     2      B  RES         I33
  R6R5     2      B  RES         I71
  R6R6     2      B  RES         I39
  R7E12    1      A  RES         I11
  R7F33    1      A  RES         I65
  R8E18    1      A  RES          I9
  R8E37    2      B  RES         I78
  R9A5     1      A  RES         I136
  R9A6     1      A  RES         I191
  R9L4     2      B  RES         I76
  R9L9     2      B  RES         I52
  R9N3     2      B  RES         I20
  R9P8     2      B  RES         I49
  R9P22    2      B  RES         I36
  R9P32    2      B  RES         I24
  R9R2     2      B  RES         I26
  R9R11    2      B  RES         I39
  R9U1     2      B  RES         I52
  R9U12    2      B  RES         I76

P5V_STBY_DBG    @BASEBOARD_FAB2_LIB.BASEBOARD_FAB2(SCH_1):P5V_STBY_DBG
  F1L1     1   A<0>  FUSE_SMT    I129
  Q1L2     1  SOURCE<0>  FET_N_DUAL_SMLF  I188

P5V_STBY_DGB_FS   @BASEBOARD_FAB2_LIB.BASEBOARD_FAB2(SCH_1):P5V_STBY_DGB_FS
  C9A1     1      A  CAP_A       I127
  F1L1     2   B<0>  FUSE_SMT    I129
  J9A2    14   IO14  CONN14_H54902001_PIP  I171

P5V_SWITCH_G    @BASEBOARD_FAB2_LIB.BASEBOARD_FAB2(SCH_1):P5V_SWITCH_G
  EU8B1    7      G  SLG55021_SM  I13
  Q8B1     4   GATE  MOSFET_N_LCC3  I87

P5V_USB         @BASEBOARD_FAB2_LIB.BASEBOARD_FAB2(SCH_1):P5V_USB
  C9B8     1      A  CAPP        I113
  J9B1     1   VBUS  CONN9_H51826001_PIP2  I69
  U1M3     1    OUT  TPS2061_SM  I100

PD_ADCREXT      @BASEBOARD_FAB2_LIB.BASEBOARD_FAB2(SCH_1):PD_ADCREXT
  R9G7     1      A  RES         I78
  U9F4    P2  ADCREXT  AST1250_BGA   I1

PD_CKMNG_OE     @BASEBOARD_FAB2_LIB.BASEBOARD_FAB2(SCH_1):PD_CKMNG_OE
  EU8F2    5  OE_96  ICS9FGP204_MLFP  I34
  EU8F2    6  OE_CPU  ICS9FGP204_MLFP  I34
  R2T25    1      A  RES         I48

PD_CPU0_BIST_ENABLE   @BASEBOARD_FAB2_LIB.BASEBOARD_FAB2(SCH_1):PD_CPU0_BIST_ENABLE
  R4P1     2      B  RES          I4
  U5D1   BA20  BIST_ENABLE  SKX_EXT_B_BGA1  I259

PD_CPU0_DMIMODE_OVERRIDE   @BASEBOARD_FAB2_LIB.BASEBOARD_FAB2(SCH_1):PD_CPU0_DMIMODE_OVERRIDE
  R4P6     2      B  RES         I68
  U5D1   AW12  DMIMODE_OVERRIDE  SKX_EXT_B_BGA1  I204

PD_CPU0_KSFC_DIS   @BASEBOARD_FAB2_LIB.BASEBOARD_FAB2(SCH_1):PD_CPU0_KSFC_DIS
  R4P7     2      B  RES         I72
  U5D1   AW14  TEST_15  SKX_EXT_B_BGA1  I259

PD_CPU0_MCP01_DMON   @BASEBOARD_FAB2_LIB.BASEBOARD_FAB2(SCH_1):PD_CPU0_MCP01_DMON
  R4P5     2      B  RES         I80
  U5D1   CN28  RSVD<75>  SKX_EXT_B_BGA1  I127

PD_CPU0_RSVD_TEST_1   @BASEBOARD_FAB2_LIB.BASEBOARD_FAB2(SCH_1):PD_CPU0_RSVD_TEST_1
  R5R1     1      A  RES         I188
  U5D1   AF45  TEST_1  SKX_EXT_B_BGA1  I204

PD_CPU0_RSVD_TEST_2   @BASEBOARD_FAB2_LIB.BASEBOARD_FAB2(SCH_1):PD_CPU0_RSVD_TEST_2
  R5P4     1      A  RES         I190
  U5D1   AG46  TEST_2  SKX_EXT_B_BGA1  I204

PD_CPU0_TEST12   @BASEBOARD_FAB2_LIB.BASEBOARD_FAB2(SCH_1):PD_CPU0_TEST12
  R6D5     1      A  RES         I81
  U5D1   AY19  TEST_12  SKX_EXT_B_BGA1  I259

PD_CPU0_TEST13   @BASEBOARD_FAB2_LIB.BASEBOARD_FAB2(SCH_1):PD_CPU0_TEST13
  R5P3     1      A  RES         I80
  U5D1   DB51  TEST_13  SKX_EXT_B_BGA1  I259

PD_CPU0_TEST14   @BASEBOARD_FAB2_LIB.BASEBOARD_FAB2(SCH_1):PD_CPU0_TEST14
  R5P2     1      A  RES         I79
  U5D1   DC50  TEST_14  SKX_EXT_B_BGA1  I259

PD_CPU0_TXT_PLTEN   @BASEBOARD_FAB2_LIB.BASEBOARD_FAB2(SCH_1):PD_CPU0_TXT_PLTEN
  R6D6     2      B  RES          I3
  U5D1   AV15  TXT_PLTEN  SKX_EXT_B_BGA1  I259

PD_CPU1_BIST_ENABLE   @BASEBOARD_FAB2_LIB.BASEBOARD_FAB2(SCH_1):PD_CPU1_BIST_ENABLE
  R3D13    2      B  RES         I12
  U2D1   BA20  BIST_ENABLE  SKX_EXT_B_BGA1  I172

PD_CPU1_DMIMODE_OVERRIDE   @BASEBOARD_FAB2_LIB.BASEBOARD_FAB2(SCH_1):PD_CPU1_DMIMODE_OVERRIDE
  R7P14    2      B  RES         I70
  U2D1   AW12  DMIMODE_OVERRIDE  SKX_EXT_B_BGA1  I169

PD_CPU1_KSFC_DIS   @BASEBOARD_FAB2_LIB.BASEBOARD_FAB2(SCH_1):PD_CPU1_KSFC_DIS
  R7P15    2      B  RES         I74
  U2D1   AW14  TEST_15  SKX_EXT_B_BGA1  I172

PD_CPU1_MCP01_DMON   @BASEBOARD_FAB2_LIB.BASEBOARD_FAB2(SCH_1):PD_CPU1_MCP01_DMON
  R7P13    2      B  RES         I81
  U2D1   CN28  RSVD<75>  SKX_EXT_B_BGA1  I107

PD_CPU1_RSVD_TEST_1   @BASEBOARD_FAB2_LIB.BASEBOARD_FAB2(SCH_1):PD_CPU1_RSVD_TEST_1
  R8R1     1      A  RES         I174
  U2D1   AF45  TEST_1  SKX_EXT_B_BGA1  I169

PD_CPU1_RSVD_TEST_2   @BASEBOARD_FAB2_LIB.BASEBOARD_FAB2(SCH_1):PD_CPU1_RSVD_TEST_2
  R8P3     1      A  RES         I173
  U2D1   AG46  TEST_2  SKX_EXT_B_BGA1  I169

PD_CPU1_TEST12   @BASEBOARD_FAB2_LIB.BASEBOARD_FAB2(SCH_1):PD_CPU1_TEST12
  R3D9     1      A  RES         I88
  U2D1   AY19  TEST_12  SKX_EXT_B_BGA1  I172

PD_CPU1_TEST13   @BASEBOARD_FAB2_LIB.BASEBOARD_FAB2(SCH_1):PD_CPU1_TEST13
  R8P2     1      A  RES         I86
  U2D1   DB51  TEST_13  SKX_EXT_B_BGA1  I172

PD_CPU1_TEST14   @BASEBOARD_FAB2_LIB.BASEBOARD_FAB2(SCH_1):PD_CPU1_TEST14
  R8P1     1      A  RES         I85
  U2D1   DC50  TEST_14  SKX_EXT_B_BGA1  I172

PD_CPU1_TXT_PLTEN   @BASEBOARD_FAB2_LIB.BASEBOARD_FAB2(SCH_1):PD_CPU1_TXT_PLTEN
  R3D12    2      B  RES         I11
  U2D1   AV15  TXT_PLTEN  SKX_EXT_B_BGA1  I172

PD_DIR_2        @BASEBOARD_FAB2_LIB.BASEBOARD_FAB2(SCH_1):PD_DIR_2
  R1U30    1      A  RES          I2
  U9G1     1    DIR  GTL2014_SM   I1

PD_FRU_WP       @BASEBOARD_FAB2_LIB.BASEBOARD_FAB2(SCH_1):PD_FRU_WP
  R8D27    1      A  RES         I50
  U8D4     7     WP  AT24C64     I49

PD_GTL2014_1_VREF   @BASEBOARD_FAB2_LIB.BASEBOARD_FAB2(SCH_1):PD_GTL2014_1_VREF
  R3P32    2      B  RES         I71
  U3P1     4   VREF  GTL2014_SM  I42

PD_GTL2014_2_VREF   @BASEBOARD_FAB2_LIB.BASEBOARD_FAB2(SCH_1):PD_GTL2014_2_VREF
  R4C9     2      B  RES         I69
  U4C2     4   VREF  GTL2014_SM  I46

PD_GTL2104_4_DIR   @BASEBOARD_FAB2_LIB.BASEBOARD_FAB2(SCH_1):PD_GTL2104_4_DIR
  R2T50    1      A  RES         I127
  U2T4     1    DIR  GTL2014_SM  I30

PD_GTL2104_DIR_0   @BASEBOARD_FAB2_LIB.BASEBOARD_FAB2(SCH_1):PD_GTL2104_DIR_0
  R7D26    1      A  RES         I54
  U7D2     1    DIR  GTL2014_SM  I32

PD_GTL2104_DIR_1   @BASEBOARD_FAB2_LIB.BASEBOARD_FAB2(SCH_1):PD_GTL2104_DIR_1
  R3R1     1      A  RES         I46
  U3P2     1    DIR  GTL2014_SM   I1

PD_HSC_RETRY_N   @BASEBOARD_FAB2_LIB.BASEBOARD_FAB2(SCH_1):PD_HSC_RETRY_N
  EU1D2   17  RETRY_N  ADM1278_SM  I10
  R1D28    1      A  RES         I26

PD_IE_DEBUG_MODE   @BASEBOARD_FAB2_LIB.BASEBOARD_FAB2(SCH_1):PD_IE_DEBUG_MODE
  J9G1    11   IO11  CONN12_C73564003  I128
  R1U64    1      A  RES         I69

PD_ME_RCVR_N    @BASEBOARD_FAB2_LIB.BASEBOARD_FAB2(SCH_1):PD_ME_RCVR_N
  J7G3     5    IO5  CONN12_C73564003  I174
  R7G28    1      A  RES         I102

PD_PASSWORD_CLEAR   @BASEBOARD_FAB2_LIB.BASEBOARD_FAB2(SCH_1):PD_PASSWORD_CLEAR
  J7G3    11   IO11  CONN12_C73564003  I174
  R7G29    1      A  RES         I148

PD_PEREXT       @BASEBOARD_FAB2_LIB.BASEBOARD_FAB2(SCH_1):PD_PEREXT
  R2T12    1      A  RES         I205
  U9F4   D20  NC_PEREXT  AST1250_BGA  I100

PD_PIROM_CPU0_ADDR0   @BASEBOARD_FAB2_LIB.BASEBOARD_FAB2(SCH_1):PD_PIROM_CPU0_ADDR0
  R6N14    2      B  RES         I302
  U5D1   CU58  PIROM_ADDR<0>  SKX_EXT_B_BGA1  I259

PD_PIROM_CPU0_ADDR1   @BASEBOARD_FAB2_LIB.BASEBOARD_FAB2(SCH_1):PD_PIROM_CPU0_ADDR1
  R6N13    2      B  RES         I303
  U5D1   CV57  PIROM_ADDR<1>  SKX_EXT_B_BGA1  I259

PD_PIROM_CPU0_ADDR2   @BASEBOARD_FAB2_LIB.BASEBOARD_FAB2(SCH_1):PD_PIROM_CPU0_ADDR2
  R6N15    2      B  RES         I304
  U5D1   CW56  PIROM_ADDR<2>  SKX_EXT_B_BGA1  I259

PD_PIROM_CPU1_ADDR1   @BASEBOARD_FAB2_LIB.BASEBOARD_FAB2(SCH_1):PD_PIROM_CPU1_ADDR1
  R1C33    2      B  RES         I313
  U2D1   CV57  PIROM_ADDR<1>  SKX_EXT_B_BGA1  I172

PD_PIROM_CPU1_ADDR2   @BASEBOARD_FAB2_LIB.BASEBOARD_FAB2(SCH_1):PD_PIROM_CPU1_ADDR2
  R1C32    2      B  RES         I312
  U2D1   CW56  PIROM_ADDR<2>  SKX_EXT_B_BGA1  I172

PD_RST_RTCRST_N   @BASEBOARD_FAB2_LIB.BASEBOARD_FAB2(SCH_1):PD_RST_RTCRST_N
  J9G1     6    IO6  CONN12_C73564003  I128
  R1U63    1      A  RES         I15

PD_SATA0_CONTROLLER_TYPE_R   @BASEBOARD_FAB2_LIB.BASEBOARD_FAB2(SCH_1):PD_SATA0_CONTROLLER_TYPE_R
  J8A1   1D2  SIDEBANDA_6  CONN72_G97614002_A_CP  I163
  R2L18    1      A  RES         I266

PD_SATA1_CONTROLLER_TYPE_R   @BASEBOARD_FAB2_LIB.BASEBOARD_FAB2(SCH_1):PD_SATA1_CONTROLLER_TYPE_R
  J8A1   2D2  SIDEBANDB_6  CONN72_G97614002_A_CP  I163
  R2L22    1      A  RES         I264

PD_SATA2_CONTROLLER_TYPE   @BASEBOARD_FAB2_LIB.BASEBOARD_FAB2(SCH_1):PD_SATA2_CONTROLLER_TYPE
  J8A2    D2  SIDEBAND6  CONN36_G97614001_CP  I26
  R1L3     1      A  RES          I5

PD_SPRV_RSET    @BASEBOARD_FAB2_LIB.BASEBOARD_FAB2(SCH_1):PD_SPRV_RSET
  EU9E1   48   RSET  SPRINGVILLE_SM1  I72
  R9E23    1      A  RES         I174

PD_SP_ENTEST    @BASEBOARD_FAB2_LIB.BASEBOARD_FAB2(SCH_1):PD_SP_ENTEST
  R1U7     2      B  RES         I127
  U9F4    E4  ENTEST  AST1250_BGA  I100

PD_TMP421_1_A0   @BASEBOARD_FAB2_LIB.BASEBOARD_FAB2(SCH_1):PD_TMP421_1_A0
  R9B8     1      A  RES         I10
  U9B4     4   A<0>  TMP421_TSSOP   I1

PD_TMP421_2_A1   @BASEBOARD_FAB2_LIB.BASEBOARD_FAB2(SCH_1):PD_TMP421_2_A1
  R1E10    2      B  RES         I38
  U1E1     3   A<1>  TMP421_TSSOP  I30

PD_USB_BMC_P1_DN   @BASEBOARD_FAB2_LIB.BASEBOARD_FAB2(SCH_1):PD_USB_BMC_P1_DN
  R9G5     1      A  RES         I516
  U9F4    J2  USB11_HDN  AST1250_BGA  I347

PD_USB_BMC_P1_DP   @BASEBOARD_FAB2_LIB.BASEBOARD_FAB2(SCH_1):PD_USB_BMC_P1_DP
  R9G6     1      A  RES         I517
  U9F4    J1  USB11_HDP  AST1250_BGA  I347

PECI_BMC        @BASEBOARD_FAB2_LIB.BASEBOARD_FAB2(SCH_1):PECI_BMC
  R7C17    2      B  RES         I28
  R7C18    1      A  RES         I11
  R9F20    1      A  RES         I133
  R9F33    1      A  RES         I132

PECI_BMC_R      @BASEBOARD_FAB2_LIB.BASEBOARD_FAB2(SCH_1):PECI_BMC_R
  R9F33    2      B  RES         I132
  U9F4   AA21   PECI  AST1250_BGA  I100

PECI_CPU_G      @BASEBOARD_FAB2_LIB.BASEBOARD_FAB2(SCH_1):PECI_CPU_G
  R7C18    2      B  RES         I11
  R7C19    2      B  RES         I15
  R7D15    1      A  RES         I32
  U2D1   AU12   PECI  SKX_EXT_B_BGA1  I172
  U5D1   AU12   PECI  SKX_EXT_B_BGA1  I259

PECI_PCH        @BASEBOARD_FAB2_LIB.BASEBOARD_FAB2(SCH_1):PECI_PCH
  R7C19    1      A  RES         I15
  R7C22    2      B  RES         I14
  U7C1    U9   PECI  LBG_CORE_QAT_EXT_D  I73

PE_PCH_SPRV_RX_C_DN   @BASEBOARD_FAB2_LIB.BASEBOARD_FAB2(SCH_1):PE_PCH_SPRV_RX_C_DN
  C9E5     2      B  CAP_A       I87
  U7C1   AM69  PCIE5_GBE_RXN  LBG_CORE_QAT_EXT_D  I220

PE_PCH_SPRV_RX_C_DP   @BASEBOARD_FAB2_LIB.BASEBOARD_FAB2(SCH_1):PE_PCH_SPRV_RX_C_DP
  C9E4     2      B  CAP_A       I88
  U7C1   AM71  PCIE5_GBE_RXP  LBG_CORE_QAT_EXT_D  I220

PE_PCH_SPRV_RX_DN   @BASEBOARD_FAB2_LIB.BASEBOARD_FAB2(SCH_1):PE_PCH_SPRV_RX_DN
  C9E5     1      A  CAP_A       I87
  EU9E1   20  PE_TN  SPRINGVILLE_SM1  I72

PE_PCH_SPRV_RX_DP   @BASEBOARD_FAB2_LIB.BASEBOARD_FAB2(SCH_1):PE_PCH_SPRV_RX_DP
  C9E4     1      A  CAP_A       I88
  EU9E1   21  PE_TP  SPRINGVILLE_SM1  I72

PE_PCH_SPRV_TX_C_DN   @BASEBOARD_FAB2_LIB.BASEBOARD_FAB2(SCH_1):PE_PCH_SPRV_TX_C_DN
  C2M24    2      B  CAP_A       I90
  EU9E1   23  PE_RN  SPRINGVILLE_SM1  I72

PE_PCH_SPRV_TX_C_DP   @BASEBOARD_FAB2_LIB.BASEBOARD_FAB2(SCH_1):PE_PCH_SPRV_TX_C_DP
  C2M23    2      B  CAP_A       I89
  EU9E1   24  PE_RP  SPRINGVILLE_SM1  I72

PE_PCH_SPRV_TX_DN   @BASEBOARD_FAB2_LIB.BASEBOARD_FAB2(SCH_1):PE_PCH_SPRV_TX_DN
  C2M24    1      A  CAP_A       I90
  U7C1   BH65  PCIE5_GBE_TXN  LBG_CORE_QAT_EXT_D  I220

PE_PCH_SPRV_TX_DP   @BASEBOARD_FAB2_LIB.BASEBOARD_FAB2(SCH_1):PE_PCH_SPRV_TX_DP
  C2M23    1      A  CAP_A       I89
  U7C1   BJ63  PCIE5_GBE_TXP  LBG_CORE_QAT_EXT_D  I220

PU_10GBE_LOM_PCI_DISABLE_N   @BASEBOARD_FAB2_LIB.BASEBOARD_FAB2(SCH_1):PU_10GBE_LOM_PCI_DISABLE_N
  R2N9     2      B  RES         I267
  U7C1   BW22  GPP_I8_PCI_DIS_N  LBG_CORE_QAT_EXT_D  I147

PU_24M_OSC_OE   @BASEBOARD_FAB2_LIB.BASEBOARD_FAB2(SCH_1):PU_24M_OSC_OE
  R9F61    2      B  RES         I252
  Y9F2     1  ENABLE_CONTROL  OSC_C_SM4   I250

PU_ADR_TIMER_HOLD_OFF_N   @BASEBOARD_FAB2_LIB.BASEBOARD_FAB2(SCH_1):PU_ADR_TIMER_HOLD_OFF_N
  R8D5     1      A  RES         I50
  R8D13    2      B  RES         I52
  U7C1   BB3  GPP_H15_SML3ALERT_N_IE_N  LBG_CORE_QAT_EXT_D  I147

PU_AT24C64_A2   @BASEBOARD_FAB2_LIB.BASEBOARD_FAB2(SCH_1):PU_AT24C64_A2
  R8D28    2      B  RES         I70
  U8D4     3     A2  AT24C64     I49

PU_BIOS_RECOVER_BOOT   @BASEBOARD_FAB2_LIB.BASEBOARD_FAB2(SCH_1):PU_BIOS_RECOVER_BOOT
  J7G3    12   IO12  CONN12_C73564003  I174
  R7G31    2      B  RES         I139

PU_BIOS_SPI_HOLD0_N   @BASEBOARD_FAB2_LIB.BASEBOARD_FAB2(SCH_1):PU_BIOS_SPI_HOLD0_N
  R7F3     2      B  RES         I109
  R7F32    2      B  RES         I140
  U7F1     1  HOLD_N_IO<3>  W25Q256_XSOI  I146

PU_BIOS_SPI_HOLD1_N   @BASEBOARD_FAB2_LIB.BASEBOARD_FAB2(SCH_1):PU_BIOS_SPI_HOLD1_N
  R3T1     2      B  RES         I157
  R3T4     2      B  RES         I174
  U3T1     1  HOLD_N_IO<3>  W25Q256_XSOI  I165

PU_BIOS_SPI_WP0_N   @BASEBOARD_FAB2_LIB.BASEBOARD_FAB2(SCH_1):PU_BIOS_SPI_WP0_N
  R7F28    2      B  RES         I168
  R7F30    1      A  RES         I170
  R7F37    2      B  RES         I108
  U7F1     9  WP_N_IO<2>  W25Q256_XSOI  I146

PU_BIOS_SPI_WP1_N   @BASEBOARD_FAB2_LIB.BASEBOARD_FAB2(SCH_1):PU_BIOS_SPI_WP1_N
  R3T9     1      A  RES         I179
  R3T12    2      B  RES         I178
  R3U1     2      B  RES         I156
  U3T1     9  WP_N_IO<2>  W25Q256_XSOI  I165

PU_BIOS_USB_RECOVERY   @BASEBOARD_FAB2_LIB.BASEBOARD_FAB2(SCH_1):PU_BIOS_USB_RECOVERY
  J7G3     6    IO6  CONN12_C73564003  I174
  R7G27    2      B  RES         I155

PU_CPU0_EAR_N   @BASEBOARD_FAB2_LIB.BASEBOARD_FAB2(SCH_1):PU_CPU0_EAR_N
  R6D14    2      B  RES         I52
  U5D1   AJ14  EAR_N  SKX_EXT_B_BGA1  I259

PU_CPU0_FRMAGENT   @BASEBOARD_FAB2_LIB.BASEBOARD_FAB2(SCH_1):PU_CPU0_FRMAGENT
  R5D3     2      B  RES         I29
  U5D1   AV17  FRMAGENT  SKX_EXT_B_BGA1  I259

PU_CPU0_LEGACY_SKT   @BASEBOARD_FAB2_LIB.BASEBOARD_FAB2(SCH_1):PU_CPU0_LEGACY_SKT
  R4P14    2      B  RES         I53
  U5D1   AE20  LEGACY_SKT  SKX_EXT_B_BGA1  I259

PU_CPU0_SAFE_MODE_BOOT   @BASEBOARD_FAB2_LIB.BASEBOARD_FAB2(SCH_1):PU_CPU0_SAFE_MODE_BOOT
  R6D13    2      B  RES         I33
  U5D1   AR18  SAFE_MODE_BOOT  SKX_EXT_B_BGA1  I259

PU_CPU0_SOCKET_ID_0   @BASEBOARD_FAB2_LIB.BASEBOARD_FAB2(SCH_1):PU_CPU0_SOCKET_ID_0
  R6D15    2      B  RES         I48
  U5D1   AU22  SOCKET_ID<0>  SKX_EXT_B_BGA1  I259

PU_CPU0_SOCKET_ID_1   @BASEBOARD_FAB2_LIB.BASEBOARD_FAB2(SCH_1):PU_CPU0_SOCKET_ID_1
  R6D10    2      B  RES         I49
  U5D1   AU16  SOCKET_ID<1>  SKX_EXT_B_BGA1  I259

PU_CPU0_TSC_SYNC   @BASEBOARD_FAB2_LIB.BASEBOARD_FAB2(SCH_1):PU_CPU0_TSC_SYNC
  R4P21    2      B  RES         I72
  U5D1   AM11  TSC_SYNC  SKX_EXT_B_BGA1  I259

PU_CPU0_TXT_AGENT   @BASEBOARD_FAB2_LIB.BASEBOARD_FAB2(SCH_1):PU_CPU0_TXT_AGENT
  R5D4     2      B  RES         I32
  U5D1   AW18  TXT_AGENT  SKX_EXT_B_BGA1  I259

PU_CPU1_EAR_N   @BASEBOARD_FAB2_LIB.BASEBOARD_FAB2(SCH_1):PU_CPU1_EAR_N
  R3D25    2      B  RES         I66
  U2D1   AJ14  EAR_N  SKX_EXT_B_BGA1  I172

PU_CPU1_FRMAGENT   @BASEBOARD_FAB2_LIB.BASEBOARD_FAB2(SCH_1):PU_CPU1_FRMAGENT
  R3D22    2      B  RES         I17
  U2D1   AV17  FRMAGENT  SKX_EXT_B_BGA1  I172

PU_CPU1_LEGACY_SKT   @BASEBOARD_FAB2_LIB.BASEBOARD_FAB2(SCH_1):PU_CPU1_LEGACY_SKT
  R7P22    2      B  RES         I76
  U2D1   AE20  LEGACY_SKT  SKX_EXT_B_BGA1  I172

PU_CPU1_SAFE_MODE_BOOT   @BASEBOARD_FAB2_LIB.BASEBOARD_FAB2(SCH_1):PU_CPU1_SAFE_MODE_BOOT
  R3D26    2      B  RES         I28
  U2D1   AR18  SAFE_MODE_BOOT  SKX_EXT_B_BGA1  I172

PU_CPU1_SOCKET_ID_0   @BASEBOARD_FAB2_LIB.BASEBOARD_FAB2(SCH_1):PU_CPU1_SOCKET_ID_0
  R3D24    2      B  RES         I59
  U2D1   AU22  SOCKET_ID<0>  SKX_EXT_B_BGA1  I172

PU_CPU1_SOCKET_ID_1   @BASEBOARD_FAB2_LIB.BASEBOARD_FAB2(SCH_1):PU_CPU1_SOCKET_ID_1
  R3D17    2      B  RES         I60
  U2D1   AU16  SOCKET_ID<1>  SKX_EXT_B_BGA1  I172

PU_CPU1_TSC_SYNC   @BASEBOARD_FAB2_LIB.BASEBOARD_FAB2(SCH_1):PU_CPU1_TSC_SYNC
  R4C10    2      B  RES         I76
  U2D1   AM11  TSC_SYNC  SKX_EXT_B_BGA1  I172

PU_CPU1_TXT_AGENT   @BASEBOARD_FAB2_LIB.BASEBOARD_FAB2(SCH_1):PU_CPU1_TXT_AGENT
  R3D23    2      B  RES         I25
  U2D1   AW18  TXT_AGENT  SKX_EXT_B_BGA1  I172

PU_DATAIN1_SATA_0_R   @BASEBOARD_FAB2_LIB.BASEBOARD_FAB2(SCH_1):PU_DATAIN1_SATA_0_R
  J8A1   1D1  SIDEBANDA_5  CONN72_G97614002_A_CP  I163
  R2L21    2      B  RES         I263

PU_DATAIN1_SATA_1_R   @BASEBOARD_FAB2_LIB.BASEBOARD_FAB2(SCH_1):PU_DATAIN1_SATA_1_R
  J8A1   2D1  SIDEBANDB_5  CONN72_G97614002_A_CP  I163
  R2L23    2      B  RES         I261

PU_DATAIN1_SATA_2   @BASEBOARD_FAB2_LIB.BASEBOARD_FAB2(SCH_1):PU_DATAIN1_SATA_2
  J8A2    D1  SIDEBAND5  CONN36_G97614001_CP  I26
  R1L1     2      B  RES         I25

PU_FAB2_MARKER_CPLD   @BASEBOARD_FAB2_LIB.BASEBOARD_FAB2(SCH_1):PU_FAB2_MARKER_CPLD
  R7D42    2      B  RES         I193
  U8D7   K16   PR9B  LCMXO2_A_256BGA  I59

PU_FM_RCIN_N    @BASEBOARD_FAB2_LIB.BASEBOARD_FAB2(SCH_1):PU_FM_RCIN_N
  R7D2     2      B  RES         I332
  U7C1    N3  GPP_A0_RCIN_N_ESPI_ALERT1_N  LBG_CORE_QAT_EXT_D  I115

PU_GTL2014_1_DIR   @BASEBOARD_FAB2_LIB.BASEBOARD_FAB2(SCH_1):PU_GTL2014_1_DIR
  R3P36    2      B  RES         I36
  U3P1     1    DIR  GTL2014_SM  I42

PU_GTL2014_2_DIR   @BASEBOARD_FAB2_LIB.BASEBOARD_FAB2(SCH_1):PU_GTL2014_2_DIR
  R4C8     2      B  RES         I55
  U4C2     1    DIR  GTL2014_SM  I46

PU_IRQ_PCH_SCI_WHEA_N   @BASEBOARD_FAB2_LIB.BASEBOARD_FAB2(SCH_1):PU_IRQ_PCH_SCI_WHEA_N
  R7D4     2      B  RES         I245
  U7C1    R1  GPP_A12_BMBUSY_N_SXEXITHLDOFF_N  LBG_CORE_QAT_EXT_D  I115

PU_IRQ_VRALERT_N   @BASEBOARD_FAB2_LIB.BASEBOARD_FAB2(SCH_1):PU_IRQ_VRALERT_N
  R2N16    2      B  RES         I247
  U7C1   BN15  GPP_B2  LBG_CORE_QAT_EXT_D  I115

PU_JTAG_SPRV_TCK   @BASEBOARD_FAB2_LIB.BASEBOARD_FAB2(SCH_1):PU_JTAG_SPRV_TCK
  EU9E1   19  JTAG_CLK  SPRINGVILLE_SM1  I72
  R9E2     2      B  RES         I177

PU_JTAG_SPRV_TDI   @BASEBOARD_FAB2_LIB.BASEBOARD_FAB2(SCH_1):PU_JTAG_SPRV_TDI
  EU9E1   29  JTAG_TDI  SPRINGVILLE_SM1  I72
  R9E1     2      B  RES         I179

PU_JTAG_SPRV_TDO   @BASEBOARD_FAB2_LIB.BASEBOARD_FAB2(SCH_1):PU_JTAG_SPRV_TDO
  EU9E1    4  JTAG_TDO  SPRINGVILLE_SM1  I72
  R9E22    1      A  RES         I181

PU_JTAG_SPRV_TMS   @BASEBOARD_FAB2_LIB.BASEBOARD_FAB2(SCH_1):PU_JTAG_SPRV_TMS
  EU9E1   18  JTAG_TMS  SPRINGVILLE_SM1  I72
  R9E3     2      B  RES         I178

PU_KEY_CONN_PIN2_R   @BASEBOARD_FAB2_LIB.BASEBOARD_FAB2(SCH_1):PU_KEY_CONN_PIN2_R
  J9A1     2    IO2  CONN4_D42317002_PIP  I131
  R9A16    1      A  RES         I129

PU_LPC_CLKRUN_N   @BASEBOARD_FAB2_LIB.BASEBOARD_FAB2(SCH_1):PU_LPC_CLKRUN_N
  R7D8     2      B  RES         I200
  U7C1   AB1  GPP_A8_CLKRUN_N  LBG_CORE_QAT_EXT_D  I115

PU_LPC_PME_N    @BASEBOARD_FAB2_LIB.BASEBOARD_FAB2(SCH_1):PU_LPC_PME_N
  R7D10    2      B  RES         I202
  U7C1   AC2  GPP_A11_PME_N  LBG_CORE_QAT_EXT_D  I115

PU_M2_CLK_REQ_N   @BASEBOARD_FAB2_LIB.BASEBOARD_FAB2(SCH_1):PU_M2_CLK_REQ_N
  J8F1    52  CLKREQ_N_NC  SCONN75K_H17033002_SMT1  I53
  R8F36    2      B  RES         I136

PU_NV_HOLD_N    @BASEBOARD_FAB2_LIB.BASEBOARD_FAB2(SCH_1):PU_NV_HOLD_N
  R1R9     2      B  RES         I10
  U9E1     7  RESET_N  M25PE16_SM   I1

PU_NV_WP_N      @BASEBOARD_FAB2_LIB.BASEBOARD_FAB2(SCH_1):PU_NV_WP_N
  R1R3     2      B  RES         I11
  U9E1     3    W_N  M25PE16_SM   I1

PU_PCH_TLS_ENABLE_STRAP   @BASEBOARD_FAB2_LIB.BASEBOARD_FAB2(SCH_1):PU_PCH_TLS_ENABLE_STRAP
  R8C17    1      A  RES         I41
  R8C18    2      B  RES         I40
  U7C1   BY27  GPP_C2_SMBALERT_N  LBG_CORE_QAT_EXT_D  I115

PU_PI7C9X1172_I2C_SPI_N   @BASEBOARD_FAB2_LIB.BASEBOARD_FAB2(SCH_1):PU_PI7C9X1172_I2C_SPI_N
  EU9F3   32  I2C_SPI_N  PI7C9X1172_QFN   I1
  R9F47    2      B  RES          I4

PU_PIROM_CPU1_ADDR0   @BASEBOARD_FAB2_LIB.BASEBOARD_FAB2(SCH_1):PU_PIROM_CPU1_ADDR0
  R1C34    2      B  RES         I320
  U2D1   CU58  PIROM_ADDR<0>  SKX_EXT_B_BGA1  I172

PU_RST_PERST_BIT0   @BASEBOARD_FAB2_LIB.BASEBOARD_FAB2(SCH_1):PU_RST_PERST_BIT0
  R2R1     2      B  RES         I34
  U8D7    F4   PL3C  LCMXO2_A_256BGA  I179

PU_RST_PERST_BIT1   @BASEBOARD_FAB2_LIB.BASEBOARD_FAB2(SCH_1):PU_RST_PERST_BIT1
  R7E6     2      B  RES         I33
  U8D7    B9  PT19A  LCMXO2_A_256BGA  I59

PU_SPI0_RST     @BASEBOARD_FAB2_LIB.BASEBOARD_FAB2(SCH_1):PU_SPI0_RST
  R7F6     2      B  RES         I90
  U7F1     3  RESET_N  W25Q256_XSOI  I146

PU_SPI1_RST     @BASEBOARD_FAB2_LIB.BASEBOARD_FAB2(SCH_1):PU_SPI1_RST
  R3T3     2      B  RES         I150
  U3T1     3  RESET_N  W25Q256_XSOI  I165

PU_SPI_BMC_BT_HOLD_N   @BASEBOARD_FAB2_LIB.BASEBOARD_FAB2(SCH_1):PU_SPI_BMC_BT_HOLD_N
  R8F14    2      B  RES          I9
  U8F2     1  HOLD_N_IO<3>  W25Q128_SKT16  I32

PU_SPI_BMC_BT_WP_N   @BASEBOARD_FAB2_LIB.BASEBOARD_FAB2(SCH_1):PU_SPI_BMC_BT_WP_N
  R8F34    2      B  RES         I22
  R8F35    1      A  RES         I24
  U8F2     9  WP_N_IO<2>  W25Q128_SKT16  I32

PU_SPI_FLASH_RESET_2_N   @BASEBOARD_FAB2_LIB.BASEBOARD_FAB2(SCH_1):PU_SPI_FLASH_RESET_2_N
  R8F16    2      B  RES          I8
  U8F2     3  RESET_N  W25Q128_SKT16  I32

PU_SPRV_LAN_PWR_GOOD   @BASEBOARD_FAB2_LIB.BASEBOARD_FAB2(SCH_1):PU_SPRV_LAN_PWR_GOOD
  EU9E1    1  LAN_PWR_GOOD  SPRINGVILLE_SM1  I72
  R9F5     2      B  RES         I173

PU_THERMTRIP_FORCE_N   @BASEBOARD_FAB2_LIB.BASEBOARD_FAB2(SCH_1):PU_THERMTRIP_FORCE_N
  R7E5     2      B  RES         I38
  U8D7   A12  PT22B  LCMXO2_A_256BGA  I59

PU_TMP421_1_A1   @BASEBOARD_FAB2_LIB.BASEBOARD_FAB2(SCH_1):PU_TMP421_1_A1
  R9B6     2      B  RES         I35
  U9B4     3   A<1>  TMP421_TSSOP   I1

PU_TMP421_2_A0   @BASEBOARD_FAB2_LIB.BASEBOARD_FAB2(SCH_1):PU_TMP421_2_A0
  R1E9     2      B  RES         I34
  U1E1     4   A<0>  TMP421_TSSOP  I30

PU_TRI_STATE_EN   @BASEBOARD_FAB2_LIB.BASEBOARD_FAB2(SCH_1):PU_TRI_STATE_EN
  R8E23    1      A  RES          I3
  U8E4     1     OE  TTL1G126_A_SOT   I1

PU_VR_PVCCIN_CPU0_FLT1_SMBALT_N   @BASEBOARD_FAB2_LIB.BASEBOARD_FAB2(SCH_1):PU_VR_PVCCIN_CPU0_FLT1_SMBALT_N_IMON
  EU4D4   20    MP2  PXE1610B_QFN  I155
  R4E20    2      B  RES         I116

PU_VR_PVCCIN_CPU0_IMON   @BASEBOARD_FAB2_LIB.BASEBOARD_FAB2(SCH_1):PU_VR_PVCCIN_CPU0_IMON
  EU4D4   39    MP3  PXE1610B_QFN  I155
  R4D31    2      B  RES         I22

PU_VR_PVCCIN_CPU1_FLT1_SMBALT_N   @BASEBOARD_FAB2_LIB.BASEBOARD_FAB2(SCH_1):PU_VR_PVCCIN_CPU1_FLT1_SMBALT_N_IMON
  EU1C2   20    MP2  PXE1610B_QFN  I130
  R1D53    2      B  RES         I33

PU_VR_PVCCIN_CPU1_IMON   @BASEBOARD_FAB2_LIB.BASEBOARD_FAB2(SCH_1):PU_VR_PVCCIN_CPU1_IMON
  EU1C2   39    MP3  PXE1610B_QFN  I130
  R1C18    2      B  RES         I34

PU_VR_PVCCIO_CPU0_FAULT1   @BASEBOARD_FAB2_LIB.BASEBOARD_FAB2(SCH_1):PU_VR_PVCCIO_CPU0_FAULT1
  EU3P1   32    MP4  PXE1110B_QFN  I93
  R3N23    2      B  RES         I60

PU_VR_PVCCIO_CPU1_FAULT1   @BASEBOARD_FAB2_LIB.BASEBOARD_FAB2(SCH_1):PU_VR_PVCCIO_CPU1_FAULT1
  EU4D5   32    MP4  PXE1110B_QFN  I96
  R6P49    2      B  RES         I14

PU_VR_PVDDQ_ABC_FAULT1   @BASEBOARD_FAB2_LIB.BASEBOARD_FAB2(SCH_1):PU_VR_PVDDQ_ABC_FAULT1
  EU7G1   13    MP0  PXM1310B_QFN  I358
  R7F36    2      B  RES         I300

PU_VR_PVDDQ_DEF_FAULT1   @BASEBOARD_FAB2_LIB.BASEBOARD_FAB2(SCH_1):PU_VR_PVDDQ_DEF_FAULT1
  EU7A5   13    MP0  PXM1310B_QFN  I75
  R7A9     2      B  RES         I14

PU_VR_PVDDQ_GHJ_FAULT1   @BASEBOARD_FAB2_LIB.BASEBOARD_FAB2(SCH_1):PU_VR_PVDDQ_GHJ_FAULT1
  EU1G2   13    MP0  PXM1310B_QFN  I90
  R1G6     2      B  RES         I13

PU_VR_PVDDQ_KLM_FAULT1   @BASEBOARD_FAB2_LIB.BASEBOARD_FAB2(SCH_1):PU_VR_PVDDQ_KLM_FAULT1
  EU1B1   13    MP0  PXM1310B_QFN  I90
  R1B13    2      B  RES         I13

PU_VR_PVNN_PCH_FAULT1   @BASEBOARD_FAB2_LIB.BASEBOARD_FAB2(SCH_1):PU_VR_PVNN_PCH_FAULT1
  EU8A1   32    MP4  PXE1110B_QFN  I229
  R2L24    2      B  RES         I148

PVCCIN_CPU0     @BASEBOARD_FAB2_LIB.BASEBOARD_FAB2(SCH_1):PVCCIN_CPU0
  C4D4     1      A  CAP_A       I69
  C4D12    1      A  CAP_A        I9
  C4D34    1      A  CAP_A       I68
  C4E3     1      A  CAP_A       I61
  C4E11    1      A  CAP_A       I27
  C5D1     1      A  CAP_A       I126
  C5D2     1      A  CAP_A       I136
  C5D3     1      A  CAP_A       I130
  C5D4     1      A  CAP_A       I127
  C5D5     1      A  CAP_A       I125
  C5D14    1      A  CAP_A       I117
  C5D15    1      A  CAP_A       I132
  C5D16    1      A  CAP_A       I123
  C5D17    1      A  CAP_A       I118
  C5D18    1      A  CAP_A       I134
  C5D19    1      A  CAP_A       I128
  C5D24    1      A  CAP_A       I138
  C5D25    1      A  CAP_A       I155
  C5D26    1      A  CAP_A       I154
  C5D27    1      A  CAP_A       I109
  C5D28    1      A  CAP_A       I100
  C5D29    1      A  CAP_A       I102
  C5D30    1      A  CAP_A       I111
  C5D31    1      A  CAP_A       I106
  C5D32    1      A  CAP_A       I103
  C5D39    1      A  CAP_A       I140
  C5D40    1      A  CAP_A       I115
  C5D41    1      A  CAP_A       I114
  C5D42    1      A  CAP_A       I135
  C5D43    1      A  CAP_A       I131
  C5D44    1      A  CAP_A       I142
  C5D45    1      A  CAP_A       I156
  C5D46    1      A  CAP_A       I107
  C5D47    1      A  CAP_A       I104
  C5D58    1      A  CAP_A       I120
  C5D59    1      A  CAP_A       I129
  C5D60    1      A  CAP_A       I112
  C5D61    1      A  CAP_A       I113
  C5P3     1      A  CAP         I189
  C5P4     1      A  CAP         I27
  C5P5     1      A  CAP         I42
  C5P6     1      A  CAP         I38
  C5P14    1      A  CAP         I41
  C5P15    1      A  CAP         I187
  C5P16    1      A  CAP         I188
  C5P17    1      A  CAP         I190
  C5P22    1      A  CAP         I55
  C5P23    1      A  CAP         I28
  C5P24    1      A  CAP         I33
  C5P25    1      A  CAP         I37
  C5P26    1      A  CAP         I56
  C5P27    1      A  CAP         I44
  C5P32    1      A  CAP         I53
  C5P33    1      A  CAP         I50
  C5P34    1      A  CAP         I54
  C5P35    1      A  CAP         I51
  C5P36    1      A  CAP         I65
  C5P37    1      A  CAP         I63
  C5P40    1      A  CAP         I57
  C5P41    1      A  CAP         I40
  C5P42    1      A  CAP         I59
  C5P43    1      A  CAP         I60
  C5P44    1      A  CAP         I61
  C6N9     1      A  CAPP        I34
  C6P3     1      A  CAP_A       I25
  C6P8     1      A  CAPP        I32
  C6P14    1      A  CAPP        I29
  C6P16    1      A  CAP_A       I62
  C6P18    1      A  CAPP        I30
  C6P21    1      A  CAP_A       I66
  C6P23    1      A  CAPP        I28
  C6R2     1      A  CAP_A       I70
  C6R3     1      A  CAPP        I16
  C6R7     1      A  CAP_A        I9
  C6R9     1      A  CAPP        I18
  EU4C2    1    VOS  IR354XX_SM  I71
  EU4D1    1    VOS  IR354XX_SM  I71
  EU4D3    1    VOS  IR354XX_SM  I70
  EU4D6    1    VOS  IR354XX_SM  I64
  EU4E1    1    VOS  IR354XX_SM  I63
  L4C3     2    INB  INDUCTOR     I5
  L4D1     2    INB  INDUCTOR    I24
  L4D2     2    INB  INDUCTOR    I15
  L4D3     2    INB  INDUCTOR    I29
  L4E1     2    INB  INDUCTOR     I5
  R4E13    1      A  RES         I67
  R4E14    2      B  RES         I60
  R5P1     1      A  RES         I309
  U5D1   AF43  VCCIN<267>  SKX_EXT_B_BGA1  I310
  U5D1   AG38  VCCIN<266>  SKX_EXT_B_BGA1  I310
  U5D1   AG40  VCCIN<265>  SKX_EXT_B_BGA1  I310
  U5D1   AG42  VCCIN<264>  SKX_EXT_B_BGA1  I310
  U5D1   AH37  VCCIN<263>  SKX_EXT_B_BGA1  I310
  U5D1   AH39  VCCIN<262>  SKX_EXT_B_BGA1  I310
  U5D1   AH41  VCCIN<261>  SKX_EXT_B_BGA1  I310
  U5D1   AJ36  VCCIN<260>  SKX_EXT_B_BGA1  I310
  U5D1   AK35  VCCIN<259>  SKX_EXT_B_BGA1  I310
  U5D1   AK45  VCCIN<258>  SKX_EXT_B_BGA1  I310
  U5D1   AK47  VCCIN<257>  SKX_EXT_B_BGA1  I310
  U5D1   AK49  VCCIN<256>  SKX_EXT_B_BGA1  I310
  U5D1   AK51  VCCIN<255>  SKX_EXT_B_BGA1  I310
  U5D1   AK53  VCCIN<254>  SKX_EXT_B_BGA1  I310
  U5D1   AL34  VCCIN<253>  SKX_EXT_B_BGA1  I310
  U5D1   AL46  VCCIN<252>  SKX_EXT_B_BGA1  I310
  U5D1   AL48  VCCIN<251>  SKX_EXT_B_BGA1  I310
  U5D1   AL50  VCCIN<250>  SKX_EXT_B_BGA1  I310
  U5D1   AL52  VCCIN<249>  SKX_EXT_B_BGA1  I310
  U5D1   AL54  VCCIN<248>  SKX_EXT_B_BGA1  I310
  U5D1   AM33  VCCIN<247>  SKX_EXT_B_BGA1  I310
  U5D1   AM53  VCCIN<246>  SKX_EXT_B_BGA1  I310
  U5D1   AM55  VCCIN<245>  SKX_EXT_B_BGA1  I310
  U5D1   AN32  VCCIN<244>  SKX_EXT_B_BGA1  I310
  U5D1   AN54  VCCIN<243>  SKX_EXT_B_BGA1  I310
  U5D1   AN56  VCCIN<242>  SKX_EXT_B_BGA1  I310
  U5D1   AP55  VCCIN<241>  SKX_EXT_B_BGA1  I310
  U5D1   AP57  VCCIN<240>  SKX_EXT_B_BGA1  I310
  U5D1   AR56  VCCIN<239>  SKX_EXT_B_BGA1  I310
  U5D1   AR58  VCCIN<238>  SKX_EXT_B_BGA1  I310
  U5D1   AT57  VCCIN<237>  SKX_EXT_B_BGA1  I310
  U5D1   AT59  VCCIN<236>  SKX_EXT_B_BGA1  I310
  U5D1   AU58  VCCIN<235>  SKX_EXT_B_BGA1  I310
  U5D1   AU60  VCCIN<234>  SKX_EXT_B_BGA1  I310
  U5D1   AV59  VCCIN<233>  SKX_EXT_B_BGA1  I310
  U5D1   AV61  VCCIN<232>  SKX_EXT_B_BGA1  I310
  U5D1   AW60  VCCIN<231>  SKX_EXT_B_BGA1  I310
  U5D1   AY61  VCCIN<230>  SKX_EXT_B_BGA1  I310
  U5D1   BA60  VCCIN<229>  SKX_EXT_B_BGA1  I310
  U5D1   BB61  VCCIN<228>  SKX_EXT_B_BGA1  I310
  U5D1   BB85  VCCIN<227>  SKX_EXT_B_BGA1  I310
  U5D1   BC60  VCCIN<226>  SKX_EXT_B_BGA1  I310
  U5D1   BC62  VCCIN<225>  SKX_EXT_B_BGA1  I310
  U5D1   BC84  VCCIN<224>  SKX_EXT_B_BGA1  I310
  U5D1   BD61  VCCIN<223>  SKX_EXT_B_BGA1  I310
  U5D1   BD73  VCCIN<222>  SKX_EXT_B_BGA1  I310
  U5D1   BD75  VCCIN<221>  SKX_EXT_B_BGA1  I310
  U5D1   BD77  VCCIN<220>  SKX_EXT_B_BGA1  I310
  U5D1   BD79  VCCIN<219>  SKX_EXT_B_BGA1  I310
  U5D1   BD81  VCCIN<218>  SKX_EXT_B_BGA1  I310
  U5D1   BD83  VCCIN<217>  SKX_EXT_B_BGA1  I310
  U5D1   BD85  VCCIN<216>  SKX_EXT_B_BGA1  I310
  U5D1   BE60  VCCIN<215>  SKX_EXT_B_BGA1  I310
  U5D1   BE62  VCCIN<214>  SKX_EXT_B_BGA1  I310
  U5D1   BE72  VCCIN<213>  SKX_EXT_B_BGA1  I310
  U5D1   BE74  VCCIN<212>  SKX_EXT_B_BGA1  I310
  U5D1   BE76  VCCIN<211>  SKX_EXT_B_BGA1  I310
  U5D1   BE78  VCCIN<210>  SKX_EXT_B_BGA1  I310
  U5D1   BE80  VCCIN<209>  SKX_EXT_B_BGA1  I310
  U5D1   BE82  VCCIN<208>  SKX_EXT_B_BGA1  I310
  U5D1   BE84  VCCIN<207>  SKX_EXT_B_BGA1  I310
  U5D1   BF61  VCCIN<206>  SKX_EXT_B_BGA1  I310
  U5D1   BF73  VCCIN<205>  SKX_EXT_B_BGA1  I310
  U5D1   BF75  VCCIN<204>  SKX_EXT_B_BGA1  I310
  U5D1   BF77  VCCIN<203>  SKX_EXT_B_BGA1  I310
  U5D1   BF79  VCCIN<202>  SKX_EXT_B_BGA1  I310
  U5D1   BF81  VCCIN<201>  SKX_EXT_B_BGA1  I310
  U5D1   BF83  VCCIN<200>  SKX_EXT_B_BGA1  I310
  U5D1   BF85  VCCIN<199>  SKX_EXT_B_BGA1  I310
  U5D1   BG60  VCCIN<198>  SKX_EXT_B_BGA1  I310
  U5D1   BG62  VCCIN<197>  SKX_EXT_B_BGA1  I310
  U5D1   BG64  VCCIN<196>  SKX_EXT_B_BGA1  I310
  U5D1   BG66  VCCIN<195>  SKX_EXT_B_BGA1  I310
  U5D1   BG68  VCCIN<194>  SKX_EXT_B_BGA1  I310
  U5D1   BG70  VCCIN<193>  SKX_EXT_B_BGA1  I310
  U5D1   BG84  VCCIN<192>  SKX_EXT_B_BGA1  I310
  U5D1   BH61  VCCIN<191>  SKX_EXT_B_BGA1  I310
  U5D1   BH63  VCCIN<190>  SKX_EXT_B_BGA1  I310
  U5D1   BH65  VCCIN<189>  SKX_EXT_B_BGA1  I310
  U5D1   BH67  VCCIN<188>  SKX_EXT_B_BGA1  I310
  U5D1   BH69  VCCIN<187>  SKX_EXT_B_BGA1  I310
  U5D1   BH71  VCCIN<186>  SKX_EXT_B_BGA1  I310
  U5D1   BH73  VCCIN<185>  SKX_EXT_B_BGA1  I310
  U5D1   BH75  VCCIN<184>  SKX_EXT_B_BGA1  I310
  U5D1   BH77  VCCIN<183>  SKX_EXT_B_BGA1  I310
  U5D1   BH79  VCCIN<182>  SKX_EXT_B_BGA1  I310
  U5D1   BH81  VCCIN<181>  SKX_EXT_B_BGA1  I310
  U5D1   BH83  VCCIN<180>  SKX_EXT_B_BGA1  I310
  U5D1   BJ60  VCCIN<179>  SKX_EXT_B_BGA1  I310
  U5D1   BJ62  VCCIN<178>  SKX_EXT_B_BGA1  I310
  U5D1   BJ64  VCCIN<177>  SKX_EXT_B_BGA1  I310
  U5D1   BJ66  VCCIN<176>  SKX_EXT_B_BGA1  I310
  U5D1   BJ68  VCCIN<175>  SKX_EXT_B_BGA1  I310
  U5D1   BJ70  VCCIN<174>  SKX_EXT_B_BGA1  I310
  U5D1   BJ72  VCCIN<173>  SKX_EXT_B_BGA1  I310
  U5D1   BJ74  VCCIN<172>  SKX_EXT_B_BGA1  I310
  U5D1   BJ76  VCCIN<171>  SKX_EXT_B_BGA1  I310
  U5D1   BJ78  VCCIN<170>  SKX_EXT_B_BGA1  I310
  U5D1   BJ80  VCCIN<169>  SKX_EXT_B_BGA1  I310
  U5D1   BJ82  VCCIN<168>  SKX_EXT_B_BGA1  I310
  U5D1   BJ84  VCCIN<167>  SKX_EXT_B_BGA1  I310
  U5D1   BK61  VCCIN<166>  SKX_EXT_B_BGA1  I310
  U5D1   BK63  VCCIN<165>  SKX_EXT_B_BGA1  I310
  U5D1   BK65  VCCIN<164>  SKX_EXT_B_BGA1  I310
  U5D1   BK67  VCCIN<163>  SKX_EXT_B_BGA1  I310
  U5D1   BK69  VCCIN<162>  SKX_EXT_B_BGA1  I310
  U5D1   BK71  VCCIN<161>  SKX_EXT_B_BGA1  I310
  U5D1   BK73  VCCIN<160>  SKX_EXT_B_BGA1  I310
  U5D1   BK75  VCCIN<159>  SKX_EXT_B_BGA1  I310
  U5D1   BK77  VCCIN<158>  SKX_EXT_B_BGA1  I310
  U5D1   BK79  VCCIN<157>  SKX_EXT_B_BGA1  I310
  U5D1   BK81  VCCIN<156>  SKX_EXT_B_BGA1  I310
  U5D1   BK83  VCCIN<155>  SKX_EXT_B_BGA1  I310
  U5D1   BL60  VCCIN<154>  SKX_EXT_B_BGA1  I310
  U5D1   BL62  VCCIN<153>  SKX_EXT_B_BGA1  I310
  U5D1   BL84  VCCIN<152>  SKX_EXT_B_BGA1  I310
  U5D1   BM61  VCCIN<151>  SKX_EXT_B_BGA1  I310
  U5D1   BM63  VCCIN<150>  SKX_EXT_B_BGA1  I310
  U5D1   BM65  VCCIN<149>  SKX_EXT_B_BGA1  I310
  U5D1   BM67  VCCIN<148>  SKX_EXT_B_BGA1  I310
  U5D1   BM69  VCCIN<147>  SKX_EXT_B_BGA1  I310
  U5D1   BM71  VCCIN<146>  SKX_EXT_B_BGA1  I310
  U5D1   BM73  VCCIN<145>  SKX_EXT_B_BGA1  I310
  U5D1   BM75  VCCIN<144>  SKX_EXT_B_BGA1  I310
  U5D1   BM77  VCCIN<143>  SKX_EXT_B_BGA1  I310
  U5D1   BM79  VCCIN<142>  SKX_EXT_B_BGA1  I310
  U5D1   BM81  VCCIN<141>  SKX_EXT_B_BGA1  I310
  U5D1   BM83  VCCIN<140>  SKX_EXT_B_BGA1  I310
  U5D1   BN60  VCCIN<139>  SKX_EXT_B_BGA1  I310
  U5D1   BN62  VCCIN<138>  SKX_EXT_B_BGA1  I310
  U5D1   BN64  VCCIN<137>  SKX_EXT_B_BGA1  I310
  U5D1   BN66  VCCIN<136>  SKX_EXT_B_BGA1  I310
  U5D1   BN68  VCCIN<135>  SKX_EXT_B_BGA1  I310
  U5D1   BN70  VCCIN<134>  SKX_EXT_B_BGA1  I310
  U5D1   BN72  VCCIN<133>  SKX_EXT_B_BGA1  I310
  U5D1   BN74  VCCIN<132>  SKX_EXT_B_BGA1  I310
  U5D1   BN76  VCCIN<131>  SKX_EXT_B_BGA1  I310
  U5D1   BN78  VCCIN<130>  SKX_EXT_B_BGA1  I310
  U5D1   BN80  VCCIN<129>  SKX_EXT_B_BGA1  I311
  U5D1   BN82  VCCIN<128>  SKX_EXT_B_BGA1  I311
  U5D1   BN84  VCCIN<127>  SKX_EXT_B_BGA1  I311
  U5D1   BP61  VCCIN<126>  SKX_EXT_B_BGA1  I311
  U5D1   BP63  VCCIN<125>  SKX_EXT_B_BGA1  I311
  U5D1   BP65  VCCIN<124>  SKX_EXT_B_BGA1  I311
  U5D1   BP67  VCCIN<123>  SKX_EXT_B_BGA1  I311
  U5D1   BP69  VCCIN<122>  SKX_EXT_B_BGA1  I311
  U5D1   BP71  VCCIN<121>  SKX_EXT_B_BGA1  I311
  U5D1   BP73  VCCIN<120>  SKX_EXT_B_BGA1  I311
  U5D1   BP75  VCCIN<119>  SKX_EXT_B_BGA1  I311
  U5D1   BP77  VCCIN<118>  SKX_EXT_B_BGA1  I311
  U5D1   BP79  VCCIN<117>  SKX_EXT_B_BGA1  I311
  U5D1   BP81  VCCIN<116>  SKX_EXT_B_BGA1  I311
  U5D1   BP83  VCCIN<115>  SKX_EXT_B_BGA1  I311
  U5D1   BR60  VCCIN<114>  SKX_EXT_B_BGA1  I311
  U5D1   BR62  VCCIN<113>  SKX_EXT_B_BGA1  I311
  U5D1   BR84  VCCIN<112>  SKX_EXT_B_BGA1  I311
  U5D1   BT61  VCCIN<111>  SKX_EXT_B_BGA1  I311
  U5D1   BT63  VCCIN<110>  SKX_EXT_B_BGA1  I311
  U5D1   BT65  VCCIN<109>  SKX_EXT_B_BGA1  I311
  U5D1   BT67  VCCIN<108>  SKX_EXT_B_BGA1  I311
  U5D1   BT69  VCCIN<107>  SKX_EXT_B_BGA1  I311
  U5D1   BT71  VCCIN<106>  SKX_EXT_B_BGA1  I311
  U5D1   BT73  VCCIN<105>  SKX_EXT_B_BGA1  I311
  U5D1   BT75  VCCIN<104>  SKX_EXT_B_BGA1  I311
  U5D1   BT77  VCCIN<103>  SKX_EXT_B_BGA1  I311
  U5D1   BT79  VCCIN<102>  SKX_EXT_B_BGA1  I311
  U5D1   BT81  VCCIN<101>  SKX_EXT_B_BGA1  I311
  U5D1   BT83  VCCIN<100>  SKX_EXT_B_BGA1  I311
  U5D1   BU60  VCCIN<99>  SKX_EXT_B_BGA1  I311
  U5D1   BU62  VCCIN<98>  SKX_EXT_B_BGA1  I311
  U5D1   BU64  VCCIN<97>  SKX_EXT_B_BGA1  I311
  U5D1   BU66  VCCIN<96>  SKX_EXT_B_BGA1  I311
  U5D1   BU68  VCCIN<95>  SKX_EXT_B_BGA1  I311
  U5D1   BU70  VCCIN<94>  SKX_EXT_B_BGA1  I311
  U5D1   BU72  VCCIN<93>  SKX_EXT_B_BGA1  I311
  U5D1   BU74  VCCIN<92>  SKX_EXT_B_BGA1  I311
  U5D1   BU76  VCCIN<91>  SKX_EXT_B_BGA1  I311
  U5D1   BU78  VCCIN<90>  SKX_EXT_B_BGA1  I311
  U5D1   BU80  VCCIN<89>  SKX_EXT_B_BGA1  I311
  U5D1   BU82  VCCIN<88>  SKX_EXT_B_BGA1  I311
  U5D1   BU84  VCCIN<87>  SKX_EXT_B_BGA1  I311
  U5D1   BV61  VCCIN<86>  SKX_EXT_B_BGA1  I311
  U5D1   BV63  VCCIN<85>  SKX_EXT_B_BGA1  I311
  U5D1   BV65  VCCIN<84>  SKX_EXT_B_BGA1  I311
  U5D1   BV67  VCCIN<83>  SKX_EXT_B_BGA1  I311
  U5D1   BV69  VCCIN<82>  SKX_EXT_B_BGA1  I311
  U5D1   BV71  VCCIN<81>  SKX_EXT_B_BGA1  I311
  U5D1   BV73  VCCIN<80>  SKX_EXT_B_BGA1  I311
  U5D1   BV75  VCCIN<79>  SKX_EXT_B_BGA1  I311
  U5D1   BV77  VCCIN<78>  SKX_EXT_B_BGA1  I311
  U5D1   BV79  VCCIN<77>  SKX_EXT_B_BGA1  I311
  U5D1   BV81  VCCIN<76>  SKX_EXT_B_BGA1  I311
  U5D1   BV83  VCCIN<75>  SKX_EXT_B_BGA1  I311
  U5D1   BW60  VCCIN<74>  SKX_EXT_B_BGA1  I311
  U5D1   BW62  VCCIN<73>  SKX_EXT_B_BGA1  I311
  U5D1   BW64  VCCIN<72>  SKX_EXT_B_BGA1  I311
  U5D1   BW66  VCCIN<71>  SKX_EXT_B_BGA1  I311
  U5D1   BW68  VCCIN<70>  SKX_EXT_B_BGA1  I311
  U5D1   BW70  VCCIN<69>  SKX_EXT_B_BGA1  I311
  U5D1   BW84  VCCIN<68>  SKX_EXT_B_BGA1  I311
  U5D1   BY61  VCCIN<67>  SKX_EXT_B_BGA1  I311
  U5D1   BY73  VCCIN<66>  SKX_EXT_B_BGA1  I311
  U5D1   BY75  VCCIN<65>  SKX_EXT_B_BGA1  I311
  U5D1   BY77  VCCIN<64>  SKX_EXT_B_BGA1  I311
  U5D1   BY79  VCCIN<63>  SKX_EXT_B_BGA1  I311
  U5D1   BY81  VCCIN<62>  SKX_EXT_B_BGA1  I311
  U5D1   BY83  VCCIN<61>  SKX_EXT_B_BGA1  I311
  U5D1   CA60  VCCIN<60>  SKX_EXT_B_BGA1  I311
  U5D1   CA62  VCCIN<59>  SKX_EXT_B_BGA1  I311
  U5D1   CA72  VCCIN<58>  SKX_EXT_B_BGA1  I311
  U5D1   CA74  VCCIN<57>  SKX_EXT_B_BGA1  I311
  U5D1   CA76  VCCIN<56>  SKX_EXT_B_BGA1  I311
  U5D1   CA78  VCCIN<55>  SKX_EXT_B_BGA1  I311
  U5D1   CA80  VCCIN<54>  SKX_EXT_B_BGA1  I311
  U5D1   CA82  VCCIN<53>  SKX_EXT_B_BGA1  I311
  U5D1   CA84  VCCIN<52>  SKX_EXT_B_BGA1  I311
  U5D1   CB61  VCCIN<51>  SKX_EXT_B_BGA1  I311
  U5D1   CB73  VCCIN<50>  SKX_EXT_B_BGA1  I311
  U5D1   CB75  VCCIN<49>  SKX_EXT_B_BGA1  I311
  U5D1   CB77  VCCIN<48>  SKX_EXT_B_BGA1  I311
  U5D1   CB79  VCCIN<47>  SKX_EXT_B_BGA1  I311
  U5D1   CB81  VCCIN<46>  SKX_EXT_B_BGA1  I311
  U5D1   CB83  VCCIN<45>  SKX_EXT_B_BGA1  I311
  U5D1   CC60  VCCIN<44>  SKX_EXT_B_BGA1  I311
  U5D1   CC62  VCCIN<43>  SKX_EXT_B_BGA1  I311
  U5D1   CC84  VCCIN<42>  SKX_EXT_B_BGA1  I311
  U5D1   CD61  VCCIN<41>  SKX_EXT_B_BGA1  I311
  U5D1   CD83  VCCIN<40>  SKX_EXT_B_BGA1  I311
  U5D1   CD85  VCCIN<39>  SKX_EXT_B_BGA1  I311
  U5D1   CE60  VCCIN<38>  SKX_EXT_B_BGA1  I311
  U5D1   CE84  VCCIN<37>  SKX_EXT_B_BGA1  I311
  U5D1   CF61  VCCIN<36>  SKX_EXT_B_BGA1  I311
  U5D1   CF85  VCCIN<35>  SKX_EXT_B_BGA1  I311
  U5D1   CG60  VCCIN<34>  SKX_EXT_B_BGA1  I311
  U5D1   CG84  VCCIN<33>  SKX_EXT_B_BGA1  I311
  U5D1   CH61  VCCIN<32>  SKX_EXT_B_BGA1  I311
  U5D1   CH85  VCCIN<31>  SKX_EXT_B_BGA1  I311
  U5D1   CJ60  VCCIN<30>  SKX_EXT_B_BGA1  I311
  U5D1   CK59  VCCIN<29>  SKX_EXT_B_BGA1  I311
  U5D1   CK61  VCCIN<28>  SKX_EXT_B_BGA1  I311
  U5D1   CL58  VCCIN<27>  SKX_EXT_B_BGA1  I311
  U5D1   CL60  VCCIN<26>  SKX_EXT_B_BGA1  I311
  U5D1   CM57  VCCIN<25>  SKX_EXT_B_BGA1  I311
  U5D1   CM59  VCCIN<24>  SKX_EXT_B_BGA1  I311
  U5D1   CN56  VCCIN<23>  SKX_EXT_B_BGA1  I311
  U5D1   CN58  VCCIN<22>  SKX_EXT_B_BGA1  I311
  U5D1   CP33  VCCIN<21>  SKX_EXT_B_BGA1  I311
  U5D1   CP55  VCCIN<20>  SKX_EXT_B_BGA1  I311
  U5D1   CP57  VCCIN<19>  SKX_EXT_B_BGA1  I311
  U5D1   CR34  VCCIN<18>  SKX_EXT_B_BGA1  I311
  U5D1   CR54  VCCIN<17>  SKX_EXT_B_BGA1  I311
  U5D1   CR56  VCCIN<16>  SKX_EXT_B_BGA1  I311
  U5D1   CT37  VCCIN<15>  SKX_EXT_B_BGA1  I311
  U5D1   CT39  VCCIN<14>  SKX_EXT_B_BGA1  I311
  U5D1   CT41  VCCIN<13>  SKX_EXT_B_BGA1  I311
  U5D1   CT53  VCCIN<12>  SKX_EXT_B_BGA1  I311
  U5D1   CT55  VCCIN<11>  SKX_EXT_B_BGA1  I311
  U5D1   CU38  VCCIN<10>  SKX_EXT_B_BGA1  I311
  U5D1   CU40  VCCIN<9>  SKX_EXT_B_BGA1  I311
  U5D1   CU42  VCCIN<8>  SKX_EXT_B_BGA1  I311
  U5D1   CU52  VCCIN<7>  SKX_EXT_B_BGA1  I311
  U5D1   CU54  VCCIN<6>  SKX_EXT_B_BGA1  I311
  U5D1   CV51  VCCIN<5>  SKX_EXT_B_BGA1  I311
  U5D1   CW46  VCCIN<4>  SKX_EXT_B_BGA1  I311
  U5D1   CW48  VCCIN<3>  SKX_EXT_B_BGA1  I311
  U5D1   CW50  VCCIN<2>  SKX_EXT_B_BGA1  I311
  U5D1   CY47  VCCIN<1>  SKX_EXT_B_BGA1  I311
  U5D1   CY49  VCCIN<0>  SKX_EXT_B_BGA1  I311

PVCCIN_CPU1     @BASEBOARD_FAB2_LIB.BASEBOARD_FAB2(SCH_1):PVCCIN_CPU1
  C1D3     1      A  CAP_A       I22
  C1D14    1      A  CAP_A        I9
  C1D24    1      A  CAP_A       I42
  C1E3     1      A  CAP_A       I18
  C1E9     1      A  CAP_A       I58
  C2D1     1      A  CAP_A       I116
  C2D2     1      A  CAP_A       I201
  C2D3     1      A  CAP_A       I202
  C2D12    1      A  CAP_A       I59
  C2D13    1      A  CAP_A       I73
  C2D14    1      A  CAP_A       I76
  C2D15    1      A  CAP_A       I159
  C2D16    1      A  CAP_A       I124
  C2D17    1      A  CAP_A       I114
  C2D19    1      A  CAP_A       I75
  C2D20    1      A  CAP_A       I79
  C2D21    1      A  CAP_A       I65
  C2D22    1      A  CAP_A       I61
  C2D23    1      A  CAP_A       I112
  C2D24    1      A  CAP_A       I80
  C2D25    1      A  CAP_A       I82
  C2D26    1      A  CAP_A       I108
  C2D27    1      A  CAP_A       I66
  C2D30    1      A  CAP_A       I83
  C2D31    1      A  CAP_A       I63
  C2D32    1      A  CAP_A       I90
  C2D33    1      A  CAP_A       I85
  C2D34    1      A  CAP_A       I122
  C2D35    1      A  CAP_A       I161
  C2D36    1      A  CAP_A       I70
  C2D37    1      A  CAP_A       I119
  C2D38    1      A  CAP_A       I160
  C2D45    1      A  CAP_A       I123
  C2D46    1      A  CAP_A       I204
  C2D47    1      A  CAP_A       I203
  C3D1     1      A  CAP_A       I111
  C3D2     1      A  CAP_A       I69
  C3D25    1      A  CAP_A       I205
  C7P1     1      A  CAP         I105
  C7P2     1      A  CAP         I100
  C7P19    1      A  CAP         I215
  C7P20    1      A  CAP         I218
  C8P3     1      A  CAP         I101
  C8P4     1      A  CAP         I88
  C8P10    1      A  CAP         I127
  C8P11    1      A  CAP         I139
  C8P12    1      A  CAP         I107
  C8P13    1      A  CAP         I132
  C8P16    1      A  CAP         I129
  C8P17    1      A  CAP         I133
  C8P18    1      A  CAP         I92
  C8P19    1      A  CAP         I103
  C8P20    1      A  CAP         I89
  C8P21    1      A  CAP         I135
  C8P24    1      A  CAP         I217
  C8P25    1      A  CAP         I136
  C8P26    1      A  CAP         I118
  C8P27    1      A  CAP         I141
  C8P28    1      A  CAP         I137
  C8P29    1      A  CAP         I125
  C8P32    1      A  CAP         I216
  C8P33    1      A  CAP         I131
  C8P34    1      A  CAP         I106
  C9N24    1      A  CAPP        I24
  C9P3     1      A  CAP_A       I59
  C9P5     1      A  CAPP        I14
  C9P8     1      A  CAPP        I12
  C9P10    1      A  CAP_A       I66
  C9P18    1      A  CAPP        I30
  C9P20    1      A  CAP_A       I55
  C9P23    1      A  CAPP        I28
  C9R2     1      A  CAP_A       I67
  C9R3     1      A  CAPP        I26
  C9R8     1      A  CAP_A        I8
  C9R9     1      A  CAPP        I25
  EU1C3    1    VOS  IR354XX_SM  I56
  EU1D1    1    VOS  IR354XX_SM  I71
  EU1D3    1    VOS  IR354XX_SM  I27
  EU1D4    1    VOS  IR354XX_SM  I24
  EU1E2    1    VOS  IR354XX_SM  I20
  L1C2     2    INB  INDUCTOR    I40
  L1D1     2    INB  INDUCTOR    I20
  L1D2     2    INB  INDUCTOR    I11
  L1D3     2    INB  INDUCTOR    I16
  L1E1     2    INB  INDUCTOR    I10
  R1E3     1      A  RES          I7
  R1E4     2      B  RES         I15
  RT8P1    1      A  RES         I49
  U2D1   AF43  VCCIN<267>  SKX_EXT_B_BGA1  I50
  U2D1   AG38  VCCIN<266>  SKX_EXT_B_BGA1  I50
  U2D1   AG40  VCCIN<265>  SKX_EXT_B_BGA1  I50
  U2D1   AG42  VCCIN<264>  SKX_EXT_B_BGA1  I50
  U2D1   AH37  VCCIN<263>  SKX_EXT_B_BGA1  I50
  U2D1   AH39  VCCIN<262>  SKX_EXT_B_BGA1  I50
  U2D1   AH41  VCCIN<261>  SKX_EXT_B_BGA1  I50
  U2D1   AJ36  VCCIN<260>  SKX_EXT_B_BGA1  I50
  U2D1   AK35  VCCIN<259>  SKX_EXT_B_BGA1  I50
  U2D1   AK45  VCCIN<258>  SKX_EXT_B_BGA1  I50
  U2D1   AK47  VCCIN<257>  SKX_EXT_B_BGA1  I50
  U2D1   AK49  VCCIN<256>  SKX_EXT_B_BGA1  I50
  U2D1   AK51  VCCIN<255>  SKX_EXT_B_BGA1  I50
  U2D1   AK53  VCCIN<254>  SKX_EXT_B_BGA1  I50
  U2D1   AL34  VCCIN<253>  SKX_EXT_B_BGA1  I50
  U2D1   AL46  VCCIN<252>  SKX_EXT_B_BGA1  I50
  U2D1   AL48  VCCIN<251>  SKX_EXT_B_BGA1  I50
  U2D1   AL50  VCCIN<250>  SKX_EXT_B_BGA1  I50
  U2D1   AL52  VCCIN<249>  SKX_EXT_B_BGA1  I50
  U2D1   AL54  VCCIN<248>  SKX_EXT_B_BGA1  I50
  U2D1   AM33  VCCIN<247>  SKX_EXT_B_BGA1  I50
  U2D1   AM53  VCCIN<246>  SKX_EXT_B_BGA1  I50
  U2D1   AM55  VCCIN<245>  SKX_EXT_B_BGA1  I50
  U2D1   AN32  VCCIN<244>  SKX_EXT_B_BGA1  I50
  U2D1   AN54  VCCIN<243>  SKX_EXT_B_BGA1  I50
  U2D1   AN56  VCCIN<242>  SKX_EXT_B_BGA1  I50
  U2D1   AP55  VCCIN<241>  SKX_EXT_B_BGA1  I50
  U2D1   AP57  VCCIN<240>  SKX_EXT_B_BGA1  I50
  U2D1   AR56  VCCIN<239>  SKX_EXT_B_BGA1  I50
  U2D1   AR58  VCCIN<238>  SKX_EXT_B_BGA1  I50
  U2D1   AT57  VCCIN<237>  SKX_EXT_B_BGA1  I50
  U2D1   AT59  VCCIN<236>  SKX_EXT_B_BGA1  I50
  U2D1   AU58  VCCIN<235>  SKX_EXT_B_BGA1  I50
  U2D1   AU60  VCCIN<234>  SKX_EXT_B_BGA1  I50
  U2D1   AV59  VCCIN<233>  SKX_EXT_B_BGA1  I50
  U2D1   AV61  VCCIN<232>  SKX_EXT_B_BGA1  I50
  U2D1   AW60  VCCIN<231>  SKX_EXT_B_BGA1  I50
  U2D1   AY61  VCCIN<230>  SKX_EXT_B_BGA1  I50
  U2D1   BA60  VCCIN<229>  SKX_EXT_B_BGA1  I50
  U2D1   BB61  VCCIN<228>  SKX_EXT_B_BGA1  I50
  U2D1   BB85  VCCIN<227>  SKX_EXT_B_BGA1  I50
  U2D1   BC60  VCCIN<226>  SKX_EXT_B_BGA1  I50
  U2D1   BC62  VCCIN<225>  SKX_EXT_B_BGA1  I50
  U2D1   BC84  VCCIN<224>  SKX_EXT_B_BGA1  I50
  U2D1   BD61  VCCIN<223>  SKX_EXT_B_BGA1  I50
  U2D1   BD73  VCCIN<222>  SKX_EXT_B_BGA1  I50
  U2D1   BD75  VCCIN<221>  SKX_EXT_B_BGA1  I50
  U2D1   BD77  VCCIN<220>  SKX_EXT_B_BGA1  I50
  U2D1   BD79  VCCIN<219>  SKX_EXT_B_BGA1  I50
  U2D1   BD81  VCCIN<218>  SKX_EXT_B_BGA1  I50
  U2D1   BD83  VCCIN<217>  SKX_EXT_B_BGA1  I50
  U2D1   BD85  VCCIN<216>  SKX_EXT_B_BGA1  I50
  U2D1   BE60  VCCIN<215>  SKX_EXT_B_BGA1  I50
  U2D1   BE62  VCCIN<214>  SKX_EXT_B_BGA1  I50
  U2D1   BE72  VCCIN<213>  SKX_EXT_B_BGA1  I50
  U2D1   BE74  VCCIN<212>  SKX_EXT_B_BGA1  I50
  U2D1   BE76  VCCIN<211>  SKX_EXT_B_BGA1  I50
  U2D1   BE78  VCCIN<210>  SKX_EXT_B_BGA1  I50
  U2D1   BE80  VCCIN<209>  SKX_EXT_B_BGA1  I50
  U2D1   BE82  VCCIN<208>  SKX_EXT_B_BGA1  I50
  U2D1   BE84  VCCIN<207>  SKX_EXT_B_BGA1  I50
  U2D1   BF61  VCCIN<206>  SKX_EXT_B_BGA1  I50
  U2D1   BF73  VCCIN<205>  SKX_EXT_B_BGA1  I50
  U2D1   BF75  VCCIN<204>  SKX_EXT_B_BGA1  I50
  U2D1   BF77  VCCIN<203>  SKX_EXT_B_BGA1  I50
  U2D1   BF79  VCCIN<202>  SKX_EXT_B_BGA1  I50
  U2D1   BF81  VCCIN<201>  SKX_EXT_B_BGA1  I50
  U2D1   BF83  VCCIN<200>  SKX_EXT_B_BGA1  I50
  U2D1   BF85  VCCIN<199>  SKX_EXT_B_BGA1  I50
  U2D1   BG60  VCCIN<198>  SKX_EXT_B_BGA1  I50
  U2D1   BG62  VCCIN<197>  SKX_EXT_B_BGA1  I50
  U2D1   BG64  VCCIN<196>  SKX_EXT_B_BGA1  I50
  U2D1   BG66  VCCIN<195>  SKX_EXT_B_BGA1  I50
  U2D1   BG68  VCCIN<194>  SKX_EXT_B_BGA1  I50
  U2D1   BG70  VCCIN<193>  SKX_EXT_B_BGA1  I50
  U2D1   BG84  VCCIN<192>  SKX_EXT_B_BGA1  I50
  U2D1   BH61  VCCIN<191>  SKX_EXT_B_BGA1  I50
  U2D1   BH63  VCCIN<190>  SKX_EXT_B_BGA1  I50
  U2D1   BH65  VCCIN<189>  SKX_EXT_B_BGA1  I50
  U2D1   BH67  VCCIN<188>  SKX_EXT_B_BGA1  I50
  U2D1   BH69  VCCIN<187>  SKX_EXT_B_BGA1  I50
  U2D1   BH71  VCCIN<186>  SKX_EXT_B_BGA1  I50
  U2D1   BH73  VCCIN<185>  SKX_EXT_B_BGA1  I50
  U2D1   BH75  VCCIN<184>  SKX_EXT_B_BGA1  I50
  U2D1   BH77  VCCIN<183>  SKX_EXT_B_BGA1  I50
  U2D1   BH79  VCCIN<182>  SKX_EXT_B_BGA1  I50
  U2D1   BH81  VCCIN<181>  SKX_EXT_B_BGA1  I50
  U2D1   BH83  VCCIN<180>  SKX_EXT_B_BGA1  I50
  U2D1   BJ60  VCCIN<179>  SKX_EXT_B_BGA1  I50
  U2D1   BJ62  VCCIN<178>  SKX_EXT_B_BGA1  I50
  U2D1   BJ64  VCCIN<177>  SKX_EXT_B_BGA1  I50
  U2D1   BJ66  VCCIN<176>  SKX_EXT_B_BGA1  I50
  U2D1   BJ68  VCCIN<175>  SKX_EXT_B_BGA1  I50
  U2D1   BJ70  VCCIN<174>  SKX_EXT_B_BGA1  I50
  U2D1   BJ72  VCCIN<173>  SKX_EXT_B_BGA1  I50
  U2D1   BJ74  VCCIN<172>  SKX_EXT_B_BGA1  I50
  U2D1   BJ76  VCCIN<171>  SKX_EXT_B_BGA1  I50
  U2D1   BJ78  VCCIN<170>  SKX_EXT_B_BGA1  I50
  U2D1   BJ80  VCCIN<169>  SKX_EXT_B_BGA1  I50
  U2D1   BJ82  VCCIN<168>  SKX_EXT_B_BGA1  I50
  U2D1   BJ84  VCCIN<167>  SKX_EXT_B_BGA1  I50
  U2D1   BK61  VCCIN<166>  SKX_EXT_B_BGA1  I50
  U2D1   BK63  VCCIN<165>  SKX_EXT_B_BGA1  I50
  U2D1   BK65  VCCIN<164>  SKX_EXT_B_BGA1  I50
  U2D1   BK67  VCCIN<163>  SKX_EXT_B_BGA1  I50
  U2D1   BK69  VCCIN<162>  SKX_EXT_B_BGA1  I50
  U2D1   BK71  VCCIN<161>  SKX_EXT_B_BGA1  I50
  U2D1   BK73  VCCIN<160>  SKX_EXT_B_BGA1  I50
  U2D1   BK75  VCCIN<159>  SKX_EXT_B_BGA1  I50
  U2D1   BK77  VCCIN<158>  SKX_EXT_B_BGA1  I50
  U2D1   BK79  VCCIN<157>  SKX_EXT_B_BGA1  I50
  U2D1   BK81  VCCIN<156>  SKX_EXT_B_BGA1  I50
  U2D1   BK83  VCCIN<155>  SKX_EXT_B_BGA1  I50
  U2D1   BL60  VCCIN<154>  SKX_EXT_B_BGA1  I50
  U2D1   BL62  VCCIN<153>  SKX_EXT_B_BGA1  I50
  U2D1   BL84  VCCIN<152>  SKX_EXT_B_BGA1  I50
  U2D1   BM61  VCCIN<151>  SKX_EXT_B_BGA1  I50
  U2D1   BM63  VCCIN<150>  SKX_EXT_B_BGA1  I50
  U2D1   BM65  VCCIN<149>  SKX_EXT_B_BGA1  I50
  U2D1   BM67  VCCIN<148>  SKX_EXT_B_BGA1  I50
  U2D1   BM69  VCCIN<147>  SKX_EXT_B_BGA1  I50
  U2D1   BM71  VCCIN<146>  SKX_EXT_B_BGA1  I50
  U2D1   BM73  VCCIN<145>  SKX_EXT_B_BGA1  I50
  U2D1   BM75  VCCIN<144>  SKX_EXT_B_BGA1  I50
  U2D1   BM77  VCCIN<143>  SKX_EXT_B_BGA1  I50
  U2D1   BM79  VCCIN<142>  SKX_EXT_B_BGA1  I50
  U2D1   BM81  VCCIN<141>  SKX_EXT_B_BGA1  I50
  U2D1   BM83  VCCIN<140>  SKX_EXT_B_BGA1  I50
  U2D1   BN60  VCCIN<139>  SKX_EXT_B_BGA1  I50
  U2D1   BN62  VCCIN<138>  SKX_EXT_B_BGA1  I50
  U2D1   BN64  VCCIN<137>  SKX_EXT_B_BGA1  I50
  U2D1   BN66  VCCIN<136>  SKX_EXT_B_BGA1  I50
  U2D1   BN68  VCCIN<135>  SKX_EXT_B_BGA1  I50
  U2D1   BN70  VCCIN<134>  SKX_EXT_B_BGA1  I50
  U2D1   BN72  VCCIN<133>  SKX_EXT_B_BGA1  I50
  U2D1   BN74  VCCIN<132>  SKX_EXT_B_BGA1  I50
  U2D1   BN76  VCCIN<131>  SKX_EXT_B_BGA1  I50
  U2D1   BN78  VCCIN<130>  SKX_EXT_B_BGA1  I50
  U2D1   BN80  VCCIN<129>  SKX_EXT_B_BGA1  I51
  U2D1   BN82  VCCIN<128>  SKX_EXT_B_BGA1  I51
  U2D1   BN84  VCCIN<127>  SKX_EXT_B_BGA1  I51
  U2D1   BP61  VCCIN<126>  SKX_EXT_B_BGA1  I51
  U2D1   BP63  VCCIN<125>  SKX_EXT_B_BGA1  I51
  U2D1   BP65  VCCIN<124>  SKX_EXT_B_BGA1  I51
  U2D1   BP67  VCCIN<123>  SKX_EXT_B_BGA1  I51
  U2D1   BP69  VCCIN<122>  SKX_EXT_B_BGA1  I51
  U2D1   BP71  VCCIN<121>  SKX_EXT_B_BGA1  I51
  U2D1   BP73  VCCIN<120>  SKX_EXT_B_BGA1  I51
  U2D1   BP75  VCCIN<119>  SKX_EXT_B_BGA1  I51
  U2D1   BP77  VCCIN<118>  SKX_EXT_B_BGA1  I51
  U2D1   BP79  VCCIN<117>  SKX_EXT_B_BGA1  I51
  U2D1   BP81  VCCIN<116>  SKX_EXT_B_BGA1  I51
  U2D1   BP83  VCCIN<115>  SKX_EXT_B_BGA1  I51
  U2D1   BR60  VCCIN<114>  SKX_EXT_B_BGA1  I51
  U2D1   BR62  VCCIN<113>  SKX_EXT_B_BGA1  I51
  U2D1   BR84  VCCIN<112>  SKX_EXT_B_BGA1  I51
  U2D1   BT61  VCCIN<111>  SKX_EXT_B_BGA1  I51
  U2D1   BT63  VCCIN<110>  SKX_EXT_B_BGA1  I51
  U2D1   BT65  VCCIN<109>  SKX_EXT_B_BGA1  I51
  U2D1   BT67  VCCIN<108>  SKX_EXT_B_BGA1  I51
  U2D1   BT69  VCCIN<107>  SKX_EXT_B_BGA1  I51
  U2D1   BT71  VCCIN<106>  SKX_EXT_B_BGA1  I51
  U2D1   BT73  VCCIN<105>  SKX_EXT_B_BGA1  I51
  U2D1   BT75  VCCIN<104>  SKX_EXT_B_BGA1  I51
  U2D1   BT77  VCCIN<103>  SKX_EXT_B_BGA1  I51
  U2D1   BT79  VCCIN<102>  SKX_EXT_B_BGA1  I51
  U2D1   BT81  VCCIN<101>  SKX_EXT_B_BGA1  I51
  U2D1   BT83  VCCIN<100>  SKX_EXT_B_BGA1  I51
  U2D1   BU60  VCCIN<99>  SKX_EXT_B_BGA1  I51
  U2D1   BU62  VCCIN<98>  SKX_EXT_B_BGA1  I51
  U2D1   BU64  VCCIN<97>  SKX_EXT_B_BGA1  I51
  U2D1   BU66  VCCIN<96>  SKX_EXT_B_BGA1  I51
  U2D1   BU68  VCCIN<95>  SKX_EXT_B_BGA1  I51
  U2D1   BU70  VCCIN<94>  SKX_EXT_B_BGA1  I51
  U2D1   BU72  VCCIN<93>  SKX_EXT_B_BGA1  I51
  U2D1   BU74  VCCIN<92>  SKX_EXT_B_BGA1  I51
  U2D1   BU76  VCCIN<91>  SKX_EXT_B_BGA1  I51
  U2D1   BU78  VCCIN<90>  SKX_EXT_B_BGA1  I51
  U2D1   BU80  VCCIN<89>  SKX_EXT_B_BGA1  I51
  U2D1   BU82  VCCIN<88>  SKX_EXT_B_BGA1  I51
  U2D1   BU84  VCCIN<87>  SKX_EXT_B_BGA1  I51
  U2D1   BV61  VCCIN<86>  SKX_EXT_B_BGA1  I51
  U2D1   BV63  VCCIN<85>  SKX_EXT_B_BGA1  I51
  U2D1   BV65  VCCIN<84>  SKX_EXT_B_BGA1  I51
  U2D1   BV67  VCCIN<83>  SKX_EXT_B_BGA1  I51
  U2D1   BV69  VCCIN<82>  SKX_EXT_B_BGA1  I51
  U2D1   BV71  VCCIN<81>  SKX_EXT_B_BGA1  I51
  U2D1   BV73  VCCIN<80>  SKX_EXT_B_BGA1  I51
  U2D1   BV75  VCCIN<79>  SKX_EXT_B_BGA1  I51
  U2D1   BV77  VCCIN<78>  SKX_EXT_B_BGA1  I51
  U2D1   BV79  VCCIN<77>  SKX_EXT_B_BGA1  I51
  U2D1   BV81  VCCIN<76>  SKX_EXT_B_BGA1  I51
  U2D1   BV83  VCCIN<75>  SKX_EXT_B_BGA1  I51
  U2D1   BW60  VCCIN<74>  SKX_EXT_B_BGA1  I51
  U2D1   BW62  VCCIN<73>  SKX_EXT_B_BGA1  I51
  U2D1   BW64  VCCIN<72>  SKX_EXT_B_BGA1  I51
  U2D1   BW66  VCCIN<71>  SKX_EXT_B_BGA1  I51
  U2D1   BW68  VCCIN<70>  SKX_EXT_B_BGA1  I51
  U2D1   BW70  VCCIN<69>  SKX_EXT_B_BGA1  I51
  U2D1   BW84  VCCIN<68>  SKX_EXT_B_BGA1  I51
  U2D1   BY61  VCCIN<67>  SKX_EXT_B_BGA1  I51
  U2D1   BY73  VCCIN<66>  SKX_EXT_B_BGA1  I51
  U2D1   BY75  VCCIN<65>  SKX_EXT_B_BGA1  I51
  U2D1   BY77  VCCIN<64>  SKX_EXT_B_BGA1  I51
  U2D1   BY79  VCCIN<63>  SKX_EXT_B_BGA1  I51
  U2D1   BY81  VCCIN<62>  SKX_EXT_B_BGA1  I51
  U2D1   BY83  VCCIN<61>  SKX_EXT_B_BGA1  I51
  U2D1   CA60  VCCIN<60>  SKX_EXT_B_BGA1  I51
  U2D1   CA62  VCCIN<59>  SKX_EXT_B_BGA1  I51
  U2D1   CA72  VCCIN<58>  SKX_EXT_B_BGA1  I51
  U2D1   CA74  VCCIN<57>  SKX_EXT_B_BGA1  I51
  U2D1   CA76  VCCIN<56>  SKX_EXT_B_BGA1  I51
  U2D1   CA78  VCCIN<55>  SKX_EXT_B_BGA1  I51
  U2D1   CA80  VCCIN<54>  SKX_EXT_B_BGA1  I51
  U2D1   CA82  VCCIN<53>  SKX_EXT_B_BGA1  I51
  U2D1   CA84  VCCIN<52>  SKX_EXT_B_BGA1  I51
  U2D1   CB61  VCCIN<51>  SKX_EXT_B_BGA1  I51
  U2D1   CB73  VCCIN<50>  SKX_EXT_B_BGA1  I51
  U2D1   CB75  VCCIN<49>  SKX_EXT_B_BGA1  I51
  U2D1   CB77  VCCIN<48>  SKX_EXT_B_BGA1  I51
  U2D1   CB79  VCCIN<47>  SKX_EXT_B_BGA1  I51
  U2D1   CB81  VCCIN<46>  SKX_EXT_B_BGA1  I51
  U2D1   CB83  VCCIN<45>  SKX_EXT_B_BGA1  I51
  U2D1   CC60  VCCIN<44>  SKX_EXT_B_BGA1  I51
  U2D1   CC62  VCCIN<43>  SKX_EXT_B_BGA1  I51
  U2D1   CC84  VCCIN<42>  SKX_EXT_B_BGA1  I51
  U2D1   CD61  VCCIN<41>  SKX_EXT_B_BGA1  I51
  U2D1   CD83  VCCIN<40>  SKX_EXT_B_BGA1  I51
  U2D1   CD85  VCCIN<39>  SKX_EXT_B_BGA1  I51
  U2D1   CE60  VCCIN<38>  SKX_EXT_B_BGA1  I51
  U2D1   CE84  VCCIN<37>  SKX_EXT_B_BGA1  I51
  U2D1   CF61  VCCIN<36>  SKX_EXT_B_BGA1  I51
  U2D1   CF85  VCCIN<35>  SKX_EXT_B_BGA1  I51
  U2D1   CG60  VCCIN<34>  SKX_EXT_B_BGA1  I51
  U2D1   CG84  VCCIN<33>  SKX_EXT_B_BGA1  I51
  U2D1   CH61  VCCIN<32>  SKX_EXT_B_BGA1  I51
  U2D1   CH85  VCCIN<31>  SKX_EXT_B_BGA1  I51
  U2D1   CJ60  VCCIN<30>  SKX_EXT_B_BGA1  I51
  U2D1   CK59  VCCIN<29>  SKX_EXT_B_BGA1  I51
  U2D1   CK61  VCCIN<28>  SKX_EXT_B_BGA1  I51
  U2D1   CL58  VCCIN<27>  SKX_EXT_B_BGA1  I51
  U2D1   CL60  VCCIN<26>  SKX_EXT_B_BGA1  I51
  U2D1   CM57  VCCIN<25>  SKX_EXT_B_BGA1  I51
  U2D1   CM59  VCCIN<24>  SKX_EXT_B_BGA1  I51
  U2D1   CN56  VCCIN<23>  SKX_EXT_B_BGA1  I51
  U2D1   CN58  VCCIN<22>  SKX_EXT_B_BGA1  I51
  U2D1   CP33  VCCIN<21>  SKX_EXT_B_BGA1  I51
  U2D1   CP55  VCCIN<20>  SKX_EXT_B_BGA1  I51
  U2D1   CP57  VCCIN<19>  SKX_EXT_B_BGA1  I51
  U2D1   CR34  VCCIN<18>  SKX_EXT_B_BGA1  I51
  U2D1   CR54  VCCIN<17>  SKX_EXT_B_BGA1  I51
  U2D1   CR56  VCCIN<16>  SKX_EXT_B_BGA1  I51
  U2D1   CT37  VCCIN<15>  SKX_EXT_B_BGA1  I51
  U2D1   CT39  VCCIN<14>  SKX_EXT_B_BGA1  I51
  U2D1   CT41  VCCIN<13>  SKX_EXT_B_BGA1  I51
  U2D1   CT53  VCCIN<12>  SKX_EXT_B_BGA1  I51
  U2D1   CT55  VCCIN<11>  SKX_EXT_B_BGA1  I51
  U2D1   CU38  VCCIN<10>  SKX_EXT_B_BGA1  I51
  U2D1   CU40  VCCIN<9>  SKX_EXT_B_BGA1  I51
  U2D1   CU42  VCCIN<8>  SKX_EXT_B_BGA1  I51
  U2D1   CU52  VCCIN<7>  SKX_EXT_B_BGA1  I51
  U2D1   CU54  VCCIN<6>  SKX_EXT_B_BGA1  I51
  U2D1   CV51  VCCIN<5>  SKX_EXT_B_BGA1  I51
  U2D1   CW46  VCCIN<4>  SKX_EXT_B_BGA1  I51
  U2D1   CW48  VCCIN<3>  SKX_EXT_B_BGA1  I51
  U2D1   CW50  VCCIN<2>  SKX_EXT_B_BGA1  I51
  U2D1   CY47  VCCIN<1>  SKX_EXT_B_BGA1  I51
  U2D1   CY49  VCCIN<0>  SKX_EXT_B_BGA1  I51

PVCCIN_PVSA_CPU0_IINSEN   @BASEBOARD_FAB2_LIB.BASEBOARD_FAB2(SCH_1):PVCCIN_PVSA_CPU0_IINSEN
  EU4D4   46  IINSEN  PXE1610B_QFN  I155
  U4C1     6    OUT  ADM4073_SM  I53

PVCCIN_PVSA_CPU1_IINSEN   @BASEBOARD_FAB2_LIB.BASEBOARD_FAB2(SCH_1):PVCCIN_PVSA_CPU1_IINSEN
  EU1C2   46  IINSEN  PXE1610B_QFN  I130
  U1B3     6    OUT  ADM4073_SM  I52

PVCCIOMCP_CPU0   @BASEBOARD_FAB2_LIB.BASEBOARD_FAB2(SCH_1):PVCCIOMCP_CPU0
  C3M46    1      A  CAP_A       I99
  C3N14    1      A  CAPP        I101
  C3N40    1      A  CAP_A       I86
  J6B1   C17  IOC17  SCONN120_H61426002_SM  I56
  J6B1   C18  IOC18  SCONN120_H61426002_SM  I56
  J6B1   C19  IOC19  SCONN120_H61426002_SM  I56
  J6B1   D15  IOD15  SCONN120_H61426002_SM  I56
  J6B1   D16  IOD16  SCONN120_H61426002_SM  I56
  J6B1   D17  IOD17  SCONN120_H61426002_SM  I56
  J6B1   D18  IOD18  SCONN120_H61426002_SM  I56
  J6B1   D19  IOD19  SCONN120_H61426002_SM  I56
  J6B1   E15  IOE15  SCONN120_H61426002_SM  I56
  J6B1   E16  IOE16  SCONN120_H61426002_SM  I56
  J6B1   E17  IOE17  SCONN120_H61426002_SM  I56
  J6B1   E18  IOE18  SCONN120_H61426002_SM  I56
  J6B1   E19  IOE19  SCONN120_H61426002_SM  I56
  J6B1   F15  IOF15  SCONN120_H61426002_SM  I56
  J6B1   F16  IOF16  SCONN120_H61426002_SM  I56
  J6B1   F17  IOF17  SCONN120_H61426002_SM  I56
  J6B1   F18  IOF18  SCONN120_H61426002_SM  I56
  J6B1   F19  IOF19  SCONN120_H61426002_SM  I56
  U5D1   BM11  CD_VCCP<15>  SKX_EXT_B_BGA1  I34
  U5D1   BN12  CD_VCCP<14>  SKX_EXT_B_BGA1  I34
  U5D1   BN14  CD_VCCP<13>  SKX_EXT_B_BGA1  I34
  U5D1   BP11  CD_VCCP<12>  SKX_EXT_B_BGA1  I34
  U5D1   BP13  CD_VCCP<11>  SKX_EXT_B_BGA1  I34
  U5D1   BP15  CD_VCCP<10>  SKX_EXT_B_BGA1  I34
  U5D1   BR12  CD_VCCP<9>  SKX_EXT_B_BGA1  I34
  U5D1   BR14  CD_VCCP<8>  SKX_EXT_B_BGA1  I34
  U5D1   BT11  CD_VCCP<7>  SKX_EXT_B_BGA1  I34
  U5D1   BT13  CD_VCCP<6>  SKX_EXT_B_BGA1  I34
  U5D1   BT15  CD_VCCP<5>  SKX_EXT_B_BGA1  I34
  U5D1   BU12  CD_VCCP<4>  SKX_EXT_B_BGA1  I34
  U5D1   BU14  CD_VCCP<3>  SKX_EXT_B_BGA1  I34
  U5D1   BV11  CD_VCCP<2>  SKX_EXT_B_BGA1  I34
  U5D1   BV13  CD_VCCP<1>  SKX_EXT_B_BGA1  I34
  U5D1   BV15  CD_VCCP<0>  SKX_EXT_B_BGA1  I34

PVCCIOMCP_CPU1   @BASEBOARD_FAB2_LIB.BASEBOARD_FAB2(SCH_1):PVCCIOMCP_CPU1
  C3C1     1      A  CAP_A       I38
  C3C2     1      A  CAP_A       I31
  C4C1     1      A  CAPP        I29
  J4B2   C17  IOC17  SCONN120_H61426002_SM  I46
  J4B2   C18  IOC18  SCONN120_H61426002_SM  I46
  J4B2   C19  IOC19  SCONN120_H61426002_SM  I46
  J4B2   D15  IOD15  SCONN120_H61426002_SM  I46
  J4B2   D16  IOD16  SCONN120_H61426002_SM  I46
  J4B2   D17  IOD17  SCONN120_H61426002_SM  I46
  J4B2   D18  IOD18  SCONN120_H61426002_SM  I46
  J4B2   D19  IOD19  SCONN120_H61426002_SM  I46
  J4B2   E15  IOE15  SCONN120_H61426002_SM  I46
  J4B2   E16  IOE16  SCONN120_H61426002_SM  I46
  J4B2   E17  IOE17  SCONN120_H61426002_SM  I46
  J4B2   E18  IOE18  SCONN120_H61426002_SM  I46
  J4B2   E19  IOE19  SCONN120_H61426002_SM  I46
  J4B2   F15  IOF15  SCONN120_H61426002_SM  I46
  J4B2   F16  IOF16  SCONN120_H61426002_SM  I46
  J4B2   F17  IOF17  SCONN120_H61426002_SM  I46
  J4B2   F18  IOF18  SCONN120_H61426002_SM  I46
  J4B2   F19  IOF19  SCONN120_H61426002_SM  I46
  U2D1   BM11  CD_VCCP<15>  SKX_EXT_B_BGA1  I33
  U2D1   BN12  CD_VCCP<14>  SKX_EXT_B_BGA1  I33
  U2D1   BN14  CD_VCCP<13>  SKX_EXT_B_BGA1  I33
  U2D1   BP11  CD_VCCP<12>  SKX_EXT_B_BGA1  I33
  U2D1   BP13  CD_VCCP<11>  SKX_EXT_B_BGA1  I33
  U2D1   BP15  CD_VCCP<10>  SKX_EXT_B_BGA1  I33
  U2D1   BR12  CD_VCCP<9>  SKX_EXT_B_BGA1  I33
  U2D1   BR14  CD_VCCP<8>  SKX_EXT_B_BGA1  I33
  U2D1   BT11  CD_VCCP<7>  SKX_EXT_B_BGA1  I33
  U2D1   BT13  CD_VCCP<6>  SKX_EXT_B_BGA1  I33
  U2D1   BT15  CD_VCCP<5>  SKX_EXT_B_BGA1  I33
  U2D1   BU12  CD_VCCP<4>  SKX_EXT_B_BGA1  I33
  U2D1   BU14  CD_VCCP<3>  SKX_EXT_B_BGA1  I33
  U2D1   BV11  CD_VCCP<2>  SKX_EXT_B_BGA1  I33
  U2D1   BV13  CD_VCCP<1>  SKX_EXT_B_BGA1  I33
  U2D1   BV15  CD_VCCP<0>  SKX_EXT_B_BGA1  I33

PVCCIO_CPU0     @BASEBOARD_FAB2_LIB.BASEBOARD_FAB2(SCH_1):PVCCIO_CPU0
  C1T21    1      A  CAP_A       I28
  C3N26    1      A  CAPP        I17
  C3N35    1      A  CAPP        I18
  C3N38    1      A  CAPP        I16
  C4P1     1      A  CAP         I10
  C4P6     1      A  CAP_A       I164
  C4P8     1      A  CAP_A       I178
  C4P9     1      A  CAP         I12
  C4P10    1      A  CAP         I17
  C6D3     1      A  CAP_A       I80
  C6D4     1      A  CAP_A       I74
  C6D6     1      A  CAP_A       I81
  C6D7     1      A  CAP_A       I72
  C6D9     1      A  CAP_A       I145
  C6D10    1      A  CAP_A       I147
  C6F2     1      A  CAP_A        I2
  C7C6     1      A  CAP_A       I23
  C7C10    1      A  CAP_A       I77
  C7E1     1      A  CAP_A       I23
  EU7C1    1    VOS  IR354XX_SM  I101
  J6B1    F1   IOF1  SCONN120_H61426002_SM  I56
  L7C2     2    INB  INDUCTOR    I25
  R1L15    1      A  RES         I60
  R1L17    2      B  RES         I56
  R1M3     1      A  RES         I51
  R1M4     1      A  RES         I54
  R1U43    1      A  RES         I25
  R2T19    1      A  RES         I63
  R2T26    1      A  RES         I87
  R2T36    1      A  RES         I97
  R2T37    1      A  RES         I94
  R2T72    1      A  RES         I143
  R2U40    1      A  RES         I53
  R2U41    1      A  RES         I54
  R3L11    1      A  RES          I7
  R3L13    1      A  RES         I47
  R3N21    2      B  RES         I74
  R3P13    1      A  RES         I17
  R3P17    1      A  RES         I28
  R3P45    1      A  RES         I39
  R3P60    1      A  RES         I67
  R3R13    1      A  RES         I65
  R3T11    1      A  RES         I330
  R3U2     1      A  RES         I295
  R4E9     1      A  RES         I52
  R4E10    1      A  RES         I20
  R4P12    1      A  RES         I57
  R4P14    1      A  RES         I53
  R4P15    1      A  RES         I53
  R4P17    2      B  RES         I58
  R4P20    2      B  RES         I59
  R4P21    1      A  RES         I72
  R4P23    1      A  RES         I58
  R4P24    1      A  RES         I59
  R4R2     1      A  RES         I101
  R4R3     1      A  RES         I79
  R4R4     1      A  RES         I42
  R4T5     1      A  RES         I19
  R4T6     1      A  RES         I17
  R5D3     1      A  RES         I29
  R5D4     1      A  RES         I32
  R5D6     1      A  RES         I312
  R6B1     1      A  RES         I161
  R6B2     1      A  RES         I159
  R6D7     1      A  RES         I31
  R6D8     1      A  RES          I3
  R6D9     1      A  RES         I64
  R6D10    1      A  RES         I49
  R6D12    1      A  RES          I2
  R6D13    1      A  RES         I33
  R6D14    1      A  RES         I52
  R6D15    1      A  RES         I48
  R6N1     2      B  RES         I164
  R6N2     2      B  RES         I163
  R6P16    1      A  RES         I132
  R6P46    1      A  RES         I49
  R6T8     1      A  RES         I121
  R6T9     1      A  RES         I120
  R7C3     1      A  RES         I78
  R7C17    1      A  RES         I28
  R7C22    1      A  RES         I14
  R7D33    1      A  RES         I51
  R7E2     1      A  RES         I19
  R7P18    1      A  RES         I100
  R7P20    1      A  RES         I44
  R7P27    1      A  RES         I65
  R7P30    1      A  RES         I50
  R9A4     2      B  RES         I55
  U5D1   AA10  VCCIO<45>  SKX_EXT_B_BGA1  I34
  U5D1   AC4  VCCIO<43>  SKX_EXT_B_BGA1  I34
  U5D1   AC20  VCCIO<44>  SKX_EXT_B_BGA1  I34
  U5D1   AC36  VCCIO<97>  SKX_EXT_B_BGA1  I34
  U5D1   AD35  VCCIO<99>  SKX_EXT_B_BGA1  I34
  U5D1   AD37  VCCIO<96>  SKX_EXT_B_BGA1  I34
  U5D1   AE10  VCCIO<1>  SKX_EXT_B_BGA1  I127
  U5D1   AE34  VCCIO<100>  SKX_EXT_B_BGA1  I34
  U5D1   AE36  VCCIO<95>  SKX_EXT_B_BGA1  I34
  U5D1   AF5  VCCIO<2>  SKX_EXT_B_BGA1  I127
  U5D1   AF35  VCCIO<98>  SKX_EXT_B_BGA1  I34
  U5D1   AG34  VCCIO<101>  SKX_EXT_B_BGA1  I34
  U5D1   AH9  VCCIO<42>  SKX_EXT_B_BGA1  I34
  U5D1   AL28  VCCIO<103>  SKX_EXT_B_BGA1  I34
  U5D1   AM5  VCCIO<4>  SKX_EXT_B_BGA1  I127
  U5D1   AM29  VCCIO<102>  SKX_EXT_B_BGA1  I34
  U5D1   AN10  VCCIO<40>  SKX_EXT_B_BGA1  I34
  U5D1   AR28  VCCIO<104>  SKX_EXT_B_BGA1  I34
  U5D1   AT5  VCCIO<5>  SKX_EXT_B_BGA1  I127
  U5D1   AT7  VCCIO<6>  SKX_EXT_B_BGA1  I127
  U5D1   AT11  VCCIO<38>  SKX_EXT_B_BGA1  I34
  U5D1   AV27  VCCIO<80>  SKX_EXT_B_BGA1  I34
  U5D1   AW6  VCCIO<37>  SKX_EXT_B_BGA1  I34
  U5D1   AW26  VCCIO<79>  SKX_EXT_B_BGA1  I34
  U5D1   AY11  VCCIO<36>  SKX_EXT_B_BGA1  I34
  U5D1   AY27  VCCIO<78>  SKX_EXT_B_BGA1  I34
  U5D1   BA24  VCCIO<35>  SKX_EXT_B_BGA1  I34
  U5D1   BA26  VCCIO<77>  SKX_EXT_B_BGA1  I34
  U5D1   BB5  VCCIO<34>  SKX_EXT_B_BGA1  I34
  U5D1   BB27  VCCIO<76>  SKX_EXT_B_BGA1  I34
  U5D1   BC26  VCCIO<75>  SKX_EXT_B_BGA1  I34
  U5D1   BE24  VCCIO<7>  SKX_EXT_B_BGA1  I127
  U5D1   BF23  VCCIO<32>  SKX_EXT_B_BGA1  I34
  U5D1   BF27  VCCIO<94>  SKX_EXT_B_BGA1  I34
  U5D1   BG26  VCCIO<93>  SKX_EXT_B_BGA1  I34
  U5D1   BH25  VCCIO<92>  SKX_EXT_B_BGA1  I34
  U5D1   BH27  VCCIO<91>  SKX_EXT_B_BGA1  I34
  U5D1   BJ24  VCCIO<31>  SKX_EXT_B_BGA1  I34
  U5D1   BJ26  VCCIO<90>  SKX_EXT_B_BGA1  I34
  U5D1   BK25  VCCIO<89>  SKX_EXT_B_BGA1  I34
  U5D1   BK27  VCCIO<88>  SKX_EXT_B_BGA1  I34
  U5D1   BL26  VCCIO<87>  SKX_EXT_B_BGA1  I34
  U5D1   BM27  VCCIO<86>  SKX_EXT_B_BGA1  I34
  U5D1   BP25  VCCIO<30>  SKX_EXT_B_BGA1  I34
  U5D1   CB13  VCCIO<29>  SKX_EXT_B_BGA1  I34
  U5D1   CB17  VCCIO<28>  SKX_EXT_B_BGA1  I34
  U5D1   CC26  VCCIO<83>  SKX_EXT_B_BGA1  I34
  U5D1   CD9  VCCIO<27>  SKX_EXT_B_BGA1  I34
  U5D1   CD27  VCCIO<82>  SKX_EXT_B_BGA1  I34
  U5D1   CE18  VCCIO<26>  SKX_EXT_B_BGA1  I34
  U5D1   CF5  VCCIO<9>  SKX_EXT_B_BGA1  I127
  U5D1   CF27  VCCIO<81>  SKX_EXT_B_BGA1  I34
  U5D1   CG14  VCCIO<10>  SKX_EXT_B_BGA1  I127
  U5D1   CH9  VCCIO<24>  SKX_EXT_B_BGA1  I34
  U5D1   CH27  VCCIO<85>  SKX_EXT_B_BGA1  I34
  U5D1   CJ28  VCCIO<84>  SKX_EXT_B_BGA1  I34
  U5D1   CK5  VCCIO<22>  SKX_EXT_B_BGA1  I34
  U5D1   CL12  VCCIO<21>  SKX_EXT_B_BGA1  I34
  U5D1   CL20  VCCIO<11>  SKX_EXT_B_BGA1  I127
  U5D1   CM15  VCCIO<20>  SKX_EXT_B_BGA1  I34
  U5D1   CN6  VCCIO<19>  SKX_EXT_B_BGA1  I127
  U5D1   CP13  VCCIO<12>  SKX_EXT_B_BGA1  I127
  U5D1   CU12  VCCIO<18>  SKX_EXT_B_BGA1  I127
  U5D1   CU18  VCCIO<16>  SKX_EXT_B_BGA1  I127
  U5D1   CV7  VCCIO<23>  SKX_EXT_B_BGA1  I34
  U5D1   CV21  VCCIO<17>  SKX_EXT_B_BGA1  I127
  U5D1   CY17  VCCIO<15>  SKX_EXT_B_BGA1  I127
  U5D1    D7  VCCIO<25>  SKX_EXT_B_BGA1  I34
  U5D1   DA14  VCCIO<33>  SKX_EXT_B_BGA1  I34
  U5D1   DC18  VCCIO<14>  SKX_EXT_B_BGA1  I127
  U5D1   DD7  VCCIO<39>  SKX_EXT_B_BGA1  I34
  U5D1   DE14  VCCIO<13>  SKX_EXT_B_BGA1  I127
  U5D1   DF13  VCCIO<41>  SKX_EXT_B_BGA1  I34
  U5D1   DF21  VCCIO<48>  SKX_EXT_B_BGA1  I34
  U5D1   DG8  VCCIO<54>  SKX_EXT_B_BGA1  I34
  U5D1   DH7  VCCIO<55>  SKX_EXT_B_BGA1  I34
  U5D1   DJ16  VCCIO<60>  SKX_EXT_B_BGA1  I34
  U5D1   DK21  VCCIO<8>  SKX_EXT_B_BGA1  I127
  U5D1   DM17  VCCIO<61>  SKX_EXT_B_BGA1  I34
  U5D1   DN8  VCCIO<62>  SKX_EXT_B_BGA1  I34
  U5D1   DP19  VCCIO<63>  SKX_EXT_B_BGA1  I34
  U5D1   DR2  VCCIO<65>  SKX_EXT_B_BGA1  I34
  U5D1   DR10  VCCIO<64>  SKX_EXT_B_BGA1  I34
  U5D1   DU20  VCCIO<66>  SKX_EXT_B_BGA1  I34
  U5D1   DV11  VCCIO<3>  SKX_EXT_B_BGA1  I127
  U5D1   EA12  VCCIO<67>  SKX_EXT_B_BGA1  I34
  U5D1   EB15  VCCIO<68>  SKX_EXT_B_BGA1  I34
  U5D1   EE10  VCCIO<0>  SKX_EXT_B_BGA1  I127
  U5D1   H13  VCCIO<59>  SKX_EXT_B_BGA1  I34
  U5D1    J2  VCCIO<69>  SKX_EXT_B_BGA1  I34
  U5D1   J10  VCCIO<58>  SKX_EXT_B_BGA1  I34
  U5D1   K15  VCCIO<70>  SKX_EXT_B_BGA1  I34
  U5D1   L14  VCCIO<57>  SKX_EXT_B_BGA1  I34
  U5D1   L16  VCCIO<56>  SKX_EXT_B_BGA1  I34
  U5D1    M7  VCCIO<71>  SKX_EXT_B_BGA1  I34
  U5D1    M9  VCCIO<72>  SKX_EXT_B_BGA1  I34
  U5D1   M11  VCCIO<53>  SKX_EXT_B_BGA1  I34
  U5D1   M21  VCCIO<52>  SKX_EXT_B_BGA1  I34
  U5D1   N18  VCCIO<73>  SKX_EXT_B_BGA1  I34
  U5D1    P5  VCCIO<51>  SKX_EXT_B_BGA1  I34
  U5D1    T3  VCCIO<50>  SKX_EXT_B_BGA1  I34
  U5D1   U14  VCCIO<49>  SKX_EXT_B_BGA1  I34
  U5D1    W4  VCCIO<47>  SKX_EXT_B_BGA1  I34
  U5D1    W6  VCCIO<46>  SKX_EXT_B_BGA1  I34
  U5D1   W10  VCCIO<74>  SKX_EXT_B_BGA1  I34
  U6F1     1   VCCA  PCA9617_SSOP  I15
  U7E1     1   VCCA  PCA9617_SSOP  I61
  U9F4   V19  PECIVDD  AST1250_BGA  I11

PVCCIO_CPU1     @BASEBOARD_FAB2_LIB.BASEBOARD_FAB2(SCH_1):PVCCIO_CPU1
  C3B4     1      A  CAP_A       I47
  C3D8     1      A  CAP_A       I18
  C3D9     1      A  CAP_A       I15
  C3D15    1      A  CAP_A       I174
  C3D16    1      A  CAP_A       I176
  C3D23    1      A  CAP_A       I172
  C3D24    1      A  CAP_A       I175
  C3E1     1      A  CAP_A       I108
  C4E7     1      A  CAPP        I20
  C4G22    1      A  CAP_A       I27
  C6R5     1      A  CAPP        I24
  C6R12    1      A  CAPP        I21
  C7P3     1      A  CAP         I52
  C7P12    1      A  CAP_A       I179
  C7P16    1      A  CAP_A       I206
  C7P17    1      A  CAP         I29
  C7P18    1      A  CAP         I51
  C7R1     1      A  CAP_A       I65
  C9M8     1      A  CAP_A       I10
  EU4E2    1    VOS  IR354XX_SM  I126
  J4B2    F1   IOF1  SCONN120_H61426002_SM  I46
  L4E2     2    INB  INDUCTOR    I67
  R1U35    1      A  RES         I57
  R1U41    1      A  RES         I56
  R2T73    1      A  RES         I144
  R3B2     2      B  RES         I19
  R3B4     2      B  RES         I21
  R3D15    1      A  RES         I26
  R3D16    1      A  RES         I24
  R3D17    1      A  RES         I60
  R3D20    1      A  RES         I25
  R3D22    1      A  RES         I17
  R3D23    1      A  RES         I25
  R3D24    1      A  RES         I59
  R3D25    1      A  RES         I66
  R3D26    1      A  RES         I28
  R3D32    1      A  RES         I53
  R3E1     2      B  RES         I105
  R3P41    1      A  RES          I9
  R4C10    1      A  RES         I76
  R6P33    1      A  RES         I30
  R6P35    1      A  RES         I27
  R6T1     1      A  RES         I70
  R6T2     1      A  RES         I72
  R6T6     1      A  RES         I56
  R6T7     1      A  RES         I55
  R7M2     1      A  RES         I79
  R7M7     1      A  RES         I77
  R7P5     2      B  RES         I61
  R7P21    2      B  RES         I62
  R7P22    1      A  RES         I76
  R7P28    1      A  RES         I106
  R7R1     1      A  RES         I109
  R9M6     1      A  RES         I50
  R9M7     1      A  RES          I8
  R9M18    1      A  RES          I6
  R9M19    1      A  RES          I7
  R9N1     1      A  RES          I4
  R9N2     1      A  RES          I7
  R9N14    1      A  RES         I120
  R9P1     1      A  RES          I4
  R9P2     1      A  RES         I53
  R9U3     1      A  RES          I8
  R9U4     1      A  RES         I50
  U1B2     1   VCCA  PCA9517_SM   I1
  U2D1   AA10  VCCIO<45>  SKX_EXT_B_BGA1  I33
  U2D1   AC4  VCCIO<43>  SKX_EXT_B_BGA1  I33
  U2D1   AC20  VCCIO<44>  SKX_EXT_B_BGA1  I33
  U2D1   AC36  VCCIO<97>  SKX_EXT_B_BGA1  I33
  U2D1   AD35  VCCIO<99>  SKX_EXT_B_BGA1  I33
  U2D1   AD37  VCCIO<96>  SKX_EXT_B_BGA1  I33
  U2D1   AE10  VCCIO<1>  SKX_EXT_B_BGA1  I107
  U2D1   AE34  VCCIO<100>  SKX_EXT_B_BGA1  I33
  U2D1   AE36  VCCIO<95>  SKX_EXT_B_BGA1  I33
  U2D1   AF5  VCCIO<2>  SKX_EXT_B_BGA1  I107
  U2D1   AF35  VCCIO<98>  SKX_EXT_B_BGA1  I33
  U2D1   AG34  VCCIO<101>  SKX_EXT_B_BGA1  I33
  U2D1   AH9  VCCIO<42>  SKX_EXT_B_BGA1  I33
  U2D1   AL28  VCCIO<103>  SKX_EXT_B_BGA1  I33
  U2D1   AM5  VCCIO<4>  SKX_EXT_B_BGA1  I107
  U2D1   AM29  VCCIO<102>  SKX_EXT_B_BGA1  I33
  U2D1   AN10  VCCIO<40>  SKX_EXT_B_BGA1  I33
  U2D1   AR28  VCCIO<104>  SKX_EXT_B_BGA1  I33
  U2D1   AT5  VCCIO<5>  SKX_EXT_B_BGA1  I107
  U2D1   AT7  VCCIO<6>  SKX_EXT_B_BGA1  I107
  U2D1   AT11  VCCIO<38>  SKX_EXT_B_BGA1  I33
  U2D1   AV27  VCCIO<80>  SKX_EXT_B_BGA1  I33
  U2D1   AW6  VCCIO<37>  SKX_EXT_B_BGA1  I33
  U2D1   AW26  VCCIO<79>  SKX_EXT_B_BGA1  I33
  U2D1   AY11  VCCIO<36>  SKX_EXT_B_BGA1  I33
  U2D1   AY27  VCCIO<78>  SKX_EXT_B_BGA1  I33
  U2D1   BA24  VCCIO<35>  SKX_EXT_B_BGA1  I33
  U2D1   BA26  VCCIO<77>  SKX_EXT_B_BGA1  I33
  U2D1   BB5  VCCIO<34>  SKX_EXT_B_BGA1  I33
  U2D1   BB27  VCCIO<76>  SKX_EXT_B_BGA1  I33
  U2D1   BC26  VCCIO<75>  SKX_EXT_B_BGA1  I33
  U2D1   BE24  VCCIO<7>  SKX_EXT_B_BGA1  I107
  U2D1   BF23  VCCIO<32>  SKX_EXT_B_BGA1  I33
  U2D1   BF27  VCCIO<94>  SKX_EXT_B_BGA1  I33
  U2D1   BG26  VCCIO<93>  SKX_EXT_B_BGA1  I33
  U2D1   BH25  VCCIO<92>  SKX_EXT_B_BGA1  I33
  U2D1   BH27  VCCIO<91>  SKX_EXT_B_BGA1  I33
  U2D1   BJ24  VCCIO<31>  SKX_EXT_B_BGA1  I33
  U2D1   BJ26  VCCIO<90>  SKX_EXT_B_BGA1  I33
  U2D1   BK25  VCCIO<89>  SKX_EXT_B_BGA1  I33
  U2D1   BK27  VCCIO<88>  SKX_EXT_B_BGA1  I33
  U2D1   BL26  VCCIO<87>  SKX_EXT_B_BGA1  I33
  U2D1   BM27  VCCIO<86>  SKX_EXT_B_BGA1  I33
  U2D1   BP25  VCCIO<30>  SKX_EXT_B_BGA1  I33
  U2D1   CB13  VCCIO<29>  SKX_EXT_B_BGA1  I33
  U2D1   CB17  VCCIO<28>  SKX_EXT_B_BGA1  I33
  U2D1   CC26  VCCIO<83>  SKX_EXT_B_BGA1  I33
  U2D1   CD9  VCCIO<27>  SKX_EXT_B_BGA1  I33
  U2D1   CD27  VCCIO<82>  SKX_EXT_B_BGA1  I33
  U2D1   CE18  VCCIO<26>  SKX_EXT_B_BGA1  I33
  U2D1   CF5  VCCIO<9>  SKX_EXT_B_BGA1  I107
  U2D1   CF27  VCCIO<81>  SKX_EXT_B_BGA1  I33
  U2D1   CG14  VCCIO<10>  SKX_EXT_B_BGA1  I107
  U2D1   CH9  VCCIO<24>  SKX_EXT_B_BGA1  I33
  U2D1   CH27  VCCIO<85>  SKX_EXT_B_BGA1  I33
  U2D1   CJ28  VCCIO<84>  SKX_EXT_B_BGA1  I33
  U2D1   CK5  VCCIO<22>  SKX_EXT_B_BGA1  I33
  U2D1   CL12  VCCIO<21>  SKX_EXT_B_BGA1  I33
  U2D1   CL20  VCCIO<11>  SKX_EXT_B_BGA1  I107
  U2D1   CM15  VCCIO<20>  SKX_EXT_B_BGA1  I33
  U2D1   CN6  VCCIO<19>  SKX_EXT_B_BGA1  I107
  U2D1   CP13  VCCIO<12>  SKX_EXT_B_BGA1  I107
  U2D1   CU12  VCCIO<18>  SKX_EXT_B_BGA1  I107
  U2D1   CU18  VCCIO<16>  SKX_EXT_B_BGA1  I107
  U2D1   CV7  VCCIO<23>  SKX_EXT_B_BGA1  I33
  U2D1   CV21  VCCIO<17>  SKX_EXT_B_BGA1  I107
  U2D1   CY17  VCCIO<15>  SKX_EXT_B_BGA1  I107
  U2D1    D7  VCCIO<25>  SKX_EXT_B_BGA1  I33
  U2D1   DA14  VCCIO<33>  SKX_EXT_B_BGA1  I33
  U2D1   DC18  VCCIO<14>  SKX_EXT_B_BGA1  I107
  U2D1   DD7  VCCIO<39>  SKX_EXT_B_BGA1  I33
  U2D1   DE14  VCCIO<13>  SKX_EXT_B_BGA1  I107
  U2D1   DF13  VCCIO<41>  SKX_EXT_B_BGA1  I33
  U2D1   DF21  VCCIO<48>  SKX_EXT_B_BGA1  I33
  U2D1   DG8  VCCIO<54>  SKX_EXT_B_BGA1  I33
  U2D1   DH7  VCCIO<55>  SKX_EXT_B_BGA1  I33
  U2D1   DJ16  VCCIO<60>  SKX_EXT_B_BGA1  I33
  U2D1   DK21  VCCIO<8>  SKX_EXT_B_BGA1  I107
  U2D1   DM17  VCCIO<61>  SKX_EXT_B_BGA1  I33
  U2D1   DN8  VCCIO<62>  SKX_EXT_B_BGA1  I33
  U2D1   DP19  VCCIO<63>  SKX_EXT_B_BGA1  I33
  U2D1   DR2  VCCIO<65>  SKX_EXT_B_BGA1  I33
  U2D1   DR10  VCCIO<64>  SKX_EXT_B_BGA1  I33
  U2D1   DU20  VCCIO<66>  SKX_EXT_B_BGA1  I33
  U2D1   DV11  VCCIO<3>  SKX_EXT_B_BGA1  I107
  U2D1   EA12  VCCIO<67>  SKX_EXT_B_BGA1  I33
  U2D1   EB15  VCCIO<68>  SKX_EXT_B_BGA1  I33
  U2D1   EE10  VCCIO<0>  SKX_EXT_B_BGA1  I107
  U2D1   H13  VCCIO<59>  SKX_EXT_B_BGA1  I33
  U2D1    J2  VCCIO<69>  SKX_EXT_B_BGA1  I33
  U2D1   J10  VCCIO<58>  SKX_EXT_B_BGA1  I33
  U2D1   K15  VCCIO<70>  SKX_EXT_B_BGA1  I33
  U2D1   L14  VCCIO<57>  SKX_EXT_B_BGA1  I33
  U2D1   L16  VCCIO<56>  SKX_EXT_B_BGA1  I33
  U2D1    M7  VCCIO<71>  SKX_EXT_B_BGA1  I33
  U2D1    M9  VCCIO<72>  SKX_EXT_B_BGA1  I33
  U2D1   M11  VCCIO<53>  SKX_EXT_B_BGA1  I33
  U2D1   M21  VCCIO<52>  SKX_EXT_B_BGA1  I33
  U2D1   N18  VCCIO<73>  SKX_EXT_B_BGA1  I33
  U2D1    P5  VCCIO<51>  SKX_EXT_B_BGA1  I33
  U2D1    T3  VCCIO<50>  SKX_EXT_B_BGA1  I33
  U2D1   U14  VCCIO<49>  SKX_EXT_B_BGA1  I33
  U2D1    W4  VCCIO<47>  SKX_EXT_B_BGA1  I33
  U2D1    W6  VCCIO<46>  SKX_EXT_B_BGA1  I33
  U2D1   W10  VCCIO<74>  SKX_EXT_B_BGA1  I33
  U3B1     1   VCCA  PCA9617_SSOP  I75
  U4G1     1   VCCA  PCA9617_SSOP  I63

PVCCMCP_CPU0    @BASEBOARD_FAB2_LIB.BASEBOARD_FAB2(SCH_1):PVCCMCP_CPU0
  C3R4     1      A  CAPP        I31
  C4P2     1      A  CAP         I163
  C4P3     1      A  CAP          I8
  C4P4     1      A  CAP         I14
  C4P5     1      A  CAP         I172
  C4P7     1      A  CAP          I9
  C4R1     1      A  CAPP        I29
  C5D20    1      A  CAP_A       I173
  C5D21    1      A  CAP_A       I88
  C5D22    1      A  CAP_A       I153
  C5D23    1      A  CAP_A       I98
  C5D33    1      A  CAP_A       I174
  C5D34    1      A  CAP_A       I175
  C5D35    1      A  CAP_A       I176
  C5D36    1      A  CAP_A       I151
  C5D37    1      A  CAP_A       I70
  C5D38    1      A  CAP_A       I69
  C5D48    1      A  CAP_A       I90
  C5D49    1      A  CAP_A       I152
  C5D50    1      A  CAP_A       I89
  C5D51    1      A  CAP_A       I83
  C5D52    1      A  CAP_A       I180
  C5D53    1      A  CAP_A       I179
  C5P10    1      A  CAP          I6
  C5P11    1      A  CAP          I4
  C5P12    1      A  CAP         I183
  C5P13    1      A  CAP         I186
  C5P18    1      A  CAP          I2
  C5P19    1      A  CAP         I13
  C5P20    1      A  CAP         I185
  C5P21    1      A  CAP         I184
  C5P28    1      A  CAP          I3
  C5P29    1      A  CAP         I149
  C5P30    1      A  CAP         I148
  C5P31    1      A  CAP         I162
  C6D2     1      A  CAP_A       I77
  C6D5     1      A  CAP_A       I75
  C6D8     1      A  CAP_A       I68
  J6E1    A1   IOA1  SCONN120_H61426002_SM  I55
  J6E1    A2   IOA2  SCONN120_H61426002_SM  I55
  J6E1    A3   IOA3  SCONN120_H61426002_SM  I55
  J6E1    A5   IOA5  SCONN120_H61426002_SM  I55
  J6E1    A6   IOA6  SCONN120_H61426002_SM  I55
  J6E1    A7   IOA7  SCONN120_H61426002_SM  I55
  J6E1    A8   IOA8  SCONN120_H61426002_SM  I55
  J6E1    A9   IOA9  SCONN120_H61426002_SM  I55
  J6E1   A10  IOA10  SCONN120_H61426002_SM  I55
  J6E1   A11  IOA11  SCONN120_H61426002_SM  I55
  J6E1   A12  IOA12  SCONN120_H61426002_SM  I55
  J6E1   A13  IOA13  SCONN120_H61426002_SM  I55
  J6E1   A14  IOA14  SCONN120_H61426002_SM  I55
  J6E1   A15  IOA15  SCONN120_H61426002_SM  I55
  J6E1   A16  IOA16  SCONN120_H61426002_SM  I55
  J6E1   A17  IOA17  SCONN120_H61426002_SM  I55
  J6E1   A18  IOA18  SCONN120_H61426002_SM  I55
  J6E1    B1   IOB1  SCONN120_H61426002_SM  I55
  J6E1    B2   IOB2  SCONN120_H61426002_SM  I55
  J6E1    B3   IOB3  SCONN120_H61426002_SM  I55
  J6E1    B5   IOB5  SCONN120_H61426002_SM  I55
  J6E1    B6   IOB6  SCONN120_H61426002_SM  I55
  J6E1    B7   IOB7  SCONN120_H61426002_SM  I55
  J6E1    B8   IOB8  SCONN120_H61426002_SM  I55
  J6E1    B9   IOB9  SCONN120_H61426002_SM  I55
  J6E1   B10  IOB10  SCONN120_H61426002_SM  I55
  J6E1   B11  IOB11  SCONN120_H61426002_SM  I55
  J6E1   B12  IOB12  SCONN120_H61426002_SM  I55
  J6E1   B13  IOB13  SCONN120_H61426002_SM  I55
  J6E1   B14  IOB14  SCONN120_H61426002_SM  I55
  J6E1   B15  IOB15  SCONN120_H61426002_SM  I55
  J6E1   B16  IOB16  SCONN120_H61426002_SM  I55
  J6E1   B17  IOB17  SCONN120_H61426002_SM  I55
  J6E1   B18  IOB18  SCONN120_H61426002_SM  I55
  J6E1    C1   IOC1  SCONN120_H61426002_SM  I55
  J6E1    C2   IOC2  SCONN120_H61426002_SM  I55
  J6E1    C3   IOC3  SCONN120_H61426002_SM  I55
  J6E1    C4   IOC4  SCONN120_H61426002_SM  I55
  J6E1    C5   IOC5  SCONN120_H61426002_SM  I55
  J6E1    C6   IOC6  SCONN120_H61426002_SM  I55
  J6E1    C7   IOC7  SCONN120_H61426002_SM  I55
  J6E1    C8   IOC8  SCONN120_H61426002_SM  I55
  J6E1    C9   IOC9  SCONN120_H61426002_SM  I55
  J6E1   C10  IOC10  SCONN120_H61426002_SM  I55
  J6E1   C11  IOC11  SCONN120_H61426002_SM  I55
  J6E1   C12  IOC12  SCONN120_H61426002_SM  I55
  J6E1   C13  IOC13  SCONN120_H61426002_SM  I55
  J6E1   C14  IOC14  SCONN120_H61426002_SM  I55
  J6E1   C15  IOC15  SCONN120_H61426002_SM  I55
  J6E1   C16  IOC16  SCONN120_H61426002_SM  I55
  J6E1   C17  IOC17  SCONN120_H61426002_SM  I55
  J6E1   C18  IOC18  SCONN120_H61426002_SM  I55
  U5D1   AM21  RSVD<209>  SKX_EXT_B_BGA1  I204
  U5D1   AM25  RSVD<207>  SKX_EXT_B_BGA1  I204
  U5D1   AN18  RSVD<203>  SKX_EXT_B_BGA1  I204
  U5D1   AN22  RSVD<202>  SKX_EXT_B_BGA1  I204
  U5D1   AN24  RSVD<201>  SKX_EXT_B_BGA1  I204
  U5D1   AN26  RSVD<200>  SKX_EXT_B_BGA1  I204
  U5D1   AP23  RSVD<197>  SKX_EXT_B_BGA1  I204
  U5D1   AP25  RSVD<196>  SKX_EXT_B_BGA1  I204
  U5D1   AR20  RSVD<193>  SKX_EXT_B_BGA1  I61
  U5D1   AR22  RSVD<192>  SKX_EXT_B_BGA1  I61
  U5D1   AR26  RSVD<191>  SKX_EXT_B_BGA1  I61
  U5D1   AT23  RSVD<188>  SKX_EXT_B_BGA1  I61
  U5D1   AT25  RSVD<187>  SKX_EXT_B_BGA1  I61
  U5D1   BD13  CD_VCC_CORE<12>  SKX_EXT_B_BGA1  I34
  U5D1   BE12  CD_VCC_CORE<11>  SKX_EXT_B_BGA1  I34
  U5D1   BE14  CD_VCC_CORE<10>  SKX_EXT_B_BGA1  I34
  U5D1   BF11  CD_VCC_CORE<9>  SKX_EXT_B_BGA1  I34
  U5D1   BF13  CD_VCC_CORE<8>  SKX_EXT_B_BGA1  I34
  U5D1   BG12  CD_VCC_CORE<7>  SKX_EXT_B_BGA1  I34
  U5D1   BG14  CD_VCC_CORE<6>  SKX_EXT_B_BGA1  I34
  U5D1   BH13  CD_VCC_CORE<5>  SKX_EXT_B_BGA1  I34
  U5D1   BH19  RSVD<143>  SKX_EXT_B_BGA1  I15
  U5D1   BJ12  CD_VCC_CORE<4>  SKX_EXT_B_BGA1  I34
  U5D1   BJ14  CD_VCC_CORE<3>  SKX_EXT_B_BGA1  I34
  U5D1   BJ16  RSVD<142>  SKX_EXT_B_BGA1  I15
  U5D1   BJ18  RSVD<141>  SKX_EXT_B_BGA1  I15
  U5D1   BJ20  RSVD<140>  SKX_EXT_B_BGA1  I15
  U5D1   BK13  CD_VCC_CORE<2>  SKX_EXT_B_BGA1  I34
  U5D1   BK15  CD_VCC_CORE<1>  SKX_EXT_B_BGA1  I34
  U5D1   BK17  RSVD<139>  SKX_EXT_B_BGA1  I15
  U5D1   BL14  CD_VCC_CORE<0>  SKX_EXT_B_BGA1  I34
  U5D1   BL18  RSVD<138>  SKX_EXT_B_BGA1  I15
  U5D1   BL20  RSVD<137>  SKX_EXT_B_BGA1  I15
  U5D1   BM17  RSVD<136>  SKX_EXT_B_BGA1  I15
  U5D1   BM19  RSVD<135>  SKX_EXT_B_BGA1  I15
  U5D1   BN18  RSVD<134>  SKX_EXT_B_BGA1  I15
  U5D1   BP17  RSVD<133>  SKX_EXT_B_BGA1  I15
  U5D1   BP21  RSVD<132>  SKX_EXT_B_BGA1  I15
  U5D1   BR22  RSVD<131>  SKX_EXT_B_BGA1  I15
  U5D1   BR24  RSVD<130>  SKX_EXT_B_BGA1  I15
  U5D1   BU18  RSVD<129>  SKX_EXT_B_BGA1  I15
  U5D1   BU20  RSVD<128>  SKX_EXT_B_BGA1  I15
  U5D1   BU22  RSVD<127>  SKX_EXT_B_BGA1  I15
  U5D1   BV19  RSVD<126>  SKX_EXT_B_BGA1  I15
  U5D1   BV21  RSVD<125>  SKX_EXT_B_BGA1  I15
  U5D1   BW20  RSVD<122>  SKX_EXT_B_BGA1  I15
  U5D1   BY19  RSVD<120>  SKX_EXT_B_BGA1  I15
  U5D1   CA22  RSVD<118>  SKX_EXT_B_BGA1  I15
  U5D1   CB19  RSVD<116>  SKX_EXT_B_BGA1  I15
  U5D1   CB21  RSVD<115>  SKX_EXT_B_BGA1  I15
  U5D1   CC20  RSVD<112>  SKX_EXT_B_BGA1  I15
  U5D1   CD19  RSVD<110>  SKX_EXT_B_BGA1  I15
  U5D1   CD21  RSVD<109>  SKX_EXT_B_BGA1  I15
  U5D1   CE22  RSVD<107>  SKX_EXT_B_BGA1  I15
  U5D1   CF19  RSVD<104>  SKX_EXT_B_BGA1  I15
  U5D1   CF21  RSVD<103>  SKX_EXT_B_BGA1  I15
  U5D1   CF23  RSVD<102>  SKX_EXT_B_BGA1  I15
  U5D1   CG20  RSVD<98>  SKX_EXT_B_BGA1  I15
  U5D1   CG26  RSVD<96>  SKX_EXT_B_BGA1  I15
  U5D1   CH21  RSVD<93>  SKX_EXT_B_BGA1  I15
  U5D1   CH23  RSVD<92>  SKX_EXT_B_BGA1  I15
  U5D1   CJ20  RSVD<89>  SKX_EXT_B_BGA1  I16
  U5D1   CJ22  RSVD<88>  SKX_EXT_B_BGA1  I16
  U5D1   CJ24  RSVD<87>  SKX_EXT_B_BGA1  I16
  U5D1   CJ26  RSVD<86>  SKX_EXT_B_BGA1  I16
  U5D1   CK23  RSVD<84>  SKX_EXT_B_BGA1  I16
  U5D1   CK25  RSVD<83>  SKX_EXT_B_BGA1  I16
  U5D1   CL24  RSVD<81>  SKX_EXT_B_BGA1  I16
  U5D1   CL26  RSVD<80>  SKX_EXT_B_BGA1  I127
  U5D1   CM23  RSVD<79>  SKX_EXT_B_BGA1  I127
  U5D1   CM25  RSVD<78>  SKX_EXT_B_BGA1  I127
  U5D1   CN24  RSVD<76>  SKX_EXT_B_BGA1  I127
  U5D1   CP23  RSVD<74>  SKX_EXT_B_BGA1  I127
  U5D1   CT23  RSVD<71>  SKX_EXT_B_BGA1  I127
  U5D1   CU24  RSVD<68>  SKX_EXT_B_BGA1  I127
  U5D1   CV23  RSVD<65>  SKX_EXT_B_BGA1  I127
  U5D1   CW24  RSVD<62>  SKX_EXT_B_BGA1  I127
  U5D1   CY25  RSVD<58>  SKX_EXT_B_BGA1  I127
  U5D1   DA24  RSVD<52>  SKX_EXT_B_BGA1  I127

PVCCMCP_CPU1    @BASEBOARD_FAB2_LIB.BASEBOARD_FAB2(SCH_1):PVCCMCP_CPU1
  C2D18    1      A  CAP_A       I197
  C2D28    1      A  CAP_A       I198
  C2D29    1      A  CAP_A       I199
  C2D39    1      A  CAP_A       I165
  C2D40    1      A  CAP_A       I10
  C3D4     1      A  CAP_A        I5
  C3D5     1      A  CAP_A        I3
  C3D6     1      A  CAP_A       I170
  C3D7     1      A  CAP_A       I164
  C3D10    1      A  CAP_A       I196
  C3D11    1      A  CAP_A        I7
  C3D12    1      A  CAP_A        I4
  C3D13    1      A  CAP_A        I8
  C3D14    1      A  CAP_A       I171
  C3D17    1      A  CAP_A       I166
  C3D18    1      A  CAP_A       I169
  C3D19    1      A  CAP_A       I208
  C3D20    1      A  CAP_A       I207
  C3D21    1      A  CAP_A        I1
  C4E24    1      A  CAPP        I61
  C6R16    1      A  CAPP        I62
  C7P4     1      A  CAP         I195
  C7P5     1      A  CAP         I182
  C7P6     1      A  CAP         I23
  C7P7     1      A  CAP         I27
  C7P8     1      A  CAP         I184
  C7P9     1      A  CAP         I181
  C7P10    1      A  CAP         I26
  C7P11    1      A  CAP         I183
  C7P13    1      A  CAP         I25
  C7P14    1      A  CAP         I49
  C7P15    1      A  CAP         I45
  C8P8     1      A  CAP         I213
  C8P9     1      A  CAP         I214
  C8P14    1      A  CAP         I211
  C8P15    1      A  CAP         I212
  C8P22    1      A  CAP         I28
  C8P23    1      A  CAP         I48
  J4E1    A1   IOA1  SCONN120_H61426002_SM  I45
  J4E1    A2   IOA2  SCONN120_H61426002_SM  I45
  J4E1    A3   IOA3  SCONN120_H61426002_SM  I45
  J4E1    A5   IOA5  SCONN120_H61426002_SM  I45
  J4E1    A6   IOA6  SCONN120_H61426002_SM  I45
  J4E1    A7   IOA7  SCONN120_H61426002_SM  I45
  J4E1    A8   IOA8  SCONN120_H61426002_SM  I45
  J4E1    A9   IOA9  SCONN120_H61426002_SM  I45
  J4E1   A10  IOA10  SCONN120_H61426002_SM  I45
  J4E1   A11  IOA11  SCONN120_H61426002_SM  I45
  J4E1   A12  IOA12  SCONN120_H61426002_SM  I45
  J4E1   A13  IOA13  SCONN120_H61426002_SM  I45
  J4E1   A14  IOA14  SCONN120_H61426002_SM  I45
  J4E1   A15  IOA15  SCONN120_H61426002_SM  I45
  J4E1   A16  IOA16  SCONN120_H61426002_SM  I45
  J4E1   A17  IOA17  SCONN120_H61426002_SM  I45
  J4E1   A18  IOA18  SCONN120_H61426002_SM  I45
  J4E1    B1   IOB1  SCONN120_H61426002_SM  I45
  J4E1    B2   IOB2  SCONN120_H61426002_SM  I45
  J4E1    B3   IOB3  SCONN120_H61426002_SM  I45
  J4E1    B5   IOB5  SCONN120_H61426002_SM  I45
  J4E1    B6   IOB6  SCONN120_H61426002_SM  I45
  J4E1    B7   IOB7  SCONN120_H61426002_SM  I45
  J4E1    B8   IOB8  SCONN120_H61426002_SM  I45
  J4E1    B9   IOB9  SCONN120_H61426002_SM  I45
  J4E1   B10  IOB10  SCONN120_H61426002_SM  I45
  J4E1   B11  IOB11  SCONN120_H61426002_SM  I45
  J4E1   B12  IOB12  SCONN120_H61426002_SM  I45
  J4E1   B13  IOB13  SCONN120_H61426002_SM  I45
  J4E1   B14  IOB14  SCONN120_H61426002_SM  I45
  J4E1   B15  IOB15  SCONN120_H61426002_SM  I45
  J4E1   B16  IOB16  SCONN120_H61426002_SM  I45
  J4E1   B17  IOB17  SCONN120_H61426002_SM  I45
  J4E1   B18  IOB18  SCONN120_H61426002_SM  I45
  J4E1    C1   IOC1  SCONN120_H61426002_SM  I45
  J4E1    C2   IOC2  SCONN120_H61426002_SM  I45
  J4E1    C3   IOC3  SCONN120_H61426002_SM  I45
  J4E1    C4   IOC4  SCONN120_H61426002_SM  I45
  J4E1    C5   IOC5  SCONN120_H61426002_SM  I45
  J4E1    C6   IOC6  SCONN120_H61426002_SM  I45
  J4E1    C7   IOC7  SCONN120_H61426002_SM  I45
  J4E1    C8   IOC8  SCONN120_H61426002_SM  I45
  J4E1    C9   IOC9  SCONN120_H61426002_SM  I45
  J4E1   C10  IOC10  SCONN120_H61426002_SM  I45
  J4E1   C11  IOC11  SCONN120_H61426002_SM  I45
  J4E1   C12  IOC12  SCONN120_H61426002_SM  I45
  J4E1   C13  IOC13  SCONN120_H61426002_SM  I45
  J4E1   C14  IOC14  SCONN120_H61426002_SM  I45
  J4E1   C15  IOC15  SCONN120_H61426002_SM  I45
  J4E1   C16  IOC16  SCONN120_H61426002_SM  I45
  J4E1   C17  IOC17  SCONN120_H61426002_SM  I45
  J4E1   C18  IOC18  SCONN120_H61426002_SM  I45
  U2D1   AM21  RSVD<209>  SKX_EXT_B_BGA1  I169
  U2D1   AM25  RSVD<207>  SKX_EXT_B_BGA1  I169
  U2D1   AN18  RSVD<203>  SKX_EXT_B_BGA1  I169
  U2D1   AN22  RSVD<202>  SKX_EXT_B_BGA1  I169
  U2D1   AN24  RSVD<201>  SKX_EXT_B_BGA1  I169
  U2D1   AN26  RSVD<200>  SKX_EXT_B_BGA1  I169
  U2D1   AP23  RSVD<197>  SKX_EXT_B_BGA1  I169
  U2D1   AP25  RSVD<196>  SKX_EXT_B_BGA1  I169
  U2D1   AR20  RSVD<193>  SKX_EXT_B_BGA1  I23
  U2D1   AR22  RSVD<192>  SKX_EXT_B_BGA1  I23
  U2D1   AR26  RSVD<191>  SKX_EXT_B_BGA1  I23
  U2D1   AT23  RSVD<188>  SKX_EXT_B_BGA1  I23
  U2D1   AT25  RSVD<187>  SKX_EXT_B_BGA1  I23
  U2D1   BD13  CD_VCC_CORE<12>  SKX_EXT_B_BGA1  I33
  U2D1   BE12  CD_VCC_CORE<11>  SKX_EXT_B_BGA1  I33
  U2D1   BE14  CD_VCC_CORE<10>  SKX_EXT_B_BGA1  I33
  U2D1   BF11  CD_VCC_CORE<9>  SKX_EXT_B_BGA1  I33
  U2D1   BF13  CD_VCC_CORE<8>  SKX_EXT_B_BGA1  I33
  U2D1   BG12  CD_VCC_CORE<7>  SKX_EXT_B_BGA1  I33
  U2D1   BG14  CD_VCC_CORE<6>  SKX_EXT_B_BGA1  I33
  U2D1   BH13  CD_VCC_CORE<5>  SKX_EXT_B_BGA1  I33
  U2D1   BH19  RSVD<143>  SKX_EXT_B_BGA1   I9
  U2D1   BJ12  CD_VCC_CORE<4>  SKX_EXT_B_BGA1  I33
  U2D1   BJ14  CD_VCC_CORE<3>  SKX_EXT_B_BGA1  I33
  U2D1   BJ16  RSVD<142>  SKX_EXT_B_BGA1   I9
  U2D1   BJ18  RSVD<141>  SKX_EXT_B_BGA1   I9
  U2D1   BJ20  RSVD<140>  SKX_EXT_B_BGA1   I9
  U2D1   BK13  CD_VCC_CORE<2>  SKX_EXT_B_BGA1  I33
  U2D1   BK15  CD_VCC_CORE<1>  SKX_EXT_B_BGA1  I33
  U2D1   BK17  RSVD<139>  SKX_EXT_B_BGA1   I9
  U2D1   BL14  CD_VCC_CORE<0>  SKX_EXT_B_BGA1  I33
  U2D1   BL18  RSVD<138>  SKX_EXT_B_BGA1   I9
  U2D1   BL20  RSVD<137>  SKX_EXT_B_BGA1   I9
  U2D1   BM17  RSVD<136>  SKX_EXT_B_BGA1   I9
  U2D1   BM19  RSVD<135>  SKX_EXT_B_BGA1   I9
  U2D1   BN18  RSVD<134>  SKX_EXT_B_BGA1   I9
  U2D1   BP17  RSVD<133>  SKX_EXT_B_BGA1   I9
  U2D1   BP21  RSVD<132>  SKX_EXT_B_BGA1   I9
  U2D1   BR22  RSVD<131>  SKX_EXT_B_BGA1   I9
  U2D1   BR24  RSVD<130>  SKX_EXT_B_BGA1   I9
  U2D1   BU18  RSVD<129>  SKX_EXT_B_BGA1   I9
  U2D1   BU20  RSVD<128>  SKX_EXT_B_BGA1   I9
  U2D1   BU22  RSVD<127>  SKX_EXT_B_BGA1   I9
  U2D1   BV19  RSVD<126>  SKX_EXT_B_BGA1   I9
  U2D1   BV21  RSVD<125>  SKX_EXT_B_BGA1   I9
  U2D1   BW20  RSVD<122>  SKX_EXT_B_BGA1   I9
  U2D1   BY19  RSVD<120>  SKX_EXT_B_BGA1   I9
  U2D1   CA22  RSVD<118>  SKX_EXT_B_BGA1   I9
  U2D1   CB19  RSVD<116>  SKX_EXT_B_BGA1   I9
  U2D1   CB21  RSVD<115>  SKX_EXT_B_BGA1   I9
  U2D1   CC20  RSVD<112>  SKX_EXT_B_BGA1   I9
  U2D1   CD19  RSVD<110>  SKX_EXT_B_BGA1   I9
  U2D1   CD21  RSVD<109>  SKX_EXT_B_BGA1   I9
  U2D1   CE22  RSVD<107>  SKX_EXT_B_BGA1   I9
  U2D1   CF19  RSVD<104>  SKX_EXT_B_BGA1   I9
  U2D1   CF21  RSVD<103>  SKX_EXT_B_BGA1   I9
  U2D1   CF23  RSVD<102>  SKX_EXT_B_BGA1   I9
  U2D1   CG20  RSVD<98>  SKX_EXT_B_BGA1   I9
  U2D1   CG26  RSVD<96>  SKX_EXT_B_BGA1   I9
  U2D1   CH21  RSVD<93>  SKX_EXT_B_BGA1   I9
  U2D1   CH23  RSVD<92>  SKX_EXT_B_BGA1   I9
  U2D1   CJ20  RSVD<89>  SKX_EXT_B_BGA1  I10
  U2D1   CJ22  RSVD<88>  SKX_EXT_B_BGA1  I10
  U2D1   CJ24  RSVD<87>  SKX_EXT_B_BGA1  I10
  U2D1   CJ26  RSVD<86>  SKX_EXT_B_BGA1  I10
  U2D1   CK23  RSVD<84>  SKX_EXT_B_BGA1  I10
  U2D1   CK25  RSVD<83>  SKX_EXT_B_BGA1  I10
  U2D1   CL24  RSVD<81>  SKX_EXT_B_BGA1  I10
  U2D1   CL26  RSVD<80>  SKX_EXT_B_BGA1  I107
  U2D1   CM23  RSVD<79>  SKX_EXT_B_BGA1  I107
  U2D1   CM25  RSVD<78>  SKX_EXT_B_BGA1  I107
  U2D1   CN24  RSVD<76>  SKX_EXT_B_BGA1  I107
  U2D1   CP23  RSVD<74>  SKX_EXT_B_BGA1  I107
  U2D1   CT23  RSVD<71>  SKX_EXT_B_BGA1  I107
  U2D1   CU24  RSVD<68>  SKX_EXT_B_BGA1  I107
  U2D1   CV23  RSVD<65>  SKX_EXT_B_BGA1  I107
  U2D1   CW24  RSVD<62>  SKX_EXT_B_BGA1  I107
  U2D1   CY25  RSVD<58>  SKX_EXT_B_BGA1  I107
  U2D1   DA24  RSVD<52>  SKX_EXT_B_BGA1  I107

PVDDQ_ABC       @BASEBOARD_FAB2_LIB.BASEBOARD_FAB2(SCH_1):PVDDQ_ABC
  C3U1     1      A  CAPP        I76
  C3U5     1      A  CAPP        I77
  C3U8     1      A  CAPP        I78
  C4T4     1      A  CAP         I91
  C5D54    1      A  CAP         I190
  C5D55    1      A  CAP         I189
  C5D56    1      A  CAP         I188
  C5D57    1      A  CAP         I186
  C5F1     1      A  CAP_A       I206
  C5F2     1      A  CAP_A       I205
  C5G1     1      A  CAP_A       I231
  C5G2     1      A  CAP_A       I245
  C5G3     1      A  CAP_A       I217
  C5G4     1      A  CAP_A       I241
  C5G5     1      A  CAP_A       I235
  C5G6     1      A  CAP_A       I237
  C5G7     1      A  CAP_A       I234
  C5G8     1      A  CAP_A       I230
  C5G9     1      A  CAP         I92
  C5G10    1      A  CAP_A       I207
  C5G11    1      A  CAP_A       I250
  C5G12    1      A  CAP_A       I246
  C5G13    1      A  CAP_A       I240
  C5G14    1      A  CAP_A       I223
  C5G15    1      A  CAP_A       I220
  C5G16    1      A  CAP_A       I221
  C5G17    1      A  CAP_A       I226
  C5G18    1      A  CAP_A       I227
  C5G19    1      A  CAP_A       I213
  C5G20    1      A  CAP         I110
  C5G21    1      A  CAP         I11
  C5G22    1      A  CAP         I15
  C5G41    1      A  CAP_A       I53
  C5G42    1      A  CAP_A       I54
  C5G43    1      A  CAP_A       I56
  C5G44    1      A  CAP_A       I55
  C5G45    1      A  CAP_A       I60
  C5G46    1      A  CAP_A       I59
  C5G47    1      A  CAP_A       I58
  C5G48    1      A  CAP_A       I57
  C5G49    1      A  CAP_A       I61
  C5G50    1      A  CAP_A       I70
  C5G51    1      A  CAP_A       I69
  C5G52    1      A  CAP_A       I68
  C5G53    1      A  CAP_A       I67
  C5G54    1      A  CAP_A       I62
  C5G55    1      A  CAP_A       I66
  C5G56    1      A  CAP_A       I65
  C5G57    1      A  CAP_A       I64
  C5G58    1      A  CAP_A       I63
  C5P38    1      A  CAP         I193
  C5P39    1      A  CAP         I184
  C5T1     1      A  CAP_A       I212
  C5T2     1      A  CAP_A       I208
  C5T4     1      A  CAP_A       I211
  C5T5     1      A  CAP_A       I216
  C5T6     1      A  CAP_A       I218
  C5T7     1      A  CAP_A       I219
  C5T8     1      A  CAP_A       I222
  C5T9     1      A  CAP_A       I224
  C5T10    1      A  CAP_A       I225
  C5T11    1      A  CAP_A       I228
  C5T12    1      A  CAP_A       I229
  C5T13    1      A  CAP_A       I210
  C5U1     1      A  CAP         I88
  C5U2     1      A  CAP_A       I247
  C5U3     1      A  CAP_A       I244
  C5U4     1      A  CAP_A       I243
  C5U5     1      A  CAP_A       I239
  C5U6     1      A  CAP_A       I238
  C5U7     1      A  CAP_A       I236
  C5U8     1      A  CAP_A       I233
  C5U9     1      A  CAP_A       I232
  C5U10    1      A  CAP         I83
  C5U11    1      A  CAP_A       I209
  C5U13    1      A  CAP         I82
  C5U14    1      A  CAP         I89
  C5U15    1      A  CAP         I90
  C6G3     1      A  CAP          I6
  C6U15    1      A  CAP         I26
  C6U16    1      A  CAP         I22
  C7G27    1      A  CAP         I68
  C7G28    1      A  CAPP        I75
  EU4G3   10    VIN  MIC5166_DFN   I1
  EU7G2    1    VOS  IR354XX_SM  I102
  EU7G3    1    VOS  IR354XX_SM  I103
  J4G1    59  VDD<25>  SCONN288_H44441004_PIP  I260
  J4G1    61  VDD<24>  SCONN288_H44441004_PIP  I260
  J4G1    64  VDD<23>  SCONN288_H44441004_PIP  I260
  J4G1    67  VDD<22>  SCONN288_H44441004_PIP  I260
  J4G1    70  VDD<21>  SCONN288_H44441004_PIP  I260
  J4G1    73  VDD<20>  SCONN288_H44441004_PIP  I260
  J4G1    76  VDD<19>  SCONN288_H44441004_PIP  I260
  J4G1    80  VDD<18>  SCONN288_H44441004_PIP  I260
  J4G1    83  VDD<17>  SCONN288_H44441004_PIP  I260
  J4G1    85  VDD<16>  SCONN288_H44441004_PIP  I260
  J4G1    88  VDD<15>  SCONN288_H44441004_PIP  I260
  J4G1    90  VDD<14>  SCONN288_H44441004_PIP  I260
  J4G1    92  VDD<13>  SCONN288_H44441004_PIP  I260
  J4G1   204  VDD<12>  SCONN288_H44441004_PIP  I260
  J4G1   206  VDD<11>  SCONN288_H44441004_PIP  I260
  J4G1   209  VDD<10>  SCONN288_H44441004_PIP  I260
  J4G1   212  VDD<9>  SCONN288_H44441004_PIP  I260
  J4G1   215  VDD<8>  SCONN288_H44441004_PIP  I260
  J4G1   217  VDD<7>  SCONN288_H44441004_PIP  I260
  J4G1   220  VDD<6>  SCONN288_H44441004_PIP  I260
  J4G1   223  VDD<5>  SCONN288_H44441004_PIP  I260
  J4G1   226  VDD<4>  SCONN288_H44441004_PIP  I260
  J4G1   229  VDD<3>  SCONN288_H44441004_PIP  I260
  J4G1   231  VDD<2>  SCONN288_H44441004_PIP  I260
  J4G1   233  VDD<1>  SCONN288_H44441004_PIP  I260
  J4G1   236  VDD<0>  SCONN288_H44441004_PIP  I260
  J4G2    59  VDD<25>  SCONN288_H44441004_PIP  I169
  J4G2    61  VDD<24>  SCONN288_H44441004_PIP  I169
  J4G2    64  VDD<23>  SCONN288_H44441004_PIP  I169
  J4G2    67  VDD<22>  SCONN288_H44441004_PIP  I169
  J4G2    70  VDD<21>  SCONN288_H44441004_PIP  I169
  J4G2    73  VDD<20>  SCONN288_H44441004_PIP  I169
  J4G2    76  VDD<19>  SCONN288_H44441004_PIP  I169
  J4G2    80  VDD<18>  SCONN288_H44441004_PIP  I169
  J4G2    83  VDD<17>  SCONN288_H44441004_PIP  I169
  J4G2    85  VDD<16>  SCONN288_H44441004_PIP  I169
  J4G2    88  VDD<15>  SCONN288_H44441004_PIP  I169
  J4G2    90  VDD<14>  SCONN288_H44441004_PIP  I169
  J4G2    92  VDD<13>  SCONN288_H44441004_PIP  I169
  J4G2   204  VDD<12>  SCONN288_H44441004_PIP  I169
  J4G2   206  VDD<11>  SCONN288_H44441004_PIP  I169
  J4G2   209  VDD<10>  SCONN288_H44441004_PIP  I169
  J4G2   212  VDD<9>  SCONN288_H44441004_PIP  I169
  J4G2   215  VDD<8>  SCONN288_H44441004_PIP  I169
  J4G2   217  VDD<7>  SCONN288_H44441004_PIP  I169
  J4G2   220  VDD<6>  SCONN288_H44441004_PIP  I169
  J4G2   223  VDD<5>  SCONN288_H44441004_PIP  I169
  J4G2   226  VDD<4>  SCONN288_H44441004_PIP  I169
  J4G2   229  VDD<3>  SCONN288_H44441004_PIP  I169
  J4G2   231  VDD<2>  SCONN288_H44441004_PIP  I169
  J4G2   233  VDD<1>  SCONN288_H44441004_PIP  I169
  J4G2   236  VDD<0>  SCONN288_H44441004_PIP  I169
  J4G3    59  VDD<25>  SCONN288_H44441004_PIP  I179
  J4G3    61  VDD<24>  SCONN288_H44441004_PIP  I179
  J4G3    64  VDD<23>  SCONN288_H44441004_PIP  I179
  J4G3    67  VDD<22>  SCONN288_H44441004_PIP  I179
  J4G3    70  VDD<21>  SCONN288_H44441004_PIP  I179
  J4G3    73  VDD<20>  SCONN288_H44441004_PIP  I179
  J4G3    76  VDD<19>  SCONN288_H44441004_PIP  I179
  J4G3    80  VDD<18>  SCONN288_H44441004_PIP  I179
  J4G3    83  VDD<17>  SCONN288_H44441004_PIP  I179
  J4G3    85  VDD<16>  SCONN288_H44441004_PIP  I179
  J4G3    88  VDD<15>  SCONN288_H44441004_PIP  I179
  J4G3    90  VDD<14>  SCONN288_H44441004_PIP  I179
  J4G3    92  VDD<13>  SCONN288_H44441004_PIP  I179
  J4G3   204  VDD<12>  SCONN288_H44441004_PIP  I179
  J4G3   206  VDD<11>  SCONN288_H44441004_PIP  I179
  J4G3   209  VDD<10>  SCONN288_H44441004_PIP  I179
  J4G3   212  VDD<9>  SCONN288_H44441004_PIP  I179
  J4G3   215  VDD<8>  SCONN288_H44441004_PIP  I179
  J4G3   217  VDD<7>  SCONN288_H44441004_PIP  I179
  J4G3   220  VDD<6>  SCONN288_H44441004_PIP  I179
  J4G3   223  VDD<5>  SCONN288_H44441004_PIP  I179
  J4G3   226  VDD<4>  SCONN288_H44441004_PIP  I179
  J4G3   229  VDD<3>  SCONN288_H44441004_PIP  I179
  J4G3   231  VDD<2>  SCONN288_H44441004_PIP  I179
  J4G3   233  VDD<1>  SCONN288_H44441004_PIP  I179
  J4G3   236  VDD<0>  SCONN288_H44441004_PIP  I179
  J6T1    59  VDD<25>  SCONN288_H44441003_PIP  I75
  J6T1    61  VDD<24>  SCONN288_H44441003_PIP  I75
  J6T1    64  VDD<23>  SCONN288_H44441003_PIP  I75
  J6T1    67  VDD<22>  SCONN288_H44441003_PIP  I75
  J6T1    70  VDD<21>  SCONN288_H44441003_PIP  I75
  J6T1    73  VDD<20>  SCONN288_H44441003_PIP  I75
  J6T1    76  VDD<19>  SCONN288_H44441003_PIP  I75
  J6T1    80  VDD<18>  SCONN288_H44441003_PIP  I75
  J6T1    83  VDD<17>  SCONN288_H44441003_PIP  I75
  J6T1    85  VDD<16>  SCONN288_H44441003_PIP  I75
  J6T1    88  VDD<15>  SCONN288_H44441003_PIP  I75
  J6T1    90  VDD<14>  SCONN288_H44441003_PIP  I75
  J6T1    92  VDD<13>  SCONN288_H44441003_PIP  I75
  J6T1   204  VDD<12>  SCONN288_H44441003_PIP  I75
  J6T1   206  VDD<11>  SCONN288_H44441003_PIP  I75
  J6T1   209  VDD<10>  SCONN288_H44441003_PIP  I75
  J6T1   212  VDD<9>  SCONN288_H44441003_PIP  I75
  J6T1   215  VDD<8>  SCONN288_H44441003_PIP  I75
  J6T1   217  VDD<7>  SCONN288_H44441003_PIP  I75
  J6T1   220  VDD<6>  SCONN288_H44441003_PIP  I75
  J6T1   223  VDD<5>  SCONN288_H44441003_PIP  I75
  J6T1   226  VDD<4>  SCONN288_H44441003_PIP  I75
  J6T1   229  VDD<3>  SCONN288_H44441003_PIP  I75
  J6T1   231  VDD<2>  SCONN288_H44441003_PIP  I75
  J6T1   233  VDD<1>  SCONN288_H44441003_PIP  I75
  J6T1   236  VDD<0>  SCONN288_H44441003_PIP  I75
  J6U1    59  VDD<25>  SCONN288_H44441003_PIP  I67
  J6U1    61  VDD<24>  SCONN288_H44441003_PIP  I67
  J6U1    64  VDD<23>  SCONN288_H44441003_PIP  I67
  J6U1    67  VDD<22>  SCONN288_H44441003_PIP  I67
  J6U1    70  VDD<21>  SCONN288_H44441003_PIP  I67
  J6U1    73  VDD<20>  SCONN288_H44441003_PIP  I67
  J6U1    76  VDD<19>  SCONN288_H44441003_PIP  I67
  J6U1    80  VDD<18>  SCONN288_H44441003_PIP  I67
  J6U1    83  VDD<17>  SCONN288_H44441003_PIP  I67
  J6U1    85  VDD<16>  SCONN288_H44441003_PIP  I67
  J6U1    88  VDD<15>  SCONN288_H44441003_PIP  I67
  J6U1    90  VDD<14>  SCONN288_H44441003_PIP  I67
  J6U1    92  VDD<13>  SCONN288_H44441003_PIP  I67
  J6U1   204  VDD<12>  SCONN288_H44441003_PIP  I67
  J6U1   206  VDD<11>  SCONN288_H44441003_PIP  I67
  J6U1   209  VDD<10>  SCONN288_H44441003_PIP  I67
  J6U1   212  VDD<9>  SCONN288_H44441003_PIP  I67
  J6U1   215  VDD<8>  SCONN288_H44441003_PIP  I67
  J6U1   217  VDD<7>  SCONN288_H44441003_PIP  I67
  J6U1   220  VDD<6>  SCONN288_H44441003_PIP  I67
  J6U1   223  VDD<5>  SCONN288_H44441003_PIP  I67
  J6U1   226  VDD<4>  SCONN288_H44441003_PIP  I67
  J6U1   229  VDD<3>  SCONN288_H44441003_PIP  I67
  J6U1   231  VDD<2>  SCONN288_H44441003_PIP  I67
  J6U1   233  VDD<1>  SCONN288_H44441003_PIP  I67
  J6U1   236  VDD<0>  SCONN288_H44441003_PIP  I67
  J6U2    59  VDD<25>  SCONN288_H44441003_PIP  I171
  J6U2    61  VDD<24>  SCONN288_H44441003_PIP  I171
  J6U2    64  VDD<23>  SCONN288_H44441003_PIP  I171
  J6U2    67  VDD<22>  SCONN288_H44441003_PIP  I171
  J6U2    70  VDD<21>  SCONN288_H44441003_PIP  I171
  J6U2    73  VDD<20>  SCONN288_H44441003_PIP  I171
  J6U2    76  VDD<19>  SCONN288_H44441003_PIP  I171
  J6U2    80  VDD<18>  SCONN288_H44441003_PIP  I171
  J6U2    83  VDD<17>  SCONN288_H44441003_PIP  I171
  J6U2    85  VDD<16>  SCONN288_H44441003_PIP  I171
  J6U2    88  VDD<15>  SCONN288_H44441003_PIP  I171
  J6U2    90  VDD<14>  SCONN288_H44441003_PIP  I171
  J6U2    92  VDD<13>  SCONN288_H44441003_PIP  I171
  J6U2   204  VDD<12>  SCONN288_H44441003_PIP  I171
  J6U2   206  VDD<11>  SCONN288_H44441003_PIP  I171
  J6U2   209  VDD<10>  SCONN288_H44441003_PIP  I171
  J6U2   212  VDD<9>  SCONN288_H44441003_PIP  I171
  J6U2   215  VDD<8>  SCONN288_H44441003_PIP  I171
  J6U2   217  VDD<7>  SCONN288_H44441003_PIP  I171
  J6U2   220  VDD<6>  SCONN288_H44441003_PIP  I171
  J6U2   223  VDD<5>  SCONN288_H44441003_PIP  I171
  J6U2   226  VDD<4>  SCONN288_H44441003_PIP  I171
  J6U2   229  VDD<3>  SCONN288_H44441003_PIP  I171
  J6U2   231  VDD<2>  SCONN288_H44441003_PIP  I171
  J6U2   233  VDD<1>  SCONN288_H44441003_PIP  I171
  J6U2   236  VDD<0>  SCONN288_H44441003_PIP  I171
  L7G1     2    INB  INDUCTOR    I125
  L7G2     2    INB  INDUCTOR    I65
  R3P38    1      A  RES          I7
  R3U4     1      A  RES         I58
  R4F4     1      A  RES         I36
  R4G2     1      A  RES         I38
  R4G21    1      A  RES         I46
  R6U5     1      A  RES         I32
  SH4U2    2      B  SHUNT       I260
  U5D1   AD45  VCCD012<43>  SKX_EXT_B_BGA1  I33
  U5D1   AF55  VCCD012<44>  SKX_EXT_B_BGA1  I33
  U5D1   AF57  VCCD012<45>  SKX_EXT_B_BGA1  I33
  U5D1   AF59  VCCD012<46>  SKX_EXT_B_BGA1  I33
  U5D1   AF61  VCCD012<47>  SKX_EXT_B_BGA1  I33
  U5D1   AF63  VCCD012<48>  SKX_EXT_B_BGA1  I33
  U5D1   B47  VCCD012<51>  SKX_EXT_B_BGA1  I33
  U5D1   B49  VCCD012<0>  SKX_EXT_B_BGA1  I33
  U5D1   B53  VCCD012<1>  SKX_EXT_B_BGA1  I33
  U5D1   B59  VCCD012<2>  SKX_EXT_B_BGA1  I33
  U5D1   C46  VCCD012<50>  SKX_EXT_B_BGA1  I33
  U5D1   D45  VCCD012<49>  SKX_EXT_B_BGA1  I33
  U5D1   E46  VCCD012<3>  SKX_EXT_B_BGA1  I33
  U5D1   E48  VCCD012<4>  SKX_EXT_B_BGA1  I33
  U5D1   E50  VCCD012<5>  SKX_EXT_B_BGA1  I33
  U5D1   E52  VCCD012<6>  SKX_EXT_B_BGA1  I33
  U5D1   E54  VCCD012<7>  SKX_EXT_B_BGA1  I33
  U5D1   E56  VCCD012<8>  SKX_EXT_B_BGA1  I33
  U5D1   E58  VCCD012<9>  SKX_EXT_B_BGA1  I33
  U5D1   E60  VCCD012<10>  SKX_EXT_B_BGA1  I33
  U5D1   E62  VCCD012<11>  SKX_EXT_B_BGA1  I33
  U5D1   E64  VCCD012<12>  SKX_EXT_B_BGA1  I33
  U5D1   L46  VCCD012<13>  SKX_EXT_B_BGA1  I33
  U5D1   L48  VCCD012<14>  SKX_EXT_B_BGA1  I33
  U5D1   L50  VCCD012<15>  SKX_EXT_B_BGA1  I33
  U5D1   L52  VCCD012<16>  SKX_EXT_B_BGA1  I33
  U5D1   L54  VCCD012<17>  SKX_EXT_B_BGA1  I33
  U5D1   L56  VCCD012<18>  SKX_EXT_B_BGA1  I33
  U5D1   L58  VCCD012<19>  SKX_EXT_B_BGA1  I33
  U5D1   L60  VCCD012<20>  SKX_EXT_B_BGA1  I33
  U5D1   L62  VCCD012<21>  SKX_EXT_B_BGA1  I33
  U5D1   N64  VCCD012<22>  SKX_EXT_B_BGA1  I33
  U5D1   U46  VCCD012<23>  SKX_EXT_B_BGA1  I33
  U5D1   U48  VCCD012<24>  SKX_EXT_B_BGA1  I33
  U5D1   U50  VCCD012<25>  SKX_EXT_B_BGA1  I33
  U5D1   U52  VCCD012<26>  SKX_EXT_B_BGA1  I33
  U5D1   U54  VCCD012<27>  SKX_EXT_B_BGA1  I33
  U5D1   U56  VCCD012<28>  SKX_EXT_B_BGA1  I33
  U5D1   U58  VCCD012<29>  SKX_EXT_B_BGA1  I33
  U5D1   U60  VCCD012<30>  SKX_EXT_B_BGA1  I33
  U5D1   U62  VCCD012<31>  SKX_EXT_B_BGA1  I33
  U5D1   W64  VCCD012<32>  SKX_EXT_B_BGA1  I33
  U5D1   Y45  VCCD012<33>  SKX_EXT_B_BGA1  I33
  U5D1   Y47  VCCD012<34>  SKX_EXT_B_BGA1  I33
  U5D1   Y49  VCCD012<35>  SKX_EXT_B_BGA1  I33
  U5D1   Y51  VCCD012<36>  SKX_EXT_B_BGA1  I33
  U5D1   Y53  VCCD012<37>  SKX_EXT_B_BGA1  I33
  U5D1   Y55  VCCD012<38>  SKX_EXT_B_BGA1  I33
  U5D1   Y57  VCCD012<39>  SKX_EXT_B_BGA1  I33
  U5D1   Y59  VCCD012<40>  SKX_EXT_B_BGA1  I33
  U5D1   Y61  VCCD012<41>  SKX_EXT_B_BGA1  I33
  U5D1   Y63  VCCD012<42>  SKX_EXT_B_BGA1  I33

PVDDQ_DEF       @BASEBOARD_FAB2_LIB.BASEBOARD_FAB2(SCH_1):PVDDQ_DEF
  C3L6     1      A  CAPP        I75
  C3L14    1      A  CAPP        I76
  C4L5     1      A  CAPP        I78
  C4M2     1      A  CAP_A       I222
  C4M5     1      A  CAP_A       I196
  C5A1     1      A  CAP_A       I219
  C5A2     1      A  CAP_A       I214
  C5A3     1      A  CAP_A       I210
  C5A4     1      A  CAP_A       I206
  C5A5     1      A  CAP_A       I193
  C5A6     1      A  CAP_A       I212
  C5A7     1      A  CAP_A       I211
  C5A8     1      A  CAP_A       I209
  C5A9     1      A  CAP_A       I208
  C5A10    1      A  CAP         I110
  C5A11    1      A  CAP_A       I221
  C5A12    1      A  CAP_A       I216
  C5A13    1      A  CAP_A       I215
  C5A14    1      A  CAP_A       I213
  C5A15    1      A  CAP_A       I217
  C5A16    1      A  CAP_A       I207
  C5A17    1      A  CAP_A       I205
  C5A18    1      A  CAP_A       I204
  C5A19    1      A  CAP_A       I203
  C5A20    1      A  CAP         I92
  C5B1     1      A  CAP_A       I194
  C5B2     1      A  CAP_A       I197
  C5D6     1      A  CAP         I182
  C5D7     1      A  CAP         I183
  C5D8     1      A  CAP         I184
  C5D9     1      A  CAP         I180
  C5G59    1      A  CAP_A       I79
  C5G60    1      A  CAP_A       I78
  C5G61    1      A  CAP_A       I77
  C5G62    1      A  CAP_A       I76
  C5G63    1      A  CAP_A       I75
  C5G64    1      A  CAP_A       I74
  C5G65    1      A  CAP_A       I73
  C5G66    1      A  CAP_A       I72
  C5G67    1      A  CAP_A       I71
  C5G68    1      A  CAP_A       I88
  C5G69    1      A  CAP_A       I87
  C5G70    1      A  CAP_A       I86
  C5G71    1      A  CAP_A       I85
  C5G72    1      A  CAP_A       I84
  C5G73    1      A  CAP_A       I83
  C5G74    1      A  CAP_A       I82
  C5G75    1      A  CAP_A       I81
  C5G76    1      A  CAP_A       I80
  C5G77    1      A  CAP         I37
  C5G78    1      A  CAP         I41
  C5L1     1      A  CAP         I91
  C5L2     1      A  CAP         I90
  C5L3     1      A  CAP         I89
  C5L6     1      A  CAP_A       I237
  C5L7     1      A  CAP_A       I236
  C5L8     1      A  CAP_A       I234
  C5L9     1      A  CAP_A       I233
  C5L10    1      A  CAP_A       I232
  C5L11    1      A  CAP_A       I231
  C5L12    1      A  CAP_A       I230
  C5L13    1      A  CAP_A       I229
  C5L14    1      A  CAP         I83
  C5L15    1      A  CAP_A       I192
  C5M1     1      A  CAP_A       I223
  C5M2     1      A  CAP_A       I224
  C5M3     1      A  CAP_A       I199
  C5M4     1      A  CAP_A       I225
  C5M5     1      A  CAP_A       I226
  C5M6     1      A  CAP_A       I227
  C5M7     1      A  CAP_A       I228
  C5M8     1      A  CAP         I82
  C5M9     1      A  CAP_A       I195
  C5M10    1      A  CAP_A       I198
  C5M11    1      A  CAP_A       I200
  C5M12    1      A  CAP         I88
  C5P1     1      A  CAP         I179
  C5P2     1      A  CAP         I177
  C6A1     1      A  CAP         I87
  C6A4     1      A  CAP         I68
  C6A5     1      A  CAPP        I77
  C6L3     1      A  CAP         I24
  C6L4     1      A  CAP         I26
  EU4A1   10    VIN  MIC5166_DFN  I31
  EU7A1    1    VOS  IR354XX_SM  I106
  EU7A4    1    VOS  IR354XX_SM  I107
  J4A1    59  VDD<25>  SCONN288_H44441004_PIP  I171
  J4A1    61  VDD<24>  SCONN288_H44441004_PIP  I171
  J4A1    64  VDD<23>  SCONN288_H44441004_PIP  I171
  J4A1    67  VDD<22>  SCONN288_H44441004_PIP  I171
  J4A1    70  VDD<21>  SCONN288_H44441004_PIP  I171
  J4A1    73  VDD<20>  SCONN288_H44441004_PIP  I171
  J4A1    76  VDD<19>  SCONN288_H44441004_PIP  I171
  J4A1    80  VDD<18>  SCONN288_H44441004_PIP  I171
  J4A1    83  VDD<17>  SCONN288_H44441004_PIP  I171
  J4A1    85  VDD<16>  SCONN288_H44441004_PIP  I171
  J4A1    88  VDD<15>  SCONN288_H44441004_PIP  I171
  J4A1    90  VDD<14>  SCONN288_H44441004_PIP  I171
  J4A1    92  VDD<13>  SCONN288_H44441004_PIP  I171
  J4A1   204  VDD<12>  SCONN288_H44441004_PIP  I171
  J4A1   206  VDD<11>  SCONN288_H44441004_PIP  I171
  J4A1   209  VDD<10>  SCONN288_H44441004_PIP  I171
  J4A1   212  VDD<9>  SCONN288_H44441004_PIP  I171
  J4A1   215  VDD<8>  SCONN288_H44441004_PIP  I171
  J4A1   217  VDD<7>  SCONN288_H44441004_PIP  I171
  J4A1   220  VDD<6>  SCONN288_H44441004_PIP  I171
  J4A1   223  VDD<5>  SCONN288_H44441004_PIP  I171
  J4A1   226  VDD<4>  SCONN288_H44441004_PIP  I171
  J4A1   229  VDD<3>  SCONN288_H44441004_PIP  I171
  J4A1   231  VDD<2>  SCONN288_H44441004_PIP  I171
  J4A1   233  VDD<1>  SCONN288_H44441004_PIP  I171
  J4A1   236  VDD<0>  SCONN288_H44441004_PIP  I171
  J4A2    59  VDD<25>  SCONN288_H44441004_PIP  I167
  J4A2    61  VDD<24>  SCONN288_H44441004_PIP  I167
  J4A2    64  VDD<23>  SCONN288_H44441004_PIP  I167
  J4A2    67  VDD<22>  SCONN288_H44441004_PIP  I167
  J4A2    70  VDD<21>  SCONN288_H44441004_PIP  I167
  J4A2    73  VDD<20>  SCONN288_H44441004_PIP  I167
  J4A2    76  VDD<19>  SCONN288_H44441004_PIP  I167
  J4A2    80  VDD<18>  SCONN288_H44441004_PIP  I167
  J4A2    83  VDD<17>  SCONN288_H44441004_PIP  I167
  J4A2    85  VDD<16>  SCONN288_H44441004_PIP  I167
  J4A2    88  VDD<15>  SCONN288_H44441004_PIP  I167
  J4A2    90  VDD<14>  SCONN288_H44441004_PIP  I167
  J4A2    92  VDD<13>  SCONN288_H44441004_PIP  I167
  J4A2   204  VDD<12>  SCONN288_H44441004_PIP  I167
  J4A2   206  VDD<11>  SCONN288_H44441004_PIP  I167
  J4A2   209  VDD<10>  SCONN288_H44441004_PIP  I167
  J4A2   212  VDD<9>  SCONN288_H44441004_PIP  I167
  J4A2   215  VDD<8>  SCONN288_H44441004_PIP  I167
  J4A2   217  VDD<7>  SCONN288_H44441004_PIP  I167
  J4A2   220  VDD<6>  SCONN288_H44441004_PIP  I167
  J4A2   223  VDD<5>  SCONN288_H44441004_PIP  I167
  J4A2   226  VDD<4>  SCONN288_H44441004_PIP  I167
  J4A2   229  VDD<3>  SCONN288_H44441004_PIP  I167
  J4A2   231  VDD<2>  SCONN288_H44441004_PIP  I167
  J4A2   233  VDD<1>  SCONN288_H44441004_PIP  I167
  J4A2   236  VDD<0>  SCONN288_H44441004_PIP  I167
  J4B1    59  VDD<25>  SCONN288_H44441004_PIP  I169
  J4B1    61  VDD<24>  SCONN288_H44441004_PIP  I169
  J4B1    64  VDD<23>  SCONN288_H44441004_PIP  I169
  J4B1    67  VDD<22>  SCONN288_H44441004_PIP  I169
  J4B1    70  VDD<21>  SCONN288_H44441004_PIP  I169
  J4B1    73  VDD<20>  SCONN288_H44441004_PIP  I169
  J4B1    76  VDD<19>  SCONN288_H44441004_PIP  I169
  J4B1    80  VDD<18>  SCONN288_H44441004_PIP  I169
  J4B1    83  VDD<17>  SCONN288_H44441004_PIP  I169
  J4B1    85  VDD<16>  SCONN288_H44441004_PIP  I169
  J4B1    88  VDD<15>  SCONN288_H44441004_PIP  I169
  J4B1    90  VDD<14>  SCONN288_H44441004_PIP  I169
  J4B1    92  VDD<13>  SCONN288_H44441004_PIP  I169
  J4B1   204  VDD<12>  SCONN288_H44441004_PIP  I169
  J4B1   206  VDD<11>  SCONN288_H44441004_PIP  I169
  J4B1   209  VDD<10>  SCONN288_H44441004_PIP  I169
  J4B1   212  VDD<9>  SCONN288_H44441004_PIP  I169
  J4B1   215  VDD<8>  SCONN288_H44441004_PIP  I169
  J4B1   217  VDD<7>  SCONN288_H44441004_PIP  I169
  J4B1   220  VDD<6>  SCONN288_H44441004_PIP  I169
  J4B1   223  VDD<5>  SCONN288_H44441004_PIP  I169
  J4B1   226  VDD<4>  SCONN288_H44441004_PIP  I169
  J4B1   229  VDD<3>  SCONN288_H44441004_PIP  I169
  J4B1   231  VDD<2>  SCONN288_H44441004_PIP  I169
  J4B1   233  VDD<1>  SCONN288_H44441004_PIP  I169
  J4B1   236  VDD<0>  SCONN288_H44441004_PIP  I169
  J6L1    59  VDD<25>  SCONN288_H44441003_PIP  I170
  J6L1    61  VDD<24>  SCONN288_H44441003_PIP  I170
  J6L1    64  VDD<23>  SCONN288_H44441003_PIP  I170
  J6L1    67  VDD<22>  SCONN288_H44441003_PIP  I170
  J6L1    70  VDD<21>  SCONN288_H44441003_PIP  I170
  J6L1    73  VDD<20>  SCONN288_H44441003_PIP  I170
  J6L1    76  VDD<19>  SCONN288_H44441003_PIP  I170
  J6L1    80  VDD<18>  SCONN288_H44441003_PIP  I170
  J6L1    83  VDD<17>  SCONN288_H44441003_PIP  I170
  J6L1    85  VDD<16>  SCONN288_H44441003_PIP  I170
  J6L1    88  VDD<15>  SCONN288_H44441003_PIP  I170
  J6L1    90  VDD<14>  SCONN288_H44441003_PIP  I170
  J6L1    92  VDD<13>  SCONN288_H44441003_PIP  I170
  J6L1   204  VDD<12>  SCONN288_H44441003_PIP  I170
  J6L1   206  VDD<11>  SCONN288_H44441003_PIP  I170
  J6L1   209  VDD<10>  SCONN288_H44441003_PIP  I170
  J6L1   212  VDD<9>  SCONN288_H44441003_PIP  I170
  J6L1   215  VDD<8>  SCONN288_H44441003_PIP  I170
  J6L1   217  VDD<7>  SCONN288_H44441003_PIP  I170
  J6L1   220  VDD<6>  SCONN288_H44441003_PIP  I170
  J6L1   223  VDD<5>  SCONN288_H44441003_PIP  I170
  J6L1   226  VDD<4>  SCONN288_H44441003_PIP  I170
  J6L1   229  VDD<3>  SCONN288_H44441003_PIP  I170
  J6L1   231  VDD<2>  SCONN288_H44441003_PIP  I170
  J6L1   233  VDD<1>  SCONN288_H44441003_PIP  I170
  J6L1   236  VDD<0>  SCONN288_H44441003_PIP  I170
  J6L2    59  VDD<25>  SCONN288_H44441003_PIP  I55
  J6L2    61  VDD<24>  SCONN288_H44441003_PIP  I55
  J6L2    64  VDD<23>  SCONN288_H44441003_PIP  I55
  J6L2    67  VDD<22>  SCONN288_H44441003_PIP  I55
  J6L2    70  VDD<21>  SCONN288_H44441003_PIP  I55
  J6L2    73  VDD<20>  SCONN288_H44441003_PIP  I55
  J6L2    76  VDD<19>  SCONN288_H44441003_PIP  I55
  J6L2    80  VDD<18>  SCONN288_H44441003_PIP  I55
  J6L2    83  VDD<17>  SCONN288_H44441003_PIP  I55
  J6L2    85  VDD<16>  SCONN288_H44441003_PIP  I55
  J6L2    88  VDD<15>  SCONN288_H44441003_PIP  I55
  J6L2    90  VDD<14>  SCONN288_H44441003_PIP  I55
  J6L2    92  VDD<13>  SCONN288_H44441003_PIP  I55
  J6L2   204  VDD<12>  SCONN288_H44441003_PIP  I55
  J6L2   206  VDD<11>  SCONN288_H44441003_PIP  I55
  J6L2   209  VDD<10>  SCONN288_H44441003_PIP  I55
  J6L2   212  VDD<9>  SCONN288_H44441003_PIP  I55
  J6L2   215  VDD<8>  SCONN288_H44441003_PIP  I55
  J6L2   217  VDD<7>  SCONN288_H44441003_PIP  I55
  J6L2   220  VDD<6>  SCONN288_H44441003_PIP  I55
  J6L2   223  VDD<5>  SCONN288_H44441003_PIP  I55
  J6L2   226  VDD<4>  SCONN288_H44441003_PIP  I55
  J6L2   229  VDD<3>  SCONN288_H44441003_PIP  I55
  J6L2   231  VDD<2>  SCONN288_H44441003_PIP  I55
  J6L2   233  VDD<1>  SCONN288_H44441003_PIP  I55
  J6L2   236  VDD<0>  SCONN288_H44441003_PIP  I55
  J6M1    59  VDD<25>  SCONN288_H44441003_PIP  I50
  J6M1    61  VDD<24>  SCONN288_H44441003_PIP  I50
  J6M1    64  VDD<23>  SCONN288_H44441003_PIP  I50
  J6M1    67  VDD<22>  SCONN288_H44441003_PIP  I50
  J6M1    70  VDD<21>  SCONN288_H44441003_PIP  I50
  J6M1    73  VDD<20>  SCONN288_H44441003_PIP  I50
  J6M1    76  VDD<19>  SCONN288_H44441003_PIP  I50
  J6M1    80  VDD<18>  SCONN288_H44441003_PIP  I50
  J6M1    83  VDD<17>  SCONN288_H44441003_PIP  I50
  J6M1    85  VDD<16>  SCONN288_H44441003_PIP  I50
  J6M1    88  VDD<15>  SCONN288_H44441003_PIP  I50
  J6M1    90  VDD<14>  SCONN288_H44441003_PIP  I50
  J6M1    92  VDD<13>  SCONN288_H44441003_PIP  I50
  J6M1   204  VDD<12>  SCONN288_H44441003_PIP  I50
  J6M1   206  VDD<11>  SCONN288_H44441003_PIP  I50
  J6M1   209  VDD<10>  SCONN288_H44441003_PIP  I50
  J6M1   212  VDD<9>  SCONN288_H44441003_PIP  I50
  J6M1   215  VDD<8>  SCONN288_H44441003_PIP  I50
  J6M1   217  VDD<7>  SCONN288_H44441003_PIP  I50
  J6M1   220  VDD<6>  SCONN288_H44441003_PIP  I50
  J6M1   223  VDD<5>  SCONN288_H44441003_PIP  I50
  J6M1   226  VDD<4>  SCONN288_H44441003_PIP  I50
  J6M1   229  VDD<3>  SCONN288_H44441003_PIP  I50
  J6M1   231  VDD<2>  SCONN288_H44441003_PIP  I50
  J6M1   233  VDD<1>  SCONN288_H44441003_PIP  I50
  J6M1   236  VDD<0>  SCONN288_H44441003_PIP  I50
  L7A1     2    INB  INDUCTOR    I55
  L7A3     2    INB  INDUCTOR    I65
  R3P29    1      A  RES          I5
  R4L4     1      A  RES         I58
  R6L2     1      A  RES         I62
  R6L10    1      A  RES         I34
  R6L13    1      A  RES         I54
  R6M1     1      A  RES          I9
  SH4L2    2      B  SHUNT       I239
  U5D1   DB53  VCCD345<48>  SKX_EXT_B_BGA1  I33
  U5D1   DB55  VCCD345<47>  SKX_EXT_B_BGA1  I33
  U5D1   DB57  VCCD345<46>  SKX_EXT_B_BGA1  I33
  U5D1   DB59  VCCD345<45>  SKX_EXT_B_BGA1  I33
  U5D1   DB61  VCCD345<44>  SKX_EXT_B_BGA1  I33
  U5D1   DB63  VCCD345<43>  SKX_EXT_B_BGA1  I33
  U5D1   DD45  VCCD345<42>  SKX_EXT_B_BGA1  I33
  U5D1   DH45  VCCD345<41>  SKX_EXT_B_BGA1  I33
  U5D1   DH47  VCCD345<40>  SKX_EXT_B_BGA1  I33
  U5D1   DH49  VCCD345<39>  SKX_EXT_B_BGA1  I33
  U5D1   DH51  VCCD345<38>  SKX_EXT_B_BGA1  I33
  U5D1   DH53  VCCD345<37>  SKX_EXT_B_BGA1  I33
  U5D1   DH55  VCCD345<36>  SKX_EXT_B_BGA1  I33
  U5D1   DH57  VCCD345<35>  SKX_EXT_B_BGA1  I33
  U5D1   DH59  VCCD345<34>  SKX_EXT_B_BGA1  I33
  U5D1   DH61  VCCD345<33>  SKX_EXT_B_BGA1  I33
  U5D1   DH63  VCCD345<32>  SKX_EXT_B_BGA1  I33
  U5D1   DJ64  VCCD345<31>  SKX_EXT_B_BGA1  I33
  U5D1   DL46  VCCD345<30>  SKX_EXT_B_BGA1  I33
  U5D1   DL48  VCCD345<29>  SKX_EXT_B_BGA1  I33
  U5D1   DL50  VCCD345<28>  SKX_EXT_B_BGA1  I33
  U5D1   DL52  VCCD345<27>  SKX_EXT_B_BGA1  I33
  U5D1   DL54  VCCD345<26>  SKX_EXT_B_BGA1  I33
  U5D1   DL56  VCCD345<25>  SKX_EXT_B_BGA1  I33
  U5D1   DL58  VCCD345<24>  SKX_EXT_B_BGA1  I33
  U5D1   DL60  VCCD345<23>  SKX_EXT_B_BGA1  I33
  U5D1   DL62  VCCD345<22>  SKX_EXT_B_BGA1  I33
  U5D1   DU46  VCCD345<21>  SKX_EXT_B_BGA1  I33
  U5D1   DU48  VCCD345<20>  SKX_EXT_B_BGA1  I33
  U5D1   DU50  VCCD345<19>  SKX_EXT_B_BGA1  I33
  U5D1   DU52  VCCD345<18>  SKX_EXT_B_BGA1  I33
  U5D1   DU54  VCCD345<17>  SKX_EXT_B_BGA1  I33
  U5D1   DU56  VCCD345<16>  SKX_EXT_B_BGA1  I33
  U5D1   DU58  VCCD345<15>  SKX_EXT_B_BGA1  I33
  U5D1   DU60  VCCD345<14>  SKX_EXT_B_BGA1  I33
  U5D1   DU62  VCCD345<13>  SKX_EXT_B_BGA1  I33
  U5D1   DU64  VCCD345<12>  SKX_EXT_B_BGA1  I33
  U5D1   EC46  VCCD345<11>  SKX_EXT_B_BGA1  I33
  U5D1   EC48  VCCD345<10>  SKX_EXT_B_BGA1  I33
  U5D1   EC50  VCCD345<9>  SKX_EXT_B_BGA1  I33
  U5D1   EC52  VCCD345<8>  SKX_EXT_B_BGA1  I33
  U5D1   EC54  VCCD345<7>  SKX_EXT_B_BGA1  I33
  U5D1   EC56  VCCD345<6>  SKX_EXT_B_BGA1  I33
  U5D1   EC58  VCCD345<5>  SKX_EXT_B_BGA1  I33
  U5D1   EC60  VCCD345<4>  SKX_EXT_B_BGA1  I33
  U5D1   EC62  VCCD345<3>  SKX_EXT_B_BGA1  I33
  U5D1   EE44  VCCD345<50>  SKX_EXT_B_BGA1  I33
  U5D1   EF45  VCCD345<49>  SKX_EXT_B_BGA1  I33
  U5D1   EF49  VCCD345<2>  SKX_EXT_B_BGA1  I33
  U5D1   EF53  VCCD345<1>  SKX_EXT_B_BGA1  I33
  U5D1   EF59  VCCD345<0>  SKX_EXT_B_BGA1  I33

PVDDQ_GHJ       @BASEBOARD_FAB2_LIB.BASEBOARD_FAB2(SCH_1):PVDDQ_GHJ
  C1G17    1      A  CAP          I6
  C1G20    1      A  CAP         I68
  C2D41    1      A  CAP         I180
  C2D42    1      A  CAP         I183
  C2D43    1      A  CAP         I179
  C2D44    1      A  CAP         I181
  C2F1     1      A  CAP_A       I201
  C2G1     1      A  CAP_A       I219
  C2G2     1      A  CAP_A       I217
  C2G3     1      A  CAP_A       I216
  C2G4     1      A  CAP_A       I215
  C2G5     1      A  CAP_A       I214
  C2G6     1      A  CAP_A       I213
  C2G7     1      A  CAP         I92
  C2G8     1      A  CAP_A       I197
  C2G9     1      A  CAP_A       I218
  C2G10    1      A  CAP_A       I223
  C2G11    1      A  CAP_A       I221
  C2G12    1      A  CAP_A       I220
  C2G13    1      A  CAP_A       I210
  C2G14    1      A  CAP_A       I209
  C2G15    1      A  CAP_A       I200
  C2G16    1      A  CAP         I110
  C3G1     1      A  CAP_A       I212
  C3G2     1      A  CAP_A       I211
  C3G5     1      A  CAP_A       I208
  C3G6     1      A  CAP_A       I207
  C5G79    1      A  CAP_A       I53
  C5G80    1      A  CAP_A       I61
  C5G81    1      A  CAP_A       I60
  C5G82    1      A  CAP_A       I59
  C5G83    1      A  CAP_A       I58
  C5G84    1      A  CAP_A       I57
  C5G85    1      A  CAP_A       I56
  C5G86    1      A  CAP_A       I55
  C5G87    1      A  CAP_A       I54
  C5G88    1      A  CAP_A       I70
  C5G89    1      A  CAP_A       I69
  C5G90    1      A  CAP_A       I68
  C5G91    1      A  CAP_A       I67
  C5G92    1      A  CAP_A       I66
  C5G93    1      A  CAP_A       I65
  C5G94    1      A  CAP_A       I64
  C5G95    1      A  CAP_A       I63
  C5G96    1      A  CAP_A       I62
  C5G117    1      A  CAP         I12
  C5G118    1      A  CAP         I13
  C6U13    1      A  CAP         I29
  C6U14    1      A  CAP         I25
  C7T1     1      A  CAP         I90
  C7T4     1      A  CAP_A       I235
  C7T5     1      A  CAP_A       I234
  C7U1     1      A  CAP_A       I237
  C7U2     1      A  CAP_A       I238
  C7U7     1      A  CAP         I91
  C8P30    1      A  CAP         I184
  C8P31    1      A  CAP         I178
  C8T1     1      A  CAP_A       I202
  C8T2     1      A  CAP_A       I198
  C8T4     1      A  CAP_A       I196
  C8T5     1      A  CAP_A       I233
  C8T6     1      A  CAP_A       I231
  C8T7     1      A  CAP_A       I230
  C8T8     1      A  CAP_A       I229
  C8T9     1      A  CAP_A       I227
  C8T10    1      A  CAP_A       I226
  C8T11    1      A  CAP_A       I204
  C8U1     1      A  CAP         I82
  C8U2     1      A  CAP_A       I239
  C8U3     1      A  CAP_A       I236
  C8U4     1      A  CAP_A       I225
  C8U5     1      A  CAP_A       I228
  C8U6     1      A  CAP_A       I232
  C8U7     1      A  CAP_A       I241
  C8U8     1      A  CAP         I83
  C8U9     1      A  CAP_A       I203
  C8U11    1      A  CAP         I89
  C8U12    1      A  CAP         I88
  C8U13    1      A  CAP_A       I199
  C9T5     1      A  CAPP        I75
  C9U2     1      A  CAPP        I76
  C9U5     1      A  CAPP        I78
  C9U9     1      A  CAPP        I77
  EU1F1    1    VOS  IR354XX_SM  I111
  EU1G1    1    VOS  IR354XX_SM  I110
  EU4G2   10    VIN  MIC5166_DFN  I24
  J1G1    59  VDD<25>  SCONN288_H44441004_PIP  I171
  J1G1    61  VDD<24>  SCONN288_H44441004_PIP  I171
  J1G1    64  VDD<23>  SCONN288_H44441004_PIP  I171
  J1G1    67  VDD<22>  SCONN288_H44441004_PIP  I171
  J1G1    70  VDD<21>  SCONN288_H44441004_PIP  I171
  J1G1    73  VDD<20>  SCONN288_H44441004_PIP  I171
  J1G1    76  VDD<19>  SCONN288_H44441004_PIP  I171
  J1G1    80  VDD<18>  SCONN288_H44441004_PIP  I171
  J1G1    83  VDD<17>  SCONN288_H44441004_PIP  I171
  J1G1    85  VDD<16>  SCONN288_H44441004_PIP  I171
  J1G1    88  VDD<15>  SCONN288_H44441004_PIP  I171
  J1G1    90  VDD<14>  SCONN288_H44441004_PIP  I171
  J1G1    92  VDD<13>  SCONN288_H44441004_PIP  I171
  J1G1   204  VDD<12>  SCONN288_H44441004_PIP  I171
  J1G1   206  VDD<11>  SCONN288_H44441004_PIP  I171
  J1G1   209  VDD<10>  SCONN288_H44441004_PIP  I171
  J1G1   212  VDD<9>  SCONN288_H44441004_PIP  I171
  J1G1   215  VDD<8>  SCONN288_H44441004_PIP  I171
  J1G1   217  VDD<7>  SCONN288_H44441004_PIP  I171
  J1G1   220  VDD<6>  SCONN288_H44441004_PIP  I171
  J1G1   223  VDD<5>  SCONN288_H44441004_PIP  I171
  J1G1   226  VDD<4>  SCONN288_H44441004_PIP  I171
  J1G1   229  VDD<3>  SCONN288_H44441004_PIP  I171
  J1G1   231  VDD<2>  SCONN288_H44441004_PIP  I171
  J1G1   233  VDD<1>  SCONN288_H44441004_PIP  I171
  J1G1   236  VDD<0>  SCONN288_H44441004_PIP  I171
  J1G2    59  VDD<25>  SCONN288_H44441004_PIP  I169
  J1G2    61  VDD<24>  SCONN288_H44441004_PIP  I169
  J1G2    64  VDD<23>  SCONN288_H44441004_PIP  I169
  J1G2    67  VDD<22>  SCONN288_H44441004_PIP  I169
  J1G2    70  VDD<21>  SCONN288_H44441004_PIP  I169
  J1G2    73  VDD<20>  SCONN288_H44441004_PIP  I169
  J1G2    76  VDD<19>  SCONN288_H44441004_PIP  I169
  J1G2    80  VDD<18>  SCONN288_H44441004_PIP  I169
  J1G2    83  VDD<17>  SCONN288_H44441004_PIP  I169
  J1G2    85  VDD<16>  SCONN288_H44441004_PIP  I169
  J1G2    88  VDD<15>  SCONN288_H44441004_PIP  I169
  J1G2    90  VDD<14>  SCONN288_H44441004_PIP  I169
  J1G2    92  VDD<13>  SCONN288_H44441004_PIP  I169
  J1G2   204  VDD<12>  SCONN288_H44441004_PIP  I169
  J1G2   206  VDD<11>  SCONN288_H44441004_PIP  I169
  J1G2   209  VDD<10>  SCONN288_H44441004_PIP  I169
  J1G2   212  VDD<9>  SCONN288_H44441004_PIP  I169
  J1G2   215  VDD<8>  SCONN288_H44441004_PIP  I169
  J1G2   217  VDD<7>  SCONN288_H44441004_PIP  I169
  J1G2   220  VDD<6>  SCONN288_H44441004_PIP  I169
  J1G2   223  VDD<5>  SCONN288_H44441004_PIP  I169
  J1G2   226  VDD<4>  SCONN288_H44441004_PIP  I169
  J1G2   229  VDD<3>  SCONN288_H44441004_PIP  I169
  J1G2   231  VDD<2>  SCONN288_H44441004_PIP  I169
  J1G2   233  VDD<1>  SCONN288_H44441004_PIP  I169
  J1G2   236  VDD<0>  SCONN288_H44441004_PIP  I169
  J1G3    59  VDD<25>  SCONN288_H44441004_PIP  I169
  J1G3    61  VDD<24>  SCONN288_H44441004_PIP  I169
  J1G3    64  VDD<23>  SCONN288_H44441004_PIP  I169
  J1G3    67  VDD<22>  SCONN288_H44441004_PIP  I169
  J1G3    70  VDD<21>  SCONN288_H44441004_PIP  I169
  J1G3    73  VDD<20>  SCONN288_H44441004_PIP  I169
  J1G3    76  VDD<19>  SCONN288_H44441004_PIP  I169
  J1G3    80  VDD<18>  SCONN288_H44441004_PIP  I169
  J1G3    83  VDD<17>  SCONN288_H44441004_PIP  I169
  J1G3    85  VDD<16>  SCONN288_H44441004_PIP  I169
  J1G3    88  VDD<15>  SCONN288_H44441004_PIP  I169
  J1G3    90  VDD<14>  SCONN288_H44441004_PIP  I169
  J1G3    92  VDD<13>  SCONN288_H44441004_PIP  I169
  J1G3   204  VDD<12>  SCONN288_H44441004_PIP  I169
  J1G3   206  VDD<11>  SCONN288_H44441004_PIP  I169
  J1G3   209  VDD<10>  SCONN288_H44441004_PIP  I169
  J1G3   212  VDD<9>  SCONN288_H44441004_PIP  I169
  J1G3   215  VDD<8>  SCONN288_H44441004_PIP  I169
  J1G3   217  VDD<7>  SCONN288_H44441004_PIP  I169
  J1G3   220  VDD<6>  SCONN288_H44441004_PIP  I169
  J1G3   223  VDD<5>  SCONN288_H44441004_PIP  I169
  J1G3   226  VDD<4>  SCONN288_H44441004_PIP  I169
  J1G3   229  VDD<3>  SCONN288_H44441004_PIP  I169
  J1G3   231  VDD<2>  SCONN288_H44441004_PIP  I169
  J1G3   233  VDD<1>  SCONN288_H44441004_PIP  I169
  J1G3   236  VDD<0>  SCONN288_H44441004_PIP  I169
  J9T1    59  VDD<25>  SCONN288_H44441003_PIP  I75
  J9T1    61  VDD<24>  SCONN288_H44441003_PIP  I75
  J9T1    64  VDD<23>  SCONN288_H44441003_PIP  I75
  J9T1    67  VDD<22>  SCONN288_H44441003_PIP  I75
  J9T1    70  VDD<21>  SCONN288_H44441003_PIP  I75
  J9T1    73  VDD<20>  SCONN288_H44441003_PIP  I75
  J9T1    76  VDD<19>  SCONN288_H44441003_PIP  I75
  J9T1    80  VDD<18>  SCONN288_H44441003_PIP  I75
  J9T1    83  VDD<17>  SCONN288_H44441003_PIP  I75
  J9T1    85  VDD<16>  SCONN288_H44441003_PIP  I75
  J9T1    88  VDD<15>  SCONN288_H44441003_PIP  I75
  J9T1    90  VDD<14>  SCONN288_H44441003_PIP  I75
  J9T1    92  VDD<13>  SCONN288_H44441003_PIP  I75
  J9T1   204  VDD<12>  SCONN288_H44441003_PIP  I75
  J9T1   206  VDD<11>  SCONN288_H44441003_PIP  I75
  J9T1   209  VDD<10>  SCONN288_H44441003_PIP  I75
  J9T1   212  VDD<9>  SCONN288_H44441003_PIP  I75
  J9T1   215  VDD<8>  SCONN288_H44441003_PIP  I75
  J9T1   217  VDD<7>  SCONN288_H44441003_PIP  I75
  J9T1   220  VDD<6>  SCONN288_H44441003_PIP  I75
  J9T1   223  VDD<5>  SCONN288_H44441003_PIP  I75
  J9T1   226  VDD<4>  SCONN288_H44441003_PIP  I75
  J9T1   229  VDD<3>  SCONN288_H44441003_PIP  I75
  J9T1   231  VDD<2>  SCONN288_H44441003_PIP  I75
  J9T1   233  VDD<1>  SCONN288_H44441003_PIP  I75
  J9T1   236  VDD<0>  SCONN288_H44441003_PIP  I75
  J9U1    59  VDD<25>  SCONN288_H44441003_PIP  I56
  J9U1    61  VDD<24>  SCONN288_H44441003_PIP  I56
  J9U1    64  VDD<23>  SCONN288_H44441003_PIP  I56
  J9U1    67  VDD<22>  SCONN288_H44441003_PIP  I56
  J9U1    70  VDD<21>  SCONN288_H44441003_PIP  I56
  J9U1    73  VDD<20>  SCONN288_H44441003_PIP  I56
  J9U1    76  VDD<19>  SCONN288_H44441003_PIP  I56
  J9U1    80  VDD<18>  SCONN288_H44441003_PIP  I56
  J9U1    83  VDD<17>  SCONN288_H44441003_PIP  I56
  J9U1    85  VDD<16>  SCONN288_H44441003_PIP  I56
  J9U1    88  VDD<15>  SCONN288_H44441003_PIP  I56
  J9U1    90  VDD<14>  SCONN288_H44441003_PIP  I56
  J9U1    92  VDD<13>  SCONN288_H44441003_PIP  I56
  J9U1   204  VDD<12>  SCONN288_H44441003_PIP  I56
  J9U1   206  VDD<11>  SCONN288_H44441003_PIP  I56
  J9U1   209  VDD<10>  SCONN288_H44441003_PIP  I56
  J9U1   212  VDD<9>  SCONN288_H44441003_PIP  I56
  J9U1   215  VDD<8>  SCONN288_H44441003_PIP  I56
  J9U1   217  VDD<7>  SCONN288_H44441003_PIP  I56
  J9U1   220  VDD<6>  SCONN288_H44441003_PIP  I56
  J9U1   223  VDD<5>  SCONN288_H44441003_PIP  I56
  J9U1   226  VDD<4>  SCONN288_H44441003_PIP  I56
  J9U1   229  VDD<3>  SCONN288_H44441003_PIP  I56
  J9U1   231  VDD<2>  SCONN288_H44441003_PIP  I56
  J9U1   233  VDD<1>  SCONN288_H44441003_PIP  I56
  J9U1   236  VDD<0>  SCONN288_H44441003_PIP  I56
  J9U2    59  VDD<25>  SCONN288_H44441003_PIP  I171
  J9U2    61  VDD<24>  SCONN288_H44441003_PIP  I171
  J9U2    64  VDD<23>  SCONN288_H44441003_PIP  I171
  J9U2    67  VDD<22>  SCONN288_H44441003_PIP  I171
  J9U2    70  VDD<21>  SCONN288_H44441003_PIP  I171
  J9U2    73  VDD<20>  SCONN288_H44441003_PIP  I171
  J9U2    76  VDD<19>  SCONN288_H44441003_PIP  I171
  J9U2    80  VDD<18>  SCONN288_H44441003_PIP  I171
  J9U2    83  VDD<17>  SCONN288_H44441003_PIP  I171
  J9U2    85  VDD<16>  SCONN288_H44441003_PIP  I171
  J9U2    88  VDD<15>  SCONN288_H44441003_PIP  I171
  J9U2    90  VDD<14>  SCONN288_H44441003_PIP  I171
  J9U2    92  VDD<13>  SCONN288_H44441003_PIP  I171
  J9U2   204  VDD<12>  SCONN288_H44441003_PIP  I171
  J9U2   206  VDD<11>  SCONN288_H44441003_PIP  I171
  J9U2   209  VDD<10>  SCONN288_H44441003_PIP  I171
  J9U2   212  VDD<9>  SCONN288_H44441003_PIP  I171
  J9U2   215  VDD<8>  SCONN288_H44441003_PIP  I171
  J9U2   217  VDD<7>  SCONN288_H44441003_PIP  I171
  J9U2   220  VDD<6>  SCONN288_H44441003_PIP  I171
  J9U2   223  VDD<5>  SCONN288_H44441003_PIP  I171
  J9U2   226  VDD<4>  SCONN288_H44441003_PIP  I171
  J9U2   229  VDD<3>  SCONN288_H44441003_PIP  I171
  J9U2   231  VDD<2>  SCONN288_H44441003_PIP  I171
  J9U2   233  VDD<1>  SCONN288_H44441003_PIP  I171
  J9U2   236  VDD<0>  SCONN288_H44441003_PIP  I171
  L1F2     2    INB  INDUCTOR    I65
  L1G1     2    INB  INDUCTOR    I55
  R1F5     1      A  RES          I6
  R1G2     1      A  RES         I19
  R1G15    1      A  RES         I35
  R1G20    1      A  RES         I58
  R3D21    1      A  RES         I30
  R6U6     1      A  RES         I39
  SH7U1    2      B  SHUNT       I243
  U2D1   AD45  VCCD012<43>  SKX_EXT_B_BGA1  I32
  U2D1   AF55  VCCD012<44>  SKX_EXT_B_BGA1  I32
  U2D1   AF57  VCCD012<45>  SKX_EXT_B_BGA1  I32
  U2D1   AF59  VCCD012<46>  SKX_EXT_B_BGA1  I32
  U2D1   AF61  VCCD012<47>  SKX_EXT_B_BGA1  I32
  U2D1   AF63  VCCD012<48>  SKX_EXT_B_BGA1  I32
  U2D1   B47  VCCD012<51>  SKX_EXT_B_BGA1  I32
  U2D1   B49  VCCD012<0>  SKX_EXT_B_BGA1  I32
  U2D1   B53  VCCD012<1>  SKX_EXT_B_BGA1  I32
  U2D1   B59  VCCD012<2>  SKX_EXT_B_BGA1  I32
  U2D1   C46  VCCD012<50>  SKX_EXT_B_BGA1  I32
  U2D1   D45  VCCD012<49>  SKX_EXT_B_BGA1  I32
  U2D1   E46  VCCD012<3>  SKX_EXT_B_BGA1  I32
  U2D1   E48  VCCD012<4>  SKX_EXT_B_BGA1  I32
  U2D1   E50  VCCD012<5>  SKX_EXT_B_BGA1  I32
  U2D1   E52  VCCD012<6>  SKX_EXT_B_BGA1  I32
  U2D1   E54  VCCD012<7>  SKX_EXT_B_BGA1  I32
  U2D1   E56  VCCD012<8>  SKX_EXT_B_BGA1  I32
  U2D1   E58  VCCD012<9>  SKX_EXT_B_BGA1  I32
  U2D1   E60  VCCD012<10>  SKX_EXT_B_BGA1  I32
  U2D1   E62  VCCD012<11>  SKX_EXT_B_BGA1  I32
  U2D1   E64  VCCD012<12>  SKX_EXT_B_BGA1  I32
  U2D1   L46  VCCD012<13>  SKX_EXT_B_BGA1  I32
  U2D1   L48  VCCD012<14>  SKX_EXT_B_BGA1  I32
  U2D1   L50  VCCD012<15>  SKX_EXT_B_BGA1  I32
  U2D1   L52  VCCD012<16>  SKX_EXT_B_BGA1  I32
  U2D1   L54  VCCD012<17>  SKX_EXT_B_BGA1  I32
  U2D1   L56  VCCD012<18>  SKX_EXT_B_BGA1  I32
  U2D1   L58  VCCD012<19>  SKX_EXT_B_BGA1  I32
  U2D1   L60  VCCD012<20>  SKX_EXT_B_BGA1  I32
  U2D1   L62  VCCD012<21>  SKX_EXT_B_BGA1  I32
  U2D1   N64  VCCD012<22>  SKX_EXT_B_BGA1  I32
  U2D1   U46  VCCD012<23>  SKX_EXT_B_BGA1  I32
  U2D1   U48  VCCD012<24>  SKX_EXT_B_BGA1  I32
  U2D1   U50  VCCD012<25>  SKX_EXT_B_BGA1  I32
  U2D1   U52  VCCD012<26>  SKX_EXT_B_BGA1  I32
  U2D1   U54  VCCD012<27>  SKX_EXT_B_BGA1  I32
  U2D1   U56  VCCD012<28>  SKX_EXT_B_BGA1  I32
  U2D1   U58  VCCD012<29>  SKX_EXT_B_BGA1  I32
  U2D1   U60  VCCD012<30>  SKX_EXT_B_BGA1  I32
  U2D1   U62  VCCD012<31>  SKX_EXT_B_BGA1  I32
  U2D1   W64  VCCD012<32>  SKX_EXT_B_BGA1  I32
  U2D1   Y45  VCCD012<33>  SKX_EXT_B_BGA1  I32
  U2D1   Y47  VCCD012<34>  SKX_EXT_B_BGA1  I32
  U2D1   Y49  VCCD012<35>  SKX_EXT_B_BGA1  I32
  U2D1   Y51  VCCD012<36>  SKX_EXT_B_BGA1  I32
  U2D1   Y53  VCCD012<37>  SKX_EXT_B_BGA1  I32
  U2D1   Y55  VCCD012<38>  SKX_EXT_B_BGA1  I32
  U2D1   Y57  VCCD012<39>  SKX_EXT_B_BGA1  I32
  U2D1   Y59  VCCD012<40>  SKX_EXT_B_BGA1  I32
  U2D1   Y61  VCCD012<41>  SKX_EXT_B_BGA1  I32
  U2D1   Y63  VCCD012<42>  SKX_EXT_B_BGA1  I32

PVDDQ_KLM       @BASEBOARD_FAB2_LIB.BASEBOARD_FAB2(SCH_1):PVDDQ_KLM
  C1A1     1      A  CAP         I68
  C1A12    1      A  CAP          I6
  C2A1     1      A  CAP_A       I210
  C2A2     1      A  CAP_A       I209
  C2A3     1      A  CAP_A       I230
  C2A4     1      A  CAP_A       I234
  C2A5     1      A  CAP_A       I199
  C2A6     1      A  CAP_A       I219
  C2A7     1      A  CAP_A       I218
  C2A8     1      A  CAP         I82
  C2A9     1      A  CAP_A       I215
  C2A10    1      A  CAP_A       I214
  C2A11    1      A  CAP_A       I213
  C2A12    1      A  CAP_A       I211
  C2A13    1      A  CAP_A       I212
  C2A14    1      A  CAP_A       I220
  C2A15    1      A  CAP_A       I221
  C2A16    1      A  CAP         I89
  C2B1     1      A  CAP_A       I200
  C2B2     1      A  CAP_A       I204
  C2D4     1      A  CAP         I187
  C2D5     1      A  CAP         I188
  C2D6     1      A  CAP         I190
  C2D7     1      A  CAP         I186
  C3A1     1      A  CAP_A       I217
  C3A2     1      A  CAP_A       I216
  C3A5     1      A  CAP_A       I222
  C3A6     1      A  CAP_A       I223
  C4A15    1      A  CAP         I25
  C5G97    1      A  CAP_A       I79
  C5G98    1      A  CAP_A       I78
  C5G99    1      A  CAP_A       I77
  C5G100    1      A  CAP_A       I76
  C5G101    1      A  CAP_A       I75
  C5G102    1      A  CAP_A       I74
  C5G103    1      A  CAP_A       I71
  C5G104    1      A  CAP_A       I72
  C5G105    1      A  CAP_A       I73
  C5G106    1      A  CAP_A       I88
  C5G107    1      A  CAP_A       I87
  C5G108    1      A  CAP_A       I86
  C5G109    1      A  CAP_A       I85
  C5G110    1      A  CAP_A       I84
  C5G111    1      A  CAP_A       I83
  C5G112    1      A  CAP_A       I82
  C5G113    1      A  CAP_A       I81
  C5G114    1      A  CAP_A       I80
  C5G115    1      A  CAP         I39
  C5G116    1      A  CAP         I43
  C6L5     1      A  CAP         I26
  C7L1     1      A  CAP         I92
  C7L4     1      A  CAP_A       I238
  C7L5     1      A  CAP_A       I225
  C7M1     1      A  CAP_A       I231
  C7M2     1      A  CAP_A       I232
  C7M5     1      A  CAP_A       I202
  C8L1     1      A  CAP         I110
  C8L2     1      A  CAP         I83
  C8L5     1      A  CAP_A       I241
  C8L6     1      A  CAP_A       I240
  C8L7     1      A  CAP_A       I239
  C8L8     1      A  CAP_A       I237
  C8L9     1      A  CAP_A       I236
  C8L10    1      A  CAP_A       I229
  C8L11    1      A  CAP         I88
  C8L12    1      A  CAP_A       I201
  C8M1     1      A  CAP_A       I243
  C8M2     1      A  CAP_A       I206
  C8M3     1      A  CAP_A       I227
  C8M4     1      A  CAP_A       I233
  C8M5     1      A  CAP_A       I228
  C8M6     1      A  CAP_A       I235
  C8M7     1      A  CAP         I90
  C8M8     1      A  CAP_A       I198
  C8M9     1      A  CAP_A       I205
  C8M10    1      A  CAP_A       I203
  C8M11    1      A  CAP         I91
  C8P1     1      A  CAP         I185
  C8P2     1      A  CAP         I183
  C9L2     1      A  CAPP        I78
  C9L4     1      A  CAPP        I77
  C9L9     1      A  CAPP        I75
  C9L12    1      A  CAPP        I76
  EU1A1    1    VOS  IR354XX_SM  I102
  EU1A2    1    VOS  IR354XX_SM  I101
  EU4A2   10    VIN  MIC5166_DFN  I31
  J1A1    59  VDD<25>  SCONN288_H44441004_PIP  I169
  J1A1    61  VDD<24>  SCONN288_H44441004_PIP  I169
  J1A1    64  VDD<23>  SCONN288_H44441004_PIP  I169
  J1A1    67  VDD<22>  SCONN288_H44441004_PIP  I169
  J1A1    70  VDD<21>  SCONN288_H44441004_PIP  I169
  J1A1    73  VDD<20>  SCONN288_H44441004_PIP  I169
  J1A1    76  VDD<19>  SCONN288_H44441004_PIP  I169
  J1A1    80  VDD<18>  SCONN288_H44441004_PIP  I169
  J1A1    83  VDD<17>  SCONN288_H44441004_PIP  I169
  J1A1    85  VDD<16>  SCONN288_H44441004_PIP  I169
  J1A1    88  VDD<15>  SCONN288_H44441004_PIP  I169
  J1A1    90  VDD<14>  SCONN288_H44441004_PIP  I169
  J1A1    92  VDD<13>  SCONN288_H44441004_PIP  I169
  J1A1   204  VDD<12>  SCONN288_H44441004_PIP  I169
  J1A1   206  VDD<11>  SCONN288_H44441004_PIP  I169
  J1A1   209  VDD<10>  SCONN288_H44441004_PIP  I169
  J1A1   212  VDD<9>  SCONN288_H44441004_PIP  I169
  J1A1   215  VDD<8>  SCONN288_H44441004_PIP  I169
  J1A1   217  VDD<7>  SCONN288_H44441004_PIP  I169
  J1A1   220  VDD<6>  SCONN288_H44441004_PIP  I169
  J1A1   223  VDD<5>  SCONN288_H44441004_PIP  I169
  J1A1   226  VDD<4>  SCONN288_H44441004_PIP  I169
  J1A1   229  VDD<3>  SCONN288_H44441004_PIP  I169
  J1A1   231  VDD<2>  SCONN288_H44441004_PIP  I169
  J1A1   233  VDD<1>  SCONN288_H44441004_PIP  I169
  J1A1   236  VDD<0>  SCONN288_H44441004_PIP  I169
  J1A2    59  VDD<25>  SCONN288_H44441004_PIP  I172
  J1A2    61  VDD<24>  SCONN288_H44441004_PIP  I172
  J1A2    64  VDD<23>  SCONN288_H44441004_PIP  I172
  J1A2    67  VDD<22>  SCONN288_H44441004_PIP  I172
  J1A2    70  VDD<21>  SCONN288_H44441004_PIP  I172
  J1A2    73  VDD<20>  SCONN288_H44441004_PIP  I172
  J1A2    76  VDD<19>  SCONN288_H44441004_PIP  I172
  J1A2    80  VDD<18>  SCONN288_H44441004_PIP  I172
  J1A2    83  VDD<17>  SCONN288_H44441004_PIP  I172
  J1A2    85  VDD<16>  SCONN288_H44441004_PIP  I172
  J1A2    88  VDD<15>  SCONN288_H44441004_PIP  I172
  J1A2    90  VDD<14>  SCONN288_H44441004_PIP  I172
  J1A2    92  VDD<13>  SCONN288_H44441004_PIP  I172
  J1A2   204  VDD<12>  SCONN288_H44441004_PIP  I172
  J1A2   206  VDD<11>  SCONN288_H44441004_PIP  I172
  J1A2   209  VDD<10>  SCONN288_H44441004_PIP  I172
  J1A2   212  VDD<9>  SCONN288_H44441004_PIP  I172
  J1A2   215  VDD<8>  SCONN288_H44441004_PIP  I172
  J1A2   217  VDD<7>  SCONN288_H44441004_PIP  I172
  J1A2   220  VDD<6>  SCONN288_H44441004_PIP  I172
  J1A2   223  VDD<5>  SCONN288_H44441004_PIP  I172
  J1A2   226  VDD<4>  SCONN288_H44441004_PIP  I172
  J1A2   229  VDD<3>  SCONN288_H44441004_PIP  I172
  J1A2   231  VDD<2>  SCONN288_H44441004_PIP  I172
  J1A2   233  VDD<1>  SCONN288_H44441004_PIP  I172
  J1A2   236  VDD<0>  SCONN288_H44441004_PIP  I172
  J1B1    59  VDD<25>  SCONN288_H44441004_PIP  I167
  J1B1    61  VDD<24>  SCONN288_H44441004_PIP  I167
  J1B1    64  VDD<23>  SCONN288_H44441004_PIP  I167
  J1B1    67  VDD<22>  SCONN288_H44441004_PIP  I167
  J1B1    70  VDD<21>  SCONN288_H44441004_PIP  I167
  J1B1    73  VDD<20>  SCONN288_H44441004_PIP  I167
  J1B1    76  VDD<19>  SCONN288_H44441004_PIP  I167
  J1B1    80  VDD<18>  SCONN288_H44441004_PIP  I167
  J1B1    83  VDD<17>  SCONN288_H44441004_PIP  I167
  J1B1    85  VDD<16>  SCONN288_H44441004_PIP  I167
  J1B1    88  VDD<15>  SCONN288_H44441004_PIP  I167
  J1B1    90  VDD<14>  SCONN288_H44441004_PIP  I167
  J1B1    92  VDD<13>  SCONN288_H44441004_PIP  I167
  J1B1   204  VDD<12>  SCONN288_H44441004_PIP  I167
  J1B1   206  VDD<11>  SCONN288_H44441004_PIP  I167
  J1B1   209  VDD<10>  SCONN288_H44441004_PIP  I167
  J1B1   212  VDD<9>  SCONN288_H44441004_PIP  I167
  J1B1   215  VDD<8>  SCONN288_H44441004_PIP  I167
  J1B1   217  VDD<7>  SCONN288_H44441004_PIP  I167
  J1B1   220  VDD<6>  SCONN288_H44441004_PIP  I167
  J1B1   223  VDD<5>  SCONN288_H44441004_PIP  I167
  J1B1   226  VDD<4>  SCONN288_H44441004_PIP  I167
  J1B1   229  VDD<3>  SCONN288_H44441004_PIP  I167
  J1B1   231  VDD<2>  SCONN288_H44441004_PIP  I167
  J1B1   233  VDD<1>  SCONN288_H44441004_PIP  I167
  J1B1   236  VDD<0>  SCONN288_H44441004_PIP  I167
  J9L1    59  VDD<25>  SCONN288_H44441003_PIP  I168
  J9L1    61  VDD<24>  SCONN288_H44441003_PIP  I168
  J9L1    64  VDD<23>  SCONN288_H44441003_PIP  I168
  J9L1    67  VDD<22>  SCONN288_H44441003_PIP  I168
  J9L1    70  VDD<21>  SCONN288_H44441003_PIP  I168
  J9L1    73  VDD<20>  SCONN288_H44441003_PIP  I168
  J9L1    76  VDD<19>  SCONN288_H44441003_PIP  I168
  J9L1    80  VDD<18>  SCONN288_H44441003_PIP  I168
  J9L1    83  VDD<17>  SCONN288_H44441003_PIP  I168
  J9L1    85  VDD<16>  SCONN288_H44441003_PIP  I168
  J9L1    88  VDD<15>  SCONN288_H44441003_PIP  I168
  J9L1    90  VDD<14>  SCONN288_H44441003_PIP  I168
  J9L1    92  VDD<13>  SCONN288_H44441003_PIP  I168
  J9L1   204  VDD<12>  SCONN288_H44441003_PIP  I168
  J9L1   206  VDD<11>  SCONN288_H44441003_PIP  I168
  J9L1   209  VDD<10>  SCONN288_H44441003_PIP  I168
  J9L1   212  VDD<9>  SCONN288_H44441003_PIP  I168
  J9L1   215  VDD<8>  SCONN288_H44441003_PIP  I168
  J9L1   217  VDD<7>  SCONN288_H44441003_PIP  I168
  J9L1   220  VDD<6>  SCONN288_H44441003_PIP  I168
  J9L1   223  VDD<5>  SCONN288_H44441003_PIP  I168
  J9L1   226  VDD<4>  SCONN288_H44441003_PIP  I168
  J9L1   229  VDD<3>  SCONN288_H44441003_PIP  I168
  J9L1   231  VDD<2>  SCONN288_H44441003_PIP  I168
  J9L1   233  VDD<1>  SCONN288_H44441003_PIP  I168
  J9L1   236  VDD<0>  SCONN288_H44441003_PIP  I168
  J9L2    59  VDD<25>  SCONN288_H44441003_PIP  I55
  J9L2    61  VDD<24>  SCONN288_H44441003_PIP  I55
  J9L2    64  VDD<23>  SCONN288_H44441003_PIP  I55
  J9L2    67  VDD<22>  SCONN288_H44441003_PIP  I55
  J9L2    70  VDD<21>  SCONN288_H44441003_PIP  I55
  J9L2    73  VDD<20>  SCONN288_H44441003_PIP  I55
  J9L2    76  VDD<19>  SCONN288_H44441003_PIP  I55
  J9L2    80  VDD<18>  SCONN288_H44441003_PIP  I55
  J9L2    83  VDD<17>  SCONN288_H44441003_PIP  I55
  J9L2    85  VDD<16>  SCONN288_H44441003_PIP  I55
  J9L2    88  VDD<15>  SCONN288_H44441003_PIP  I55
  J9L2    90  VDD<14>  SCONN288_H44441003_PIP  I55
  J9L2    92  VDD<13>  SCONN288_H44441003_PIP  I55
  J9L2   204  VDD<12>  SCONN288_H44441003_PIP  I55
  J9L2   206  VDD<11>  SCONN288_H44441003_PIP  I55
  J9L2   209  VDD<10>  SCONN288_H44441003_PIP  I55
  J9L2   212  VDD<9>  SCONN288_H44441003_PIP  I55
  J9L2   215  VDD<8>  SCONN288_H44441003_PIP  I55
  J9L2   217  VDD<7>  SCONN288_H44441003_PIP  I55
  J9L2   220  VDD<6>  SCONN288_H44441003_PIP  I55
  J9L2   223  VDD<5>  SCONN288_H44441003_PIP  I55
  J9L2   226  VDD<4>  SCONN288_H44441003_PIP  I55
  J9L2   229  VDD<3>  SCONN288_H44441003_PIP  I55
  J9L2   231  VDD<2>  SCONN288_H44441003_PIP  I55
  J9L2   233  VDD<1>  SCONN288_H44441003_PIP  I55
  J9L2   236  VDD<0>  SCONN288_H44441003_PIP  I55
  J9M1    59  VDD<25>  SCONN288_H44441003_PIP  I57
  J9M1    61  VDD<24>  SCONN288_H44441003_PIP  I57
  J9M1    64  VDD<23>  SCONN288_H44441003_PIP  I57
  J9M1    67  VDD<22>  SCONN288_H44441003_PIP  I57
  J9M1    70  VDD<21>  SCONN288_H44441003_PIP  I57
  J9M1    73  VDD<20>  SCONN288_H44441003_PIP  I57
  J9M1    76  VDD<19>  SCONN288_H44441003_PIP  I57
  J9M1    80  VDD<18>  SCONN288_H44441003_PIP  I57
  J9M1    83  VDD<17>  SCONN288_H44441003_PIP  I57
  J9M1    85  VDD<16>  SCONN288_H44441003_PIP  I57
  J9M1    88  VDD<15>  SCONN288_H44441003_PIP  I57
  J9M1    90  VDD<14>  SCONN288_H44441003_PIP  I57
  J9M1    92  VDD<13>  SCONN288_H44441003_PIP  I57
  J9M1   204  VDD<12>  SCONN288_H44441003_PIP  I57
  J9M1   206  VDD<11>  SCONN288_H44441003_PIP  I57
  J9M1   209  VDD<10>  SCONN288_H44441003_PIP  I57
  J9M1   212  VDD<9>  SCONN288_H44441003_PIP  I57
  J9M1   215  VDD<8>  SCONN288_H44441003_PIP  I57
  J9M1   217  VDD<7>  SCONN288_H44441003_PIP  I57
  J9M1   220  VDD<6>  SCONN288_H44441003_PIP  I57
  J9M1   223  VDD<5>  SCONN288_H44441003_PIP  I57
  J9M1   226  VDD<4>  SCONN288_H44441003_PIP  I57
  J9M1   229  VDD<3>  SCONN288_H44441003_PIP  I57
  J9M1   231  VDD<2>  SCONN288_H44441003_PIP  I57
  J9M1   233  VDD<1>  SCONN288_H44441003_PIP  I57
  J9M1   236  VDD<0>  SCONN288_H44441003_PIP  I57
  L1A1     2    INB  INDUCTOR    I65
  L1A2     2    INB  INDUCTOR    I55
  R1A1     1      A  RES         I58
  R6L6     1      A  RES         I34
  R7M9     1      A  RES         I28
  R9L2     1      A  RES         I38
  R9L7     1      A  RES         I22
  R9M1     1      A  RES         I11
  SH7L2    2      B  SHUNT       I245
  U2D1   DB53  VCCD345<48>  SKX_EXT_B_BGA1  I32
  U2D1   DB55  VCCD345<47>  SKX_EXT_B_BGA1  I32
  U2D1   DB57  VCCD345<46>  SKX_EXT_B_BGA1  I32
  U2D1   DB59  VCCD345<45>  SKX_EXT_B_BGA1  I32
  U2D1   DB61  VCCD345<44>  SKX_EXT_B_BGA1  I32
  U2D1   DB63  VCCD345<43>  SKX_EXT_B_BGA1  I32
  U2D1   DD45  VCCD345<42>  SKX_EXT_B_BGA1  I32
  U2D1   DH45  VCCD345<41>  SKX_EXT_B_BGA1  I32
  U2D1   DH47  VCCD345<40>  SKX_EXT_B_BGA1  I32
  U2D1   DH49  VCCD345<39>  SKX_EXT_B_BGA1  I32
  U2D1   DH51  VCCD345<38>  SKX_EXT_B_BGA1  I32
  U2D1   DH53  VCCD345<37>  SKX_EXT_B_BGA1  I32
  U2D1   DH55  VCCD345<36>  SKX_EXT_B_BGA1  I32
  U2D1   DH57  VCCD345<35>  SKX_EXT_B_BGA1  I32
  U2D1   DH59  VCCD345<34>  SKX_EXT_B_BGA1  I32
  U2D1   DH61  VCCD345<33>  SKX_EXT_B_BGA1  I32
  U2D1   DH63  VCCD345<32>  SKX_EXT_B_BGA1  I32
  U2D1   DJ64  VCCD345<31>  SKX_EXT_B_BGA1  I32
  U2D1   DL46  VCCD345<30>  SKX_EXT_B_BGA1  I32
  U2D1   DL48  VCCD345<29>  SKX_EXT_B_BGA1  I32
  U2D1   DL50  VCCD345<28>  SKX_EXT_B_BGA1  I32
  U2D1   DL52  VCCD345<27>  SKX_EXT_B_BGA1  I32
  U2D1   DL54  VCCD345<26>  SKX_EXT_B_BGA1  I32
  U2D1   DL56  VCCD345<25>  SKX_EXT_B_BGA1  I32
  U2D1   DL58  VCCD345<24>  SKX_EXT_B_BGA1  I32
  U2D1   DL60  VCCD345<23>  SKX_EXT_B_BGA1  I32
  U2D1   DL62  VCCD345<22>  SKX_EXT_B_BGA1  I32
  U2D1   DU46  VCCD345<21>  SKX_EXT_B_BGA1  I32
  U2D1   DU48  VCCD345<20>  SKX_EXT_B_BGA1  I32
  U2D1   DU50  VCCD345<19>  SKX_EXT_B_BGA1  I32
  U2D1   DU52  VCCD345<18>  SKX_EXT_B_BGA1  I32
  U2D1   DU54  VCCD345<17>  SKX_EXT_B_BGA1  I32
  U2D1   DU56  VCCD345<16>  SKX_EXT_B_BGA1  I32
  U2D1   DU58  VCCD345<15>  SKX_EXT_B_BGA1  I32
  U2D1   DU60  VCCD345<14>  SKX_EXT_B_BGA1  I32
  U2D1   DU62  VCCD345<13>  SKX_EXT_B_BGA1  I32
  U2D1   DU64  VCCD345<12>  SKX_EXT_B_BGA1  I32
  U2D1   EC46  VCCD345<11>  SKX_EXT_B_BGA1  I32
  U2D1   EC48  VCCD345<10>  SKX_EXT_B_BGA1  I32
  U2D1   EC50  VCCD345<9>  SKX_EXT_B_BGA1  I32
  U2D1   EC52  VCCD345<8>  SKX_EXT_B_BGA1  I32
  U2D1   EC54  VCCD345<7>  SKX_EXT_B_BGA1  I32
  U2D1   EC56  VCCD345<6>  SKX_EXT_B_BGA1  I32
  U2D1   EC58  VCCD345<5>  SKX_EXT_B_BGA1  I32
  U2D1   EC60  VCCD345<4>  SKX_EXT_B_BGA1  I32
  U2D1   EC62  VCCD345<3>  SKX_EXT_B_BGA1  I32
  U2D1   EE44  VCCD345<50>  SKX_EXT_B_BGA1  I32
  U2D1   EF45  VCCD345<49>  SKX_EXT_B_BGA1  I32
  U2D1   EF49  VCCD345<2>  SKX_EXT_B_BGA1  I32
  U2D1   EF53  VCCD345<1>  SKX_EXT_B_BGA1  I32
  U2D1   EF59  VCCD345<0>  SKX_EXT_B_BGA1  I32

PVNN_PCH_STBY   @BASEBOARD_FAB2_LIB.BASEBOARD_FAB2(SCH_1):PVNN_PCH_STBY
  C2N3     1      A  CAP_A       I27
  C2N4     1      A  CAP_A       I28
  C2N9     1      A  CAP_A       I26
  C2N11    1      A  CAP_A       I30
  C2N12    1      A  CAP_A       I29
  C3L18    1      A  CAPP        I71
  C3L20    1      A  CAPP        I73
  C3L21    1      A  CAPP        I74
  C3L22    1      A  CAP_A       I54
  C3L23    1      A  CAP_A       I52
  C3L24    1      A  CAP_A       I56
  C3L25    1      A  CAP_A        I1
  C3L26    1      A  CAP_A        I3
  C3L27    1      A  CAP_A        I4
  C3M6     1      A  CAP_A        I6
  C3M7     1      A  CAP_A        I2
  C3N1     1      A  CAP_A       I34
  C3N2     1      A  CAP_A       I43
  C3N3     1      A  CAP_A       I32
  C3N4     1      A  CAP_A       I46
  C3N5     1      A  CAP_A       I48
  C3N6     1      A  CAP_A       I44
  C3N7     1      A  CAP_A       I35
  C3N10    1      A  CAP_A       I13
  C3N11    1      A  CAP_A       I19
  C3N12    1      A  CAP_A       I12
  C3N15    1      A  CAP_A       I49
  C3N16    1      A  CAP_A       I36
  C3N17    1      A  CAP_A       I45
  C3N18    1      A  CAP_A       I42
  C3N19    1      A  CAP_A       I31
  C3N20    1      A  CAP_A       I51
  C3N24    1      A  CAP_A       I16
  C3N27    1      A  CAP_A        I8
  C3N28    1      A  CAP_A       I17
  C3N30    1      A  CAP_A        I9
  C3N31    1      A  CAP_A       I20
  C7A27    1      A  CAPP        I75
  C7A30    1      A  CAP          I9
  C7A31    1      A  CAP         I40
  C7A32    1      A  CAP         I38
  C7A33    1      A  CAP         I23
  C7A36    1      A  CAP_A       I11
  C7B4     1      A  CAP         I24
  C7C9     1      A  CAP_A        I7
  EU7A3    1    VOS  IR354XX_SM  I116
  FB1U4    2      B  FERRITE     I155
  L7A2     2    INB  INDUCTOR    I10
  R7A13    2      B  RES         I90
  U7C1   AA29  VCCPRIM_AVID<47>  LBG_CORE_QAT_EXT_D  I21
  U7C1   AA30  VCCPRIM_AVID<46>  LBG_CORE_QAT_EXT_D  I21
  U7C1   AA32  VCCPRIM_AVID<45>  LBG_CORE_QAT_EXT_D  I21
  U7C1   AA34  VCCPRIM_AVID<44>  LBG_CORE_QAT_EXT_D  I21
  U7C1   AA36  VCCPRIM_AVID<43>  LBG_CORE_QAT_EXT_D  I21
  U7C1   AA37  VCCPRIM_AVID<42>  LBG_CORE_QAT_EXT_D  I21
  U7C1   AA39  VCCPRIM_AVID<41>  LBG_CORE_QAT_EXT_D  I21
  U7C1   AA41  VCCPRIM_AVID<40>  LBG_CORE_QAT_EXT_D  I21
  U7C1   AC29  VCCPRIM_AVID<39>  LBG_CORE_QAT_EXT_D  I21
  U7C1   AC30  VCCPRIM_AVID<38>  LBG_CORE_QAT_EXT_D  I21
  U7C1   AC32  VCCPRIM_AVID<37>  LBG_CORE_QAT_EXT_D  I21
  U7C1   AC34  VCCPRIM_AVID<36>  LBG_CORE_QAT_EXT_D  I21
  U7C1   AC36  VCCPRIM_AVID<35>  LBG_CORE_QAT_EXT_D  I21
  U7C1   AC37  VCCPRIM_AVID<34>  LBG_CORE_QAT_EXT_D  I21
  U7C1   AC39  VCCPRIM_AVID<33>  LBG_CORE_QAT_EXT_D  I21
  U7C1   AC41  VCCPRIM_AVID<32>  LBG_CORE_QAT_EXT_D  I21
  U7C1   AE30  VCCPRIM_AVID<30>  LBG_CORE_QAT_EXT_D  I21
  U7C1   AE32  VCCPRIM_AVID<29>  LBG_CORE_QAT_EXT_D  I21
  U7C1   AE34  VCCPRIM_AVID<28>  LBG_CORE_QAT_EXT_D  I21
  U7C1   AE36  VCCPRIM_AVID<27>  LBG_CORE_QAT_EXT_D  I21
  U7C1   AE37  VCCPRIM_AVID<26>  LBG_CORE_QAT_EXT_D  I21
  U7C1   AE39  VCCPRIM_AVID<25>  LBG_CORE_QAT_EXT_D  I21
  U7C1   AE41  VCCPRIM_AVID<24>  LBG_CORE_QAT_EXT_D  I21
  U7C1   AG32  VCCPRIM_AVID<23>  LBG_CORE_QAT_EXT_D  I21
  U7C1   AG34  VCCPRIM_AVID<22>  LBG_CORE_QAT_EXT_D  I21
  U7C1   AG36  VCCPRIM_AVID<21>  LBG_CORE_QAT_EXT_D  I21
  U7C1   AG37  VCCPRIM_AVID<20>  LBG_CORE_QAT_EXT_D  I21
  U7C1   AG39  VCCPRIM_AVID<19>  LBG_CORE_QAT_EXT_D  I21
  U7C1   AK32  VCCPRIM_AVID<62>  LBG_CORE_QAT_EXT_D  I21
  U7C1   AK34  VCCPRIM_AVID<18>  LBG_CORE_QAT_EXT_D  I21
  U7C1   AK37  VCCPRIM_AVID<17>  LBG_CORE_QAT_EXT_D  I21
  U7C1   AK39  VCCPRIM_AVID<16>  LBG_CORE_QAT_EXT_D  I21
  U7C1   AM32  VCCPRIM_AVID<15>  LBG_CORE_QAT_EXT_D  I21
  U7C1   AM34  VCCPRIM_AVID<14>  LBG_CORE_QAT_EXT_D  I21
  U7C1   AM36  VCCPRIM_AVID<13>  LBG_CORE_QAT_EXT_D  I21
  U7C1   AM37  VCCPRIM_AVID<12>  LBG_CORE_QAT_EXT_D  I21
  U7C1   AM39  VCCPRIM_AVID<11>  LBG_CORE_QAT_EXT_D  I21
  U7C1   AP32  VCCPRIM_AVID<10>  LBG_CORE_QAT_EXT_D  I21
  U7C1   AP34  VCCPRIM_AVID<9>  LBG_CORE_QAT_EXT_D  I21
  U7C1   AP36  VCCPRIM_AVID<8>  LBG_CORE_QAT_EXT_D  I21
  U7C1   AP37  VCCPRIM_AVID<7>  LBG_CORE_QAT_EXT_D  I21
  U7C1   AP39  VCCPRIM_AVID<6>  LBG_CORE_QAT_EXT_D  I21
  U7C1   AT32  VCCPRIM_AVID<5>  LBG_CORE_QAT_EXT_D  I21
  U7C1   AT34  VCCPRIM_AVID<4>  LBG_CORE_QAT_EXT_D  I21
  U7C1   AT36  VCCPRIM_AVID<3>  LBG_CORE_QAT_EXT_D  I21
  U7C1   AU32  VCCPRIM_AVID<2>  LBG_CORE_QAT_EXT_D  I21
  U7C1   AU34  VCCPRIM_AVID<1>  LBG_CORE_QAT_EXT_D  I21
  U7C1   AU36  VCCPRIM_AVID<0>  LBG_CORE_QAT_EXT_D  I21
  U7C1   U27  VCCPRIM_AVID<31>  LBG_CORE_QAT_EXT_D  I21
  U7C1   U31  VCCPRIM_AVID<61>  LBG_CORE_QAT_EXT_D  I21
  U7C1   U35  VCCPRIM_AVID<60>  LBG_CORE_QAT_EXT_D  I21
  U7C1   U38  VCCPRIM_AVID<59>  LBG_CORE_QAT_EXT_D  I21
  U7C1   V29  VCCPRIM_AVID<58>  LBG_CORE_QAT_EXT_D  I21
  U7C1   V33  VCCPRIM_AVID<57>  LBG_CORE_QAT_EXT_D  I21
  U7C1   V40  VCCPRIM_AVID<56>  LBG_CORE_QAT_EXT_D  I21
  U7C1   Y29  VCCPRIM_AVID<55>  LBG_CORE_QAT_EXT_D  I21
  U7C1   Y30  VCCPRIM_AVID<54>  LBG_CORE_QAT_EXT_D  I21
  U7C1   Y32  VCCPRIM_AVID<53>  LBG_CORE_QAT_EXT_D  I21
  U7C1   Y34  VCCPRIM_AVID<52>  LBG_CORE_QAT_EXT_D  I21
  U7C1   Y36  VCCPRIM_AVID<51>  LBG_CORE_QAT_EXT_D  I21
  U7C1   Y37  VCCPRIM_AVID<50>  LBG_CORE_QAT_EXT_D  I21
  U7C1   Y39  VCCPRIM_AVID<49>  LBG_CORE_QAT_EXT_D  I21
  U7C1   Y41  VCCPRIM_AVID<48>  LBG_CORE_QAT_EXT_D  I21

PVPP_ABC        @BASEBOARD_FAB2_LIB.BASEBOARD_FAB2(SCH_1):PVPP_ABC
  C3T7     1      A  CAP         I184
  C3T9     1      A  CAP         I186
  C4T3     1      A  CAPP        I217
  C4T5     1      A  CAP         I125
  C4T6     1      A  CAP         I124
  C4U1     1      A  CAP         I130
  C4U2     1      A  CAP         I129
  C4U3     1      A  CAP         I148
  C4U4     1      A  CAP         I146
  C6F3     1      A  CAP_A        I7
  C6F4     1      A  CAPP        I180
  C6F5     1      A  CAP         I149
  C6F6     1      A  CAP         I122
  C6G1     1      A  CAP         I126
  C6G2     1      A  CAP         I128
  C6G4     1      A  CAP         I131
  C6G5     1      A  CAP         I145
  J4G1   142  VPP<4>  SCONN288_H44441004_PIP  I260
  J4G1   143  VPP<3>  SCONN288_H44441004_PIP  I260
  J4G1   284  VDDSPD  SCONN288_H44441004_PIP   I1
  J4G1   286  VPP<1>  SCONN288_H44441004_PIP  I260
  J4G1   287  VPP<0>  SCONN288_H44441004_PIP  I260
  J4G1   288  VPP<2>  SCONN288_H44441004_PIP  I260
  J4G2   140  SA<1>  SCONN288_H44441004_PIP  I111
  J4G2   142  VPP<4>  SCONN288_H44441004_PIP  I169
  J4G2   143  VPP<3>  SCONN288_H44441004_PIP  I169
  J4G2   284  VDDSPD  SCONN288_H44441004_PIP  I111
  J4G2   286  VPP<1>  SCONN288_H44441004_PIP  I169
  J4G2   287  VPP<0>  SCONN288_H44441004_PIP  I169
  J4G2   288  VPP<2>  SCONN288_H44441004_PIP  I169
  J4G3   142  VPP<4>  SCONN288_H44441004_PIP  I179
  J4G3   143  VPP<3>  SCONN288_H44441004_PIP  I179
  J4G3   238  SA<2>  SCONN288_H44441004_PIP  I111
  J4G3   284  VDDSPD  SCONN288_H44441004_PIP  I111
  J4G3   286  VPP<1>  SCONN288_H44441004_PIP  I179
  J4G3   287  VPP<0>  SCONN288_H44441004_PIP  I179
  J4G3   288  VPP<2>  SCONN288_H44441004_PIP  I179
  J6T1   139  SA<0>  SCONN288_H44441003_PIP  I13
  J6T1   142  VPP<4>  SCONN288_H44441003_PIP  I75
  J6T1   143  VPP<3>  SCONN288_H44441003_PIP  I75
  J6T1   284  VDDSPD  SCONN288_H44441003_PIP  I13
  J6T1   286  VPP<1>  SCONN288_H44441003_PIP  I75
  J6T1   287  VPP<0>  SCONN288_H44441003_PIP  I75
  J6T1   288  VPP<2>  SCONN288_H44441003_PIP  I75
  J6U1   139  SA<0>  SCONN288_H44441003_PIP  I14
  J6U1   140  SA<1>  SCONN288_H44441003_PIP  I14
  J6U1   142  VPP<4>  SCONN288_H44441003_PIP  I67
  J6U1   143  VPP<3>  SCONN288_H44441003_PIP  I67
  J6U1   284  VDDSPD  SCONN288_H44441003_PIP  I14
  J6U1   286  VPP<1>  SCONN288_H44441003_PIP  I67
  J6U1   287  VPP<0>  SCONN288_H44441003_PIP  I67
  J6U1   288  VPP<2>  SCONN288_H44441003_PIP  I67
  J6U2   139  SA<0>  SCONN288_H44441003_PIP  I111
  J6U2   142  VPP<4>  SCONN288_H44441003_PIP  I171
  J6U2   143  VPP<3>  SCONN288_H44441003_PIP  I171
  J6U2   238  SA<2>  SCONN288_H44441003_PIP  I111
  J6U2   284  VDDSPD  SCONN288_H44441003_PIP  I111
  J6U2   286  VPP<1>  SCONN288_H44441003_PIP  I171
  J6U2   287  VPP<0>  SCONN288_H44441003_PIP  I171
  J6U2   288  VPP<2>  SCONN288_H44441003_PIP  I171
  J8B1    21   IO21  SCONN24_H46321001_SM   I1
  L7F1     2    INB  INDUCTOR    I178
  R3R16    1      A  RES         I48
  R4T7     1      A  RES         I13
  R4T8     1      A  RES         I11
  R4U2     1      A  RES         I100
  R4U3     1      A  RES         I94
  R6F3     1      A  RES          I7
  R7F10    1      A  RES         I177
  R7F12    1      A  RES         I168
  R8B3     1      A  RES         I24
  R8B5     1      A  RES         I22
  R8B6     1      A  RES         I37
  R8B7     1      A  RES         I36
  R8B8     1      A  RES         I14
  R8B10    1      A  RES         I16
  R8B11    1      A  RES         I35
  R8B13    1      A  RES         I34
  R8B16    1      A  RES         I17
  R8B17    1      A  RES         I18
  R8B18    1      A  RES         I20
  R8B19    1      A  RES         I21
  U5D1    A8  CD_VPP<3>  SKX_EXT_B_BGA1  I34
  U5D1   A10  CD_VPP<2>  SKX_EXT_B_BGA1  I34
  U5D1   A12  CD_VPP<1>  SKX_EXT_B_BGA1  I34
  U5D1   B11  CD_VPP<0>  SKX_EXT_B_BGA1  I34
  U6F1     8   VCCB  PCA9617_SSOP  I15

PVPP_DEF        @BASEBOARD_FAB2_LIB.BASEBOARD_FAB2(SCH_1):PVPP_DEF
  C4L1     1      A  CAP         I129
  C4L2     1      A  CAP         I102
  C4L3     1      A  CAP         I106
  C4L4     1      A  CAP         I108
  C4M1     1      A  CAPP        I267
  C4M3     1      A  CAP         I111
  C4M4     1      A  CAP         I125
  C6A2     1      A  CAP         I105
  C6A3     1      A  CAP         I104
  C6A6     1      A  CAP         I110
  C6A7     1      A  CAP         I109
  C6B1     1      A  CAP         I128
  C6B2     1      A  CAP         I126
  C6B3     1      A  CAP         I236
  C6B7     1      A  CAPP        I229
  C7B7     1      A  CAP         I238
  C7E2     1      A  CAP_A       I32
  J4A1   142  VPP<4>  SCONN288_H44441004_PIP  I171
  J4A1   143  VPP<3>  SCONN288_H44441004_PIP  I171
  J4A1   238  SA<2>  SCONN288_H44441004_PIP  I111
  J4A1   284  VDDSPD  SCONN288_H44441004_PIP  I111
  J4A1   286  VPP<1>  SCONN288_H44441004_PIP  I171
  J4A1   287  VPP<0>  SCONN288_H44441004_PIP  I171
  J4A1   288  VPP<2>  SCONN288_H44441004_PIP  I171
  J4A2   140  SA<1>  SCONN288_H44441004_PIP  I111
  J4A2   142  VPP<4>  SCONN288_H44441004_PIP  I167
  J4A2   143  VPP<3>  SCONN288_H44441004_PIP  I167
  J4A2   284  VDDSPD  SCONN288_H44441004_PIP  I111
  J4A2   286  VPP<1>  SCONN288_H44441004_PIP  I167
  J4A2   287  VPP<0>  SCONN288_H44441004_PIP  I167
  J4A2   288  VPP<2>  SCONN288_H44441004_PIP  I167
  J4B1   142  VPP<4>  SCONN288_H44441004_PIP  I169
  J4B1   143  VPP<3>  SCONN288_H44441004_PIP  I169
  J4B1   284  VDDSPD  SCONN288_H44441004_PIP  I111
  J4B1   286  VPP<1>  SCONN288_H44441004_PIP  I169
  J4B1   287  VPP<0>  SCONN288_H44441004_PIP  I169
  J4B1   288  VPP<2>  SCONN288_H44441004_PIP  I169
  J6L1   139  SA<0>  SCONN288_H44441003_PIP  I111
  J6L1   142  VPP<4>  SCONN288_H44441003_PIP  I170
  J6L1   143  VPP<3>  SCONN288_H44441003_PIP  I170
  J6L1   238  SA<2>  SCONN288_H44441003_PIP  I111
  J6L1   284  VDDSPD  SCONN288_H44441003_PIP  I111
  J6L1   286  VPP<1>  SCONN288_H44441003_PIP  I170
  J6L1   287  VPP<0>  SCONN288_H44441003_PIP  I170
  J6L1   288  VPP<2>  SCONN288_H44441003_PIP  I170
  J6L2   139  SA<0>  SCONN288_H44441003_PIP  I12
  J6L2   140  SA<1>  SCONN288_H44441003_PIP  I12
  J6L2   142  VPP<4>  SCONN288_H44441003_PIP  I55
  J6L2   143  VPP<3>  SCONN288_H44441003_PIP  I55
  J6L2   284  VDDSPD  SCONN288_H44441003_PIP  I12
  J6L2   286  VPP<1>  SCONN288_H44441003_PIP  I55
  J6L2   287  VPP<0>  SCONN288_H44441003_PIP  I55
  J6L2   288  VPP<2>  SCONN288_H44441003_PIP  I55
  J6M1   139  SA<0>  SCONN288_H44441003_PIP  I158
  J6M1   142  VPP<4>  SCONN288_H44441003_PIP  I50
  J6M1   143  VPP<3>  SCONN288_H44441003_PIP  I50
  J6M1   284  VDDSPD  SCONN288_H44441003_PIP  I158
  J6M1   286  VPP<1>  SCONN288_H44441003_PIP  I50
  J6M1   287  VPP<0>  SCONN288_H44441003_PIP  I50
  J6M1   288  VPP<2>  SCONN288_H44441003_PIP  I50
  L7B1     2    INB  INDUCTOR    I239
  R3R5     1      A  RES         I103
  R3R12    1      A  RES         I101
  R7B10    1      A  RES         I227
  R7B11    1      A  RES         I299
  U7E1     8   VCCB  PCA9617_SSOP  I61

PVPP_GHJ        @BASEBOARD_FAB2_LIB.BASEBOARD_FAB2(SCH_1):PVPP_GHJ
  C3F3     1      A  CAP         I116
  C3F4     1      A  CAP         I117
  C3G3     1      A  CAP         I118
  C3G4     1      A  CAP         I133
  C3G7     1      A  CAP         I132
  C3G8     1      A  CAP         I135
  C4F7     1      A  CAPP        I217
  C4F11    1      A  CAPP        I256
  C4G25    1      A  CAP_A       I41
  C6U2     1      A  CAP         I223
  C6U3     1      A  CAP         I221
  C7T2     1      A  CAP         I112
  C7T3     1      A  CAP         I113
  C7U3     1      A  CAP         I136
  C7U4     1      A  CAP         I109
  C7U5     1      A  CAP         I111
  C7U6     1      A  CAP         I115
  J1G1   142  VPP<4>  SCONN288_H44441004_PIP  I171
  J1G1   143  VPP<3>  SCONN288_H44441004_PIP  I171
  J1G1   284  VDDSPD  SCONN288_H44441004_PIP  I111
  J1G1   286  VPP<1>  SCONN288_H44441004_PIP  I171
  J1G1   287  VPP<0>  SCONN288_H44441004_PIP  I171
  J1G1   288  VPP<2>  SCONN288_H44441004_PIP  I171
  J1G2   140  SA<1>  SCONN288_H44441004_PIP  I111
  J1G2   142  VPP<4>  SCONN288_H44441004_PIP  I169
  J1G2   143  VPP<3>  SCONN288_H44441004_PIP  I169
  J1G2   284  VDDSPD  SCONN288_H44441004_PIP  I111
  J1G2   286  VPP<1>  SCONN288_H44441004_PIP  I169
  J1G2   287  VPP<0>  SCONN288_H44441004_PIP  I169
  J1G2   288  VPP<2>  SCONN288_H44441004_PIP  I169
  J1G3   142  VPP<4>  SCONN288_H44441004_PIP  I169
  J1G3   143  VPP<3>  SCONN288_H44441004_PIP  I169
  J1G3   238  SA<2>  SCONN288_H44441004_PIP  I186
  J1G3   284  VDDSPD  SCONN288_H44441004_PIP  I186
  J1G3   286  VPP<1>  SCONN288_H44441004_PIP  I169
  J1G3   287  VPP<0>  SCONN288_H44441004_PIP  I169
  J1G3   288  VPP<2>  SCONN288_H44441004_PIP  I169
  J9T1   139  SA<0>  SCONN288_H44441003_PIP  I13
  J9T1   142  VPP<4>  SCONN288_H44441003_PIP  I75
  J9T1   143  VPP<3>  SCONN288_H44441003_PIP  I75
  J9T1   284  VDDSPD  SCONN288_H44441003_PIP  I13
  J9T1   286  VPP<1>  SCONN288_H44441003_PIP  I75
  J9T1   287  VPP<0>  SCONN288_H44441003_PIP  I75
  J9T1   288  VPP<2>  SCONN288_H44441003_PIP  I75
  J9U1   139  SA<0>  SCONN288_H44441003_PIP  I24
  J9U1   140  SA<1>  SCONN288_H44441003_PIP  I24
  J9U1   142  VPP<4>  SCONN288_H44441003_PIP  I56
  J9U1   143  VPP<3>  SCONN288_H44441003_PIP  I56
  J9U1   284  VDDSPD  SCONN288_H44441003_PIP  I24
  J9U1   286  VPP<1>  SCONN288_H44441003_PIP  I56
  J9U1   287  VPP<0>  SCONN288_H44441003_PIP  I56
  J9U1   288  VPP<2>  SCONN288_H44441003_PIP  I56
  J9U2   139  SA<0>  SCONN288_H44441003_PIP  I187
  J9U2   142  VPP<4>  SCONN288_H44441003_PIP  I171
  J9U2   143  VPP<3>  SCONN288_H44441003_PIP  I171
  J9U2   238  SA<2>  SCONN288_H44441003_PIP  I187
  J9U2   284  VDDSPD  SCONN288_H44441003_PIP  I187
  J9U2   286  VPP<1>  SCONN288_H44441003_PIP  I171
  J9U2   287  VPP<0>  SCONN288_H44441003_PIP  I171
  J9U2   288  VPP<2>  SCONN288_H44441003_PIP  I171
  L4G1     2    INB  INDUCTOR    I277
  R4G6     1      A  RES         I211
  R4G8     1      A  RES         I271
  R6U17    1      A  RES         I106
  R6U18    1      A  RES         I104
  U2D1    A8  CD_VPP<3>  SKX_EXT_B_BGA1  I33
  U2D1   A10  CD_VPP<2>  SKX_EXT_B_BGA1  I33
  U2D1   A12  CD_VPP<1>  SKX_EXT_B_BGA1  I33
  U2D1   B11  CD_VPP<0>  SKX_EXT_B_BGA1  I33
  U4G1     8   VCCB  PCA9617_SSOP  I63

PVPP_KLM        @BASEBOARD_FAB2_LIB.BASEBOARD_FAB2(SCH_1):PVPP_KLM
  C3A3     1      A  CAP         I97
  C3A4     1      A  CAP         I93
  C3A7     1      A  CAP         I95
  C3A8     1      A  CAP         I86
  C3B1     1      A  CAP         I94
  C3B2     1      A  CAP         I84
  C3B3     1      A  CAPP        I167
  C3B5     1      A  CAP_A       I53
  C4B2     1      A  CAP         I180
  C4B3     1      A  CAP         I177
  C6L8     1      A  CAPP        I210
  C7L2     1      A  CAP         I88
  C7L3     1      A  CAP         I87
  C7L6     1      A  CAP         I90
  C7L7     1      A  CAP         I89
  C7M3     1      A  CAP         I92
  C7M4     1      A  CAP         I91
  J1A1   142  VPP<4>  SCONN288_H44441004_PIP  I169
  J1A1   143  VPP<3>  SCONN288_H44441004_PIP  I169
  J1A1   238  SA<2>  SCONN288_H44441004_PIP  I186
  J1A1   284  VDDSPD  SCONN288_H44441004_PIP  I186
  J1A1   286  VPP<1>  SCONN288_H44441004_PIP  I169
  J1A1   287  VPP<0>  SCONN288_H44441004_PIP  I169
  J1A1   288  VPP<2>  SCONN288_H44441004_PIP  I169
  J1A2   140  SA<1>  SCONN288_H44441004_PIP  I111
  J1A2   142  VPP<4>  SCONN288_H44441004_PIP  I172
  J1A2   143  VPP<3>  SCONN288_H44441004_PIP  I172
  J1A2   284  VDDSPD  SCONN288_H44441004_PIP  I111
  J1A2   286  VPP<1>  SCONN288_H44441004_PIP  I172
  J1A2   287  VPP<0>  SCONN288_H44441004_PIP  I172
  J1A2   288  VPP<2>  SCONN288_H44441004_PIP  I172
  J1B1   142  VPP<4>  SCONN288_H44441004_PIP  I167
  J1B1   143  VPP<3>  SCONN288_H44441004_PIP  I167
  J1B1   284  VDDSPD  SCONN288_H44441004_PIP  I111
  J1B1   286  VPP<1>  SCONN288_H44441004_PIP  I167
  J1B1   287  VPP<0>  SCONN288_H44441004_PIP  I167
  J1B1   288  VPP<2>  SCONN288_H44441004_PIP  I167
  J9L1   139  SA<0>  SCONN288_H44441003_PIP  I111
  J9L1   142  VPP<4>  SCONN288_H44441003_PIP  I168
  J9L1   143  VPP<3>  SCONN288_H44441003_PIP  I168
  J9L1   238  SA<2>  SCONN288_H44441003_PIP  I111
  J9L1   284  VDDSPD  SCONN288_H44441003_PIP  I111
  J9L1   286  VPP<1>  SCONN288_H44441003_PIP  I168
  J9L1   287  VPP<0>  SCONN288_H44441003_PIP  I168
  J9L1   288  VPP<2>  SCONN288_H44441003_PIP  I168
  J9L2   139  SA<0>  SCONN288_H44441003_PIP  I12
  J9L2   140  SA<1>  SCONN288_H44441003_PIP  I12
  J9L2   142  VPP<4>  SCONN288_H44441003_PIP  I55
  J9L2   143  VPP<3>  SCONN288_H44441003_PIP  I55
  J9L2   284  VDDSPD  SCONN288_H44441003_PIP  I12
  J9L2   286  VPP<1>  SCONN288_H44441003_PIP  I55
  J9L2   287  VPP<0>  SCONN288_H44441003_PIP  I55
  J9L2   288  VPP<2>  SCONN288_H44441003_PIP  I55
  J9M1   139  SA<0>  SCONN288_H44441003_PIP  I14
  J9M1   142  VPP<4>  SCONN288_H44441003_PIP  I57
  J9M1   143  VPP<3>  SCONN288_H44441003_PIP  I57
  J9M1   284  VDDSPD  SCONN288_H44441003_PIP  I14
  J9M1   286  VPP<1>  SCONN288_H44441003_PIP  I57
  J9M1   287  VPP<0>  SCONN288_H44441003_PIP  I57
  J9M1   288  VPP<2>  SCONN288_H44441003_PIP  I57
  L4A1     2    INB  INDUCTOR    I164
  R4B2     1      A  RES         I183
  R4B3     1      A  RES         I214
  R6M9     1      A  RES         I49
  R7M1     1      A  RES         I109
  R7M6     1      A  RES         I107
  U3B1     8   VCCB  PCA9617_SSOP  I75

PVSA_CPU0       @BASEBOARD_FAB2_LIB.BASEBOARD_FAB2(SCH_1):PVSA_CPU0
  C4C11    1      A  CAP_A       I43
  C5D10    1      A  CAP         I108
  C5D11    1      A  CAP         I93
  C5D12    1      A  CAP         I94
  C5D13    1      A  CAP         I91
  C5P7     1      A  CAP         I25
  C5P8     1      A  CAP         I19
  C5P9     1      A  CAP         I18
  C6N1     1      A  CAPP        I12
  C6N4     1      A  CAPP        I14
  C6N7     1      A  CAP_A        I5
  EU4C1    1    VOS  IR354XX_SM  I46
  L4C2     2    INB  INDUCTOR     I7
  R4C5     2      B  RES         I24
  R6N4     1      A  RES         I45
  U5D1   CB65  VCCSA<25>  SKX_EXT_B_BGA1  I34
  U5D1   CB67  VCCSA<24>  SKX_EXT_B_BGA1  I34
  U5D1   CB69  VCCSA<23>  SKX_EXT_B_BGA1  I34
  U5D1   CC66  VCCSA<22>  SKX_EXT_B_BGA1  I34
  U5D1   CC68  VCCSA<21>  SKX_EXT_B_BGA1  I34
  U5D1   CC70  VCCSA<20>  SKX_EXT_B_BGA1  I34
  U5D1   CD65  VCCSA<19>  SKX_EXT_B_BGA1  I34
  U5D1   CD67  VCCSA<18>  SKX_EXT_B_BGA1  I34
  U5D1   CD69  VCCSA<17>  SKX_EXT_B_BGA1  I34
  U5D1   CD71  VCCSA<16>  SKX_EXT_B_BGA1  I34
  U5D1   CE64  VCCSA<15>  SKX_EXT_B_BGA1  I34
  U5D1   CE66  VCCSA<14>  SKX_EXT_B_BGA1  I34
  U5D1   CE68  VCCSA<13>  SKX_EXT_B_BGA1  I34
  U5D1   CE72  VCCSA<12>  SKX_EXT_B_BGA1  I34
  U5D1   CE74  VCCSA<11>  SKX_EXT_B_BGA1  I34
  U5D1   CF65  VCCSA<10>  SKX_EXT_B_BGA1  I34
  U5D1   CF67  VCCSA<9>  SKX_EXT_B_BGA1  I34
  U5D1   CF73  VCCSA<8>  SKX_EXT_B_BGA1  I34
  U5D1   CF75  VCCSA<7>  SKX_EXT_B_BGA1  I34
  U5D1   CG64  VCCSA<6>  SKX_EXT_B_BGA1  I34
  U5D1   CG66  VCCSA<5>  SKX_EXT_B_BGA1  I34
  U5D1   CG74  VCCSA<4>  SKX_EXT_B_BGA1  I34
  U5D1   CH65  VCCSA<3>  SKX_EXT_B_BGA1  I34
  U5D1   CH75  VCCSA<2>  SKX_EXT_B_BGA1  I34
  U5D1   CJ64  VCCSA<1>  SKX_EXT_B_BGA1  I34
  U5D1   CJ66  VCCSA<0>  SKX_EXT_B_BGA1  I34

PVSA_CPU1       @BASEBOARD_FAB2_LIB.BASEBOARD_FAB2(SCH_1):PVSA_CPU1
  C1C19    1      A  CAP_A        I8
  C2D8     1      A  CAP         I33
  C2D9     1      A  CAP         I43
  C2D10    1      A  CAP         I37
  C2D11    1      A  CAP         I42
  C8P5     1      A  CAP         I58
  C8P6     1      A  CAP         I55
  C8P7     1      A  CAP         I50
  C9N11    1      A  CAPP        I12
  C9N20    1      A  CAPP        I14
  C9N22    1      A  CAP_A       I44
  EU1C1    1    VOS  IR354XX_SM  I51
  L1C1     2    INB  INDUCTOR    I10
  R1C12    2      B  RES         I29
  R9N4     1      A  RES         I45
  U2D1   CB65  VCCSA<25>  SKX_EXT_B_BGA1  I33
  U2D1   CB67  VCCSA<24>  SKX_EXT_B_BGA1  I33
  U2D1   CB69  VCCSA<23>  SKX_EXT_B_BGA1  I33
  U2D1   CC66  VCCSA<22>  SKX_EXT_B_BGA1  I33
  U2D1   CC68  VCCSA<21>  SKX_EXT_B_BGA1  I33
  U2D1   CC70  VCCSA<20>  SKX_EXT_B_BGA1  I33
  U2D1   CD65  VCCSA<19>  SKX_EXT_B_BGA1  I33
  U2D1   CD67  VCCSA<18>  SKX_EXT_B_BGA1  I33
  U2D1   CD69  VCCSA<17>  SKX_EXT_B_BGA1  I33
  U2D1   CD71  VCCSA<16>  SKX_EXT_B_BGA1  I33
  U2D1   CE64  VCCSA<15>  SKX_EXT_B_BGA1  I33
  U2D1   CE66  VCCSA<14>  SKX_EXT_B_BGA1  I33
  U2D1   CE68  VCCSA<13>  SKX_EXT_B_BGA1  I33
  U2D1   CE72  VCCSA<12>  SKX_EXT_B_BGA1  I33
  U2D1   CE74  VCCSA<11>  SKX_EXT_B_BGA1  I33
  U2D1   CF65  VCCSA<10>  SKX_EXT_B_BGA1  I33
  U2D1   CF67  VCCSA<9>  SKX_EXT_B_BGA1  I33
  U2D1   CF73  VCCSA<8>  SKX_EXT_B_BGA1  I33
  U2D1   CF75  VCCSA<7>  SKX_EXT_B_BGA1  I33
  U2D1   CG64  VCCSA<6>  SKX_EXT_B_BGA1  I33
  U2D1   CG66  VCCSA<5>  SKX_EXT_B_BGA1  I33
  U2D1   CG74  VCCSA<4>  SKX_EXT_B_BGA1  I33
  U2D1   CH65  VCCSA<3>  SKX_EXT_B_BGA1  I33
  U2D1   CH75  VCCSA<2>  SKX_EXT_B_BGA1  I33
  U2D1   CJ64  VCCSA<1>  SKX_EXT_B_BGA1  I33
  U2D1   CJ66  VCCSA<0>  SKX_EXT_B_BGA1  I33

PVTT_ABC        @BASEBOARD_FAB2_LIB.BASEBOARD_FAB2(SCH_1):PVTT_ABC
  C4G24    1      A  CAP         I20
  C5T3     1      A  CAP_A       I51
  C5U12    1      A  CAP_A       I50
  C5U16    1      A  CAP_A       I52
  EU4G3    9    VTT  MIC5166_DFN   I1
  J4G1    77  VTT<1>  SCONN288_H44441004_PIP  I260
  J4G1   221  VTT<0>  SCONN288_H44441004_PIP  I260
  J4G2    77  VTT<1>  SCONN288_H44441004_PIP  I169
  J4G2   221  VTT<0>  SCONN288_H44441004_PIP  I169
  J4G3    77  VTT<1>  SCONN288_H44441004_PIP  I179
  J4G3   221  VTT<0>  SCONN288_H44441004_PIP  I179
  J6T1    77  VTT<1>  SCONN288_H44441003_PIP  I75
  J6T1   221  VTT<0>  SCONN288_H44441003_PIP  I75
  J6U1    77  VTT<1>  SCONN288_H44441003_PIP  I67
  J6U1   221  VTT<0>  SCONN288_H44441003_PIP  I67
  J6U2    77  VTT<1>  SCONN288_H44441003_PIP  I171
  J6U2   221  VTT<0>  SCONN288_H44441003_PIP  I171
  R6U16    2      B  RES         I55
  SH5U1    2      B  SHUNT       I56

PVTT_DEF        @BASEBOARD_FAB2_LIB.BASEBOARD_FAB2(SCH_1):PVTT_DEF
  C4A1     1      A  CAP         I16
  C5L4     1      A  CAP_A       I47
  C5L5     1      A  CAP_A       I49
  C5M13    1      A  CAP_A       I48
  EU4A1    9    VTT  MIC5166_DFN  I31
  J4A1    77  VTT<1>  SCONN288_H44441004_PIP  I171
  J4A1   221  VTT<0>  SCONN288_H44441004_PIP  I171
  J4A2    77  VTT<1>  SCONN288_H44441004_PIP  I167
  J4A2   221  VTT<0>  SCONN288_H44441004_PIP  I167
  J4B1    77  VTT<1>  SCONN288_H44441004_PIP  I169
  J4B1   221  VTT<0>  SCONN288_H44441004_PIP  I169
  J6L1    77  VTT<1>  SCONN288_H44441003_PIP  I170
  J6L1   221  VTT<0>  SCONN288_H44441003_PIP  I170
  J6L2    77  VTT<1>  SCONN288_H44441003_PIP  I55
  J6L2   221  VTT<0>  SCONN288_H44441003_PIP  I55
  J6M1    77  VTT<1>  SCONN288_H44441003_PIP  I50
  J6M1   221  VTT<0>  SCONN288_H44441003_PIP  I50
  R4A1     2      B  RES         I52
  SH5L1    2      B  SHUNT       I53

PVTT_GHJ        @BASEBOARD_FAB2_LIB.BASEBOARD_FAB2(SCH_1):PVTT_GHJ
  C2F2     1      A  CAP_A       I47
  C4G20    1      A  CAP         I17
  C8T3     1      A  CAP_A       I48
  C8U10    1      A  CAP_A       I49
  EU4G2    9    VTT  MIC5166_DFN  I24
  J1G1    77  VTT<1>  SCONN288_H44441004_PIP  I171
  J1G1   221  VTT<0>  SCONN288_H44441004_PIP  I171
  J1G2    77  VTT<1>  SCONN288_H44441004_PIP  I169
  J1G2   221  VTT<0>  SCONN288_H44441004_PIP  I169
  J1G3    77  VTT<1>  SCONN288_H44441004_PIP  I169
  J1G3   221  VTT<0>  SCONN288_H44441004_PIP  I169
  J9T1    77  VTT<1>  SCONN288_H44441003_PIP  I75
  J9T1   221  VTT<0>  SCONN288_H44441003_PIP  I75
  J9U1    77  VTT<1>  SCONN288_H44441003_PIP  I56
  J9U1   221  VTT<0>  SCONN288_H44441003_PIP  I56
  J9U2    77  VTT<1>  SCONN288_H44441003_PIP  I171
  J9U2   221  VTT<0>  SCONN288_H44441003_PIP  I171
  R6U8     2      B  RES         I52
  SH8U1    2      B  SHUNT       I53

PVTT_KLM        @BASEBOARD_FAB2_LIB.BASEBOARD_FAB2(SCH_1):PVTT_KLM
  C4A13    1      A  CAP         I18
  C8L3     1      A  CAP_A       I48
  C8L4     1      A  CAP_A       I49
  C8M12    1      A  CAP_A       I47
  EU4A2    9    VTT  MIC5166_DFN  I31
  J1A1    77  VTT<1>  SCONN288_H44441004_PIP  I169
  J1A1   221  VTT<0>  SCONN288_H44441004_PIP  I169
  J1A2    77  VTT<1>  SCONN288_H44441004_PIP  I172
  J1A2   221  VTT<0>  SCONN288_H44441004_PIP  I172
  J1B1    77  VTT<1>  SCONN288_H44441004_PIP  I167
  J1B1   221  VTT<0>  SCONN288_H44441004_PIP  I167
  J9L1    77  VTT<1>  SCONN288_H44441003_PIP  I168
  J9L1   221  VTT<0>  SCONN288_H44441003_PIP  I168
  J9L2    77  VTT<1>  SCONN288_H44441003_PIP  I55
  J9L2   221  VTT<0>  SCONN288_H44441003_PIP  I55
  J9M1    77  VTT<1>  SCONN288_H44441003_PIP  I57
  J9M1   221  VTT<0>  SCONN288_H44441003_PIP  I57
  R6L7     2      B  RES         I52
  SH8L1    2      B  SHUNT       I53

PWRGD_CPU0_DRAMPWROK_ABC_G   @BASEBOARD_FAB2_LIB.BASEBOARD_FAB2(SCH_1):PWRGD_CPU0_DRAMPWROK_ABC_G
  R3P38    2      B  RES          I7
  U3P1     3     B1  GTL2014_SM  I42
  U5D1   AN30  DDR012_DRAM_PWR_OK  SKX_EXT_B_BGA1  I259

PWRGD_CPU0_DRAMPWROK_DEF_G   @BASEBOARD_FAB2_LIB.BASEBOARD_FAB2(SCH_1):PWRGD_CPU0_DRAMPWROK_DEF_G
  R3P29    2      B  RES          I5
  U3P1     2     B0  GTL2014_SM  I42
  U5D1   CR28  DDR345_DRAM_PWR_OK  SKX_EXT_B_BGA1  I259

PWRGD_CPU0_G    @BASEBOARD_FAB2_LIB.BASEBOARD_FAB2(SCH_1):PWRGD_CPU0_G
  R6D8     2      B  RES          I3
  R9B14    1      A  RES         I168
  U3P1     6     B3  GTL2014_SM  I42
  U5D1   BC24  PWRGOOD  SKX_EXT_B_BGA1  I259

PWRGD_CPU0_G_R   @BASEBOARD_FAB2_LIB.BASEBOARD_FAB2(SCH_1):PWRGD_CPU0_G_R
  J9B4     7    IO7  SCONN10_C12536004  I175
  R9B14    2      B  RES         I168

PWRGD_CPU0_LVC3   @BASEBOARD_FAB2_LIB.BASEBOARD_FAB2(SCH_1):PWRGD_CPU0_LVC3
  U3P1     9     A3  GTL2014_SM  I42
  U8D7    L5  PL11D  LCMXO2_A_256BGA  I179

PWRGD_CPU1_DRAMPWROK_GHJ_G   @BASEBOARD_FAB2_LIB.BASEBOARD_FAB2(SCH_1):PWRGD_CPU1_DRAMPWROK_GHJ_G
  R3D21    2      B  RES         I30
  U2D1   AN30  DDR012_DRAM_PWR_OK  SKX_EXT_B_BGA1  I172
  U4C2     3     B1  GTL2014_SM  I46

PWRGD_CPU1_DRAMPWROK_KLM_G   @BASEBOARD_FAB2_LIB.BASEBOARD_FAB2(SCH_1):PWRGD_CPU1_DRAMPWROK_KLM_G
  R7M9     2      B  RES         I28
  U2D1   CR28  DDR345_DRAM_PWR_OK  SKX_EXT_B_BGA1  I172
  U4C2     2     B0  GTL2014_SM  I46

PWRGD_CPU1_G    @BASEBOARD_FAB2_LIB.BASEBOARD_FAB2(SCH_1):PWRGD_CPU1_G
  R3D15    2      B  RES         I26
  U2D1   BC24  PWRGOOD  SKX_EXT_B_BGA1  I172
  U4C2     6     B3  GTL2014_SM  I46

PWRGD_CPU1_LVC3   @BASEBOARD_FAB2_LIB.BASEBOARD_FAB2(SCH_1):PWRGD_CPU1_LVC3
  U4C2     9     A3  GTL2014_SM  I46
  U8D7   M10  PB21C  LCMXO2_A_256BGA  I179

PWRGD_CPUPWRGD   @BASEBOARD_FAB2_LIB.BASEBOARD_FAB2(SCH_1):PWRGD_CPUPWRGD
  R3R3     2      B  RES         I61
  U8D7   F13   PR3C  LCMXO2_A_256BGA  I59

PWRGD_CPUPWRGD_GTL   @BASEBOARD_FAB2_LIB.BASEBOARD_FAB2(SCH_1):PWRGD_CPUPWRGD_GTL
  U3P2     2     B0  GTL2014_SM   I1
  U7C1    R9  PROC_PWRGD  LBG_CORE_QAT_EXT_D  I73

PWRGD_CPUPWRGD_R1   @BASEBOARD_FAB2_LIB.BASEBOARD_FAB2(SCH_1):PWRGD_CPUPWRGD_R1
  R3R3     1      A  RES         I61
  U3P2    13     A0  GTL2014_SM   I1

PWRGD_DRAMPWRGD   @BASEBOARD_FAB2_LIB.BASEBOARD_FAB2(SCH_1):PWRGD_DRAMPWRGD
  U3P1    12     A1  GTL2014_SM  I42
  U3P1    13     A0  GTL2014_SM  I42
  U4C2    12     A1  GTL2014_SM  I46
  U4C2    13     A0  GTL2014_SM  I46
  U8D7   T15  PB25C  LCMXO2_A_256BGA  I179

PWRGD_DSW_PWROK   @BASEBOARD_FAB2_LIB.BASEBOARD_FAB2(SCH_1):PWRGD_DSW_PWROK
  CR7E1    2      A  DIODE_SMLF  I103
  EU9F3   24  RESET_N  PI7C9X1172_QFN   I1
  R3P44    2      B  RES         I59
  U7C1   K13  DSW_PWROK  LBG_CORE_QAT_EXT_D  I73
  U7D3     4  ENOUT  ADM1085_SMT  I70
  U8D2     2      A  TTL1G07_A_SOP  I374
  U8D7   B11  PT22A  LCMXO2_A_256BGA  I59
  U9P2     6   OUTA  TPS3700_SM  I200

PWRGD_P12V_HSC   @BASEBOARD_FAB2_LIB.BASEBOARD_FAB2(SCH_1):PWRGD_P12V_HSC
  C8E3     1      A  CAP_A       I94
  CR8E1    1      C  DIODE_SMLF  I128
  R1D33    2      B  RES         I108
  U8E2     3    VCC  ADM809      I89

PWRGD_P12V_HSC_DLY   @BASEBOARD_FAB2_LIB.BASEBOARD_FAB2(SCH_1):PWRGD_P12V_HSC_DLY
  C8E13    1      A  CAP         I41
  CR8E1    2      A  DIODE_SMLF  I128
  R8E7     2      B  RES         I90
  R8E33    1      A  RES         I91
  U8E1    10   B<0>  TTL08_QFN15  I243

PWRGD_P12V_HSC_DLY_R   @BASEBOARD_FAB2_LIB.BASEBOARD_FAB2(SCH_1):PWRGD_P12V_HSC_DLY_R
  R8E7     1      A  RES         I90
  U8E2     2  RESET_N  ADM809      I89

PWRGD_P12V_MAIN   @BASEBOARD_FAB2_LIB.BASEBOARD_FAB2(SCH_1):PWRGD_P12V_MAIN
  R8D42    2      B  RES         I106
  U8D7    B5   PT9B  LCMXO2_A_256BGA  I59

PWRGD_P12V_MAIN_R   @BASEBOARD_FAB2_LIB.BASEBOARD_FAB2(SCH_1):PWRGD_P12V_MAIN_R
  R8D41    2      B  RES         I120
  R8D42    1      A  RES         I106
  U8D8     6   OUTA  TPS3700_SM  I104

PWRGD_P12V_R    @BASEBOARD_FAB2_LIB.BASEBOARD_FAB2(SCH_1):PWRGD_P12V_R
  EU1D2   18  PWRGD  ADM1278_SM  I10
  R1D31    1      A  RES         I43
  R1D33    1      A  RES         I108
  R9P18    2      B  RES         I41

PWRGD_P1V26_BMC_STBY   @BASEBOARD_FAB2_LIB.BASEBOARD_FAB2(SCH_1):PWRGD_P1V26_BMC_STBY
  R9F11    2      B  RES         I41
  U8D7    E7  PT12B  LCMXO2_A_256BGA  I59

PWRGD_P1V26_BMC_STBY_R   @BASEBOARD_FAB2_LIB.BASEBOARD_FAB2(SCH_1):PWRGD_P1V26_BMC_STBY_R
  C9F8     1      A  CAP         I19
  EU9F1    5  PGOOD  RT9059_DFN  I40
  R9F11    1      A  RES         I41
  R9F13    2      B  RES         I21

PWRGD_P1V538_BMC_STBY   @BASEBOARD_FAB2_LIB.BASEBOARD_FAB2(SCH_1):PWRGD_P1V538_BMC_STBY
  C9F9     1      A  CAP          I5
  EU9F1    6     EN  RT9059_DFN  I40
  R1T9     2      B  RES         I72

PWRGD_P1V538_BMC_STBY_R   @BASEBOARD_FAB2_LIB.BASEBOARD_FAB2(SCH_1):PWRGD_P1V538_BMC_STBY_R
  C9F10    1      A  CAP          I4
  EU9F2    5  PGOOD  RT9059_DFN  I70
  R1T9     1      A  RES         I72
  R9F12    2      B  RES          I6

PWRGD_P1V8MCP_CPU0   @BASEBOARD_FAB2_LIB.BASEBOARD_FAB2(SCH_1):PWRGD_P1V8MCP_CPU0
  J6B1   B15  IOB15  SCONN120_H61426002_SM  I56
  U8D7   D15   PR2D  LCMXO2_A_256BGA  I59

PWRGD_P1V8MCP_CPU1   @BASEBOARD_FAB2_LIB.BASEBOARD_FAB2(SCH_1):PWRGD_P1V8MCP_CPU1
  J4B2   B15  IOB15  SCONN120_H61426002_SM  I46
  U8D7   D16   PR2A  LCMXO2_A_256BGA  I59

PWRGD_P1V8_PCH_STBY   @BASEBOARD_FAB2_LIB.BASEBOARD_FAB2(SCH_1):PWRGD_P1V8_PCH_STBY
  R2L17    1      A  RES         I221
  R8A11    2      B  RES         I90

PWRGD_P1V8_PCH_STBY_R   @BASEBOARD_FAB2_LIB.BASEBOARD_FAB2(SCH_1):PWRGD_P1V8_PCH_STBY_R
  C8A11    1      A  CAP          I5
  EU8A2    5  PGOOD  RT9059_DFN  I86
  R8A10    2      B  RES          I3
  R8A11    1      A  RES         I90

PWRGD_P3V3      @BASEBOARD_FAB2_LIB.BASEBOARD_FAB2(SCH_1):PWRGD_P3V3
  R1L12    1      A  RES         I63
  R1L16    2      B  RES         I68
  U8D7    H6   PL5D  LCMXO2_A_256BGA  I179

PWRGD_P3V3_R    @BASEBOARD_FAB2_LIB.BASEBOARD_FAB2(SCH_1):PWRGD_P3V3_R
  R1L12    2      B  RES         I63
  U1L2     1      A  TTL1G86_SOTLF  I57

PWRGD_P3V3_R1   @BASEBOARD_FAB2_LIB.BASEBOARD_FAB2(SCH_1):PWRGD_P3V3_R1
  R1L16    1      A  RES         I68
  U1L3     2  RESET_N  ADM809      I80

PWRGD_P3V3_STBY   @BASEBOARD_FAB2_LIB.BASEBOARD_FAB2(SCH_1):PWRGD_P3V3_STBY
  C8A10    1      A  CAP         I55
  C9F6     1      A  CAP         I30
  CR7E1    1      C  DIODE_SMLF  I103
  EU8A2    6     EN  RT9059_DFN  I86
  EU8F2   40  VTTPWR_GD_PD_N  ICS9FGP204_MLFP  I34
  EU9F2    6     EN  RT9059_DFN  I70
  J7G2     5    IO5  CONN8_C77962004  I47
  R3P50    2      B  RES         I71
  R8F10    2      B  RES         I171
  U7D3     1   ENIN  ADM1085_SMT  I70
  U8D7   L12  PR10D  LCMXO2_A_256BGA  I59

PWRGD_P3V3_STBY_R   @BASEBOARD_FAB2_LIB.BASEBOARD_FAB2(SCH_1):PWRGD_P3V3_STBY_R
  C8F2     1      A  CAP         I116
  EU8F1    9  PGOOD  RT8240_QFN  I125
  R8F5     2      B  RES         I117
  R8F10    1      A  RES         I171

PWRGD_P5V       @BASEBOARD_FAB2_LIB.BASEBOARD_FAB2(SCH_1):PWRGD_P5V
  R2P20    2      B  RES         I65
  U8D7    J6   PL6D  LCMXO2_A_256BGA  I179

PWRGD_P5V_N     @BASEBOARD_FAB2_LIB.BASEBOARD_FAB2(SCH_1):PWRGD_P5V_N
  Q2P2     1   GATE  FET_N       I124
  R2P18    2      B  RES         I121
  U8D8     1   OUTB  TPS3700_SM  I104

PWRGD_P5V_R     @BASEBOARD_FAB2_LIB.BASEBOARD_FAB2(SCH_1):PWRGD_P5V_R
  Q2P2     3    DRN  FET_N       I124
  R2P20    1      A  RES         I65
  R2P21    2      B  RES         I122

PWRGD_P5V_STBY   @BASEBOARD_FAB2_LIB.BASEBOARD_FAB2(SCH_1):PWRGD_P5V_STBY
  C8E17    1      A  CAP         I113
  R7E15    2      B  RES         I89
  R8F1     1      A  RES         I111
  R8F2     1      A  RES         I176

PWRGD_P5V_STBY_R   @BASEBOARD_FAB2_LIB.BASEBOARD_FAB2(SCH_1):PWRGD_P5V_STBY_R
  C7E10    1      A  CAP         I14
  EU7E2   14  PWRGD  TPS54821_LCC  I83
  R7E12    2      B  RES         I11
  R7E15    1      A  RES         I89

PWRGD_PCH_PWROK   @BASEBOARD_FAB2_LIB.BASEBOARD_FAB2(SCH_1):PWRGD_PCH_PWROK
  R3N3     2      B  RES         I120
  U7C1   R17  PCH_PWROK  LBG_CORE_QAT_EXT_D  I73
  U8D7   C16   PR2C  LCMXO2_A_256BGA  I59
  U9F4   C15  GPIOE1_NDCD3  AST1250_BGA  I100

PWRGD_PVCCIN_CPU0   @BASEBOARD_FAB2_LIB.BASEBOARD_FAB2(SCH_1):PWRGD_PVCCIN_CPU0
  R4D63    2      B  RES         I124
  U1L1     1  OE<0>  TTL3126_QFNLF  I108
  U1L1     4  OE<0>  TTL3126_QFNLF  I108
  U1L1    10  OE<0>  TTL3126_QFNLF  I108
  U1L1    13  OE<0>  TTL3126_QFNLF  I108
  U1L5     1  OE<0>  TTL3126_QFNLF  I109
  U1L5     4  OE<0>  TTL3126_QFNLF  I109
  U1L5    10  OE<0>  TTL3126_QFNLF  I109
  U1L5    13  OE<0>  TTL3126_QFNLF  I109
  U8D7    K5  PL12C  LCMXO2_A_256BGA  I179

PWRGD_PVCCIN_CPU1   @BASEBOARD_FAB2_LIB.BASEBOARD_FAB2(SCH_1):PWRGD_PVCCIN_CPU1
  R1C30    2      B  RES         I113
  U8D7    N1  PL13B  LCMXO2_A_256BGA  I179

PWRGD_PVCCIOMCP_CPU0   @BASEBOARD_FAB2_LIB.BASEBOARD_FAB2(SCH_1):PWRGD_PVCCIOMCP_CPU0
  J6B1   B16  IOB16  SCONN120_H61426002_SM  I56
  U8D7    N6   PB8C  LCMXO2_A_256BGA  I179

PWRGD_PVCCIOMCP_CPU1   @BASEBOARD_FAB2_LIB.BASEBOARD_FAB2(SCH_1):PWRGD_PVCCIOMCP_CPU1
  J4B2   B16  IOB16  SCONN120_H61426002_SM  I46
  U8D7    T5   PB6A  LCMXO2_A_256BGA  I179

PWRGD_PVCCIO_CPU0   @BASEBOARD_FAB2_LIB.BASEBOARD_FAB2(SCH_1):PWRGD_PVCCIO_CPU0
  R3P20    2      B  RES         I58
  U7D1     1   OE_N  74CBTLV1G125  I142
  U8D7    L8  PB11D  LCMXO2_A_256BGA  I179

PWRGD_PVCCIO_CPU0_R   @BASEBOARD_FAB2_LIB.BASEBOARD_FAB2(SCH_1):PWRGD_PVCCIO_CPU0_R
  C3P6     1      A  CAP         I71
  EU3P1    9  AVRRDY  PXE1110B_QFN  I93
  R3P20    1      A  RES         I58
  R3P25    2      B  RES         I56

PWRGD_PVCCIO_CPU1   @BASEBOARD_FAB2_LIB.BASEBOARD_FAB2(SCH_1):PWRGD_PVCCIO_CPU1
  R4D46    2      B  RES         I13
  U8D7   L16  PR11A  LCMXO2_A_256BGA  I59

PWRGD_PVCCIO_CPU1_R   @BASEBOARD_FAB2_LIB.BASEBOARD_FAB2(SCH_1):PWRGD_PVCCIO_CPU1_R
  C4D33    1      A  CAP         I73
  EU4D5    9  AVRRDY  PXE1110B_QFN  I96
  R4D42    2      B  RES         I15
  R4D46    1      A  RES         I13

PWRGD_PVCCMCP_CPU0   @BASEBOARD_FAB2_LIB.BASEBOARD_FAB2(SCH_1):PWRGD_PVCCMCP_CPU0
  J6B1   D20  IOD20  SCONN120_H61426002_SM  I56
  U8D7    P5   PB5B  LCMXO2_A_256BGA  I179

PWRGD_PVCCMCP_CPU1   @BASEBOARD_FAB2_LIB.BASEBOARD_FAB2(SCH_1):PWRGD_PVCCMCP_CPU1
  J4B2   D20  IOD20  SCONN120_H61426002_SM  I46
  U8D7    L4  PL12D  LCMXO2_A_256BGA  I179

PWRGD_PVDDQ_ABC   @BASEBOARD_FAB2_LIB.BASEBOARD_FAB2(SCH_1):PWRGD_PVDDQ_ABC
  R4G23    1      A  RES         I38
  R7F24    2      B  RES         I296

PWRGD_PVDDQ_ABC_R   @BASEBOARD_FAB2_LIB.BASEBOARD_FAB2(SCH_1):PWRGD_PVDDQ_ABC_R
  C7F14    1      A  CAP         I305
  EU7G1    9  AVRRDY  PXM1310B_QFN  I358
  R7F22    2      B  RES         I301
  R7F24    1      A  RES         I296

PWRGD_PVDDQ_DEF   @BASEBOARD_FAB2_LIB.BASEBOARD_FAB2(SCH_1):PWRGD_PVDDQ_DEF
  R3M3     2      B  RES         I11
  R4A2     1      A  RES         I38

PWRGD_PVDDQ_DEF_R   @BASEBOARD_FAB2_LIB.BASEBOARD_FAB2(SCH_1):PWRGD_PVDDQ_DEF_R
  C7B3     1      A  CAP         I26
  EU7A5    9  AVRRDY  PXM1310B_QFN  I75
  R3M3     1      A  RES         I11
  R7B5     2      B  RES         I16

PWRGD_PVDDQ_GHJ   @BASEBOARD_FAB2_LIB.BASEBOARD_FAB2(SCH_1):PWRGD_PVDDQ_GHJ
  R1G12    2      B  RES         I14
  R4G16    1      A  RES         I35

PWRGD_PVDDQ_GHJ_R   @BASEBOARD_FAB2_LIB.BASEBOARD_FAB2(SCH_1):PWRGD_PVDDQ_GHJ_R
  C1G21    1      A  CAP         I80
  EU1G2    9  AVRRDY  PXM1310B_QFN  I90
  R1G12    1      A  RES         I14
  R1G16    2      B  RES         I17

PWRGD_PVDDQ_KLM   @BASEBOARD_FAB2_LIB.BASEBOARD_FAB2(SCH_1):PWRGD_PVDDQ_KLM
  R1B5     2      B  RES         I14
  R4A3     1      A  RES         I38

PWRGD_PVDDQ_KLM_R   @BASEBOARD_FAB2_LIB.BASEBOARD_FAB2(SCH_1):PWRGD_PVDDQ_KLM_R
  C1B4     1      A  CAP         I80
  EU1B1    9  AVRRDY  PXM1310B_QFN  I90
  R1B2     2      B  RES         I17
  R1B5     1      A  RES         I14

PWRGD_PVNN_P1V05_PCH   @BASEBOARD_FAB2_LIB.BASEBOARD_FAB2(SCH_1):PWRGD_PVNN_P1V05_PCH
  R2L16    2      B  RES         I147
  U8D7    P8  PB12A  LCMXO2_A_256BGA  I179

PWRGD_PVNN_PCH_R   @BASEBOARD_FAB2_LIB.BASEBOARD_FAB2(SCH_1):PWRGD_PVNN_PCH_R
  C8A9     1      A  CAP         I218
  EU8A1    9  AVRRDY  PXE1110B_QFN  I229
  R2L16    1      A  RES         I147
  R8A6     2      B  RES         I149

PWRGD_PVPP_ABC   @BASEBOARD_FAB2_LIB.BASEBOARD_FAB2(SCH_1):PWRGD_PVPP_ABC
  J8B1    19   IO19  SCONN24_H46321001_SM   I1
  R7F16    2      B  RES         I208
  U8D7    N7   PB9D  LCMXO2_A_256BGA  I179

PWRGD_PVPP_ABC_R   @BASEBOARD_FAB2_LIB.BASEBOARD_FAB2(SCH_1):PWRGD_PVPP_ABC_R
  C7F11    1      A  CAP         I142
  EU7F1    7     PG  NCP3232L_SM  I193
  R7F16    1      A  RES         I208
  R7F19    2      B  RES         I143

PWRGD_PVPP_DEF   @BASEBOARD_FAB2_LIB.BASEBOARD_FAB2(SCH_1):PWRGD_PVPP_DEF
  R7B12    2      B  RES         I257
  U8D7    M6  PB11C  LCMXO2_A_256BGA  I179

PWRGD_PVPP_DEF_R   @BASEBOARD_FAB2_LIB.BASEBOARD_FAB2(SCH_1):PWRGD_PVPP_DEF_R
  C7B12    1      A  CAP         I209
  EU7B1    7     PG  NCP3232L_SM  I214
  R7B12    1      A  RES         I257
  R7B17    2      B  RES         I210

PWRGD_PVPP_GHJ   @BASEBOARD_FAB2_LIB.BASEBOARD_FAB2(SCH_1):PWRGD_PVPP_GHJ
  R4G12    2      B  RES         I247
  U8D7    M2  PL14A  LCMXO2_A_256BGA  I179

PWRGD_PVPP_GHJ_R   @BASEBOARD_FAB2_LIB.BASEBOARD_FAB2(SCH_1):PWRGD_PVPP_GHJ_R
  C4G9     1      A  CAP         I201
  EU4G1    7     PG  NCP3232L_SM  I225
  R4G12    1      A  RES         I247
  R4G14    2      B  RES         I185

PWRGD_PVPP_KLM   @BASEBOARD_FAB2_LIB.BASEBOARD_FAB2(SCH_1):PWRGD_PVPP_KLM
  R4B7     2      B  RES         I201
  U8D7    N2  PL13C  LCMXO2_A_256BGA  I179

PWRGD_PVPP_KLM_R   @BASEBOARD_FAB2_LIB.BASEBOARD_FAB2(SCH_1):PWRGD_PVPP_KLM_R
  C4B8     1      A  CAP         I139
  EU4A3    7     PG  NCP3232L_SM  I184
  R4B7     1      A  RES         I201
  R4B10    2      B  RES         I143

PWRGD_PVSA_CPU0   @BASEBOARD_FAB2_LIB.BASEBOARD_FAB2(SCH_1):PWRGD_PVSA_CPU0
  R4D65    2      B  RES         I127
  U8D7    L1  PL11A  LCMXO2_A_256BGA  I179

PWRGD_PVSA_CPU0_R   @BASEBOARD_FAB2_LIB.BASEBOARD_FAB2(SCH_1):PWRGD_PVSA_CPU0_R
  EU4D4   15    MP0  PXE1610B_QFN  I155
  R4D65    1      A  RES         I127
  R4E5     2      B  RES         I27

PWRGD_PVSA_CPU1   @BASEBOARD_FAB2_LIB.BASEBOARD_FAB2(SCH_1):PWRGD_PVSA_CPU1
  R1D1     2      B  RES         I116
  U8D7    T4   PB3B  LCMXO2_A_256BGA  I179

PWRGD_PVSA_CPU1_R   @BASEBOARD_FAB2_LIB.BASEBOARD_FAB2(SCH_1):PWRGD_PVSA_CPU1_R
  EU1C2   15    MP0  PXE1610B_QFN  I130
  R1D1     1      A  RES         I116
  R1D8     2      B  RES         I36

PWRGD_PVTT_ABC_CPU0_R   @BASEBOARD_FAB2_LIB.BASEBOARD_FAB2(SCH_1):PWRGD_PVTT_ABC_CPU0_R
  C4G14    1      A  CAP         I15
  EU4G3    5     PG  MIC5166_DFN   I1
  R4G18    2      B  RES         I45
  R4G19    1      A  RES         I54

PWRGD_PVTT_CPU0   @BASEBOARD_FAB2_LIB.BASEBOARD_FAB2(SCH_1):PWRGD_PVTT_CPU0
  R4A6     2      B  RES         I51
  R4G19    2      B  RES         I54
  U8D7    B4  PT11D  LCMXO2_A_256BGA  I59

PWRGD_PVTT_CPU1   @BASEBOARD_FAB2_LIB.BASEBOARD_FAB2(SCH_1):PWRGD_PVTT_CPU1
  R4A4     2      B  RES         I51
  R4G15    2      B  RES         I51
  U8D7    R7   PB9A  LCMXO2_A_256BGA  I179

PWRGD_PVTT_DEF_CPU0_R   @BASEBOARD_FAB2_LIB.BASEBOARD_FAB2(SCH_1):PWRGD_PVTT_DEF_CPU0_R
  C4A12    1      A  CAP         I12
  EU4A1    5     PG  MIC5166_DFN  I31
  R4A6     1      A  RES         I51
  R6L9     2      B  RES         I19

PWRGD_PVTT_GHJ_CPU1_R   @BASEBOARD_FAB2_LIB.BASEBOARD_FAB2(SCH_1):PWRGD_PVTT_GHJ_CPU1_R
  C4G13    1      A  CAP         I15
  EU4G2    5     PG  MIC5166_DFN  I24
  R4G15    1      A  RES         I51
  R4G17    2      B  RES         I14

PWRGD_PVTT_KLM_CPU1_R   @BASEBOARD_FAB2_LIB.BASEBOARD_FAB2(SCH_1):PWRGD_PVTT_KLM_CPU1_R
  C4A3     1      A  CAP         I16
  EU4A2    5     PG  MIC5166_DFN  I31
  R4A4     1      A  RES         I51
  R4A5     2      B  RES         I17

PWRGD_SYS_PWROK   @BASEBOARD_FAB2_LIB.BASEBOARD_FAB2(SCH_1):PWRGD_SYS_PWROK
  R2N12    2      B  RES         I122
  U7C1   BY19  SYS_PWROK  LBG_CORE_QAT_EXT_D  I73
  U8D7   D14   PR1A  LCMXO2_A_256BGA  I59
  U9F4   B15  GPIOE2_NDSR3  AST1250_BGA  I100

RCC_DFX_1940_1   @BASEBOARD_FAB2_LIB.BASEBOARD_FAB2(SCH_1):RCC_DFX_1940_1
  TC1A1    2    IO1  RCC_DFX1940   I7
  TC1A1    3    IO2  RCC_DFX1940   I7

RCC_DFX_1940_2   @BASEBOARD_FAB2_LIB.BASEBOARD_FAB2(SCH_1):RCC_DFX_1940_2
  TC9A1    2    IO1  RCC_DFX1940   I9
  TC9A1    3    IO2  RCC_DFX1940   I9

RCC_DFX_1940_3   @BASEBOARD_FAB2_LIB.BASEBOARD_FAB2(SCH_1):RCC_DFX_1940_3
  TC9F1    2    IO1  RCC_DFX1940   I1
  TC9F1    3    IO2  RCC_DFX1940   I1

RCC_DFX_1940_4   @BASEBOARD_FAB2_LIB.BASEBOARD_FAB2(SCH_1):RCC_DFX_1940_4
  TC1G1    2    IO1  RCC_DFX1940   I3
  TC1G1    3    IO2  RCC_DFX1940   I3

RMII_BMC_OCP_CRSDV   @BASEBOARD_FAB2_LIB.BASEBOARD_FAB2(SCH_1):RMII_BMC_OCP_CRSDV
  R1M15    1      A  RES         I339
  U9F4   A11  RGMII1RXD2_RMII1CRSDV_GPIOV0  AST1250_BGA   I1

RMII_BMC_OCP_CRSDV_R   @BASEBOARD_FAB2_LIB.BASEBOARD_FAB2(SCH_1):RMII_BMC_OCP_CRSDV_R
  J9B3    27   IO27  SCONN120_A28699018_SM  I336
  R1M15    2      B  RES         I339

RMII_BMC_OCP_RXD0   @BASEBOARD_FAB2_LIB.BASEBOARD_FAB2(SCH_1):RMII_BMC_OCP_RXD0
  R1M17    1      A  RES         I338
  U9F4   C11  RGMII1RXD0_RMII1RXD0_GPIOU6  AST1250_BGA   I1

RMII_BMC_OCP_RXD0_R   @BASEBOARD_FAB2_LIB.BASEBOARD_FAB2(SCH_1):RMII_BMC_OCP_RXD0_R
  J9B3    43   IO43  SCONN120_A28699018_SM  I336
  R1M17    2      B  RES         I338

RMII_BMC_OCP_RXD1   @BASEBOARD_FAB2_LIB.BASEBOARD_FAB2(SCH_1):RMII_BMC_OCP_RXD1
  R1M16    1      A  RES         I337
  U9F4   B11  RGMII1RXD1_RMII1RXD1_GPIOU7  AST1250_BGA   I1

RMII_BMC_OCP_RXD1_R   @BASEBOARD_FAB2_LIB.BASEBOARD_FAB2(SCH_1):RMII_BMC_OCP_RXD1_R
  J9B3    45   IO45  SCONN120_A28699018_SM  I336
  R1M16    2      B  RES         I337

RMII_BMC_OCP_RXER   @BASEBOARD_FAB2_LIB.BASEBOARD_FAB2(SCH_1):RMII_BMC_OCP_RXER
  R1M18    2      B  RES         I340
  U9F4   E10  RGMII1RXD3_RMII1RXER_GPIOV1  AST1250_BGA   I1

RMII_BMC_OCP_RXER_R   @BASEBOARD_FAB2_LIB.BASEBOARD_FAB2(SCH_1):RMII_BMC_OCP_RXER_R
  J9B3    36   IO36  SCONN120_A28699018_SM  I336
  R1M18    1      A  RES         I340

RMII_BMC_OCP_TXD0   @BASEBOARD_FAB2_LIB.BASEBOARD_FAB2(SCH_1):RMII_BMC_OCP_TXD0
  J9B3    40   IO40  SCONN120_A28699018_SM  I336
  R8F31    2      B  RES         I126

RMII_BMC_OCP_TXD0_R   @BASEBOARD_FAB2_LIB.BASEBOARD_FAB2(SCH_1):RMII_BMC_OCP_TXD0_R
  R8F31    1      A  RES         I126
  U9F4   C12  RGMII1TXD0_RMII1TXD0_GPIOT2  AST1250_BGA   I1

RMII_BMC_OCP_TXD1   @BASEBOARD_FAB2_LIB.BASEBOARD_FAB2(SCH_1):RMII_BMC_OCP_TXD1
  J9B3    42   IO42  SCONN120_A28699018_SM  I336
  R8F28    2      B  RES         I125

RMII_BMC_OCP_TXD1_R   @BASEBOARD_FAB2_LIB.BASEBOARD_FAB2(SCH_1):RMII_BMC_OCP_TXD1_R
  R8F28    1      A  RES         I125
  U9F4   D12  RGMII1TXD1_RMII1TXD1_GPIOT3  AST1250_BGA   I1

RMII_BMC_OCP_TXEN   @BASEBOARD_FAB2_LIB.BASEBOARD_FAB2(SCH_1):RMII_BMC_OCP_TXEN
  J9B3    31   IO31  SCONN120_A28699018_SM  I336
  R8F30    2      B  RES         I154

RMII_BMC_OCP_TXEN_R   @BASEBOARD_FAB2_LIB.BASEBOARD_FAB2(SCH_1):RMII_BMC_OCP_TXEN_R
  R8F30    1      A  RES         I154
  U9F4   A12  RGMII1TXCK_RMII1TXEN_GPIOT0  AST1250_BGA   I1

RMII_BMC_PCH_SPRNGVLLE_CRSDV   @BASEBOARD_FAB2_LIB.BASEBOARD_FAB2(SCH_1):RMII_BMC_PCH_SPRNGVLLE_CRSDV
  R1T1     1      A  RES         I214
  R3P2     1      A  RES         I90
  R9F1     2      B  RES         I225
  U9F4    D8  RGMII2RXD2_RMII2CRSDV_GPIOV6  AST1250_BGA   I1

RMII_BMC_PCH_SPRNGVLLE_CRSDV_R   @BASEBOARD_FAB2_LIB.BASEBOARD_FAB2(SCH_1):RMII_BMC_PCH_SPRNGVLLE_CRSDV_R
  EU9E1    3  NC_SI_CRS_DV  SPRINGVILLE_SM1  I72
  R9F1     1      A  RES         I225

RMII_BMC_PCH_SPRNGVLLE_CRSDV_R1   @BASEBOARD_FAB2_LIB.BASEBOARD_FAB2(SCH_1):RMII_BMC_PCH_SPRNGVLLE_CRSDV_R1
  R3P2     2      B  RES         I90
  U7C1   AN3  GPP_K4_LAN_NCSI_CRS_DV  LBG_CORE_QAT_EXT_D  I34

RMII_BMC_PCH_SPRNGVLLE_RXER   @BASEBOARD_FAB2_LIB.BASEBOARD_FAB2(SCH_1):RMII_BMC_PCH_SPRNGVLLE_RXER
  R7C14    1      A  RES         I98
  R7D13    2      B  RES         I60
  U9F4    C8  RGMII2RXD3_RMII2RXER_GPIOV7  AST1250_BGA   I1

RMII_BMC_PCH_SPRNGVLLE_RXER_R   @BASEBOARD_FAB2_LIB.BASEBOARD_FAB2(SCH_1):RMII_BMC_PCH_SPRNGVLLE_RXER_R
  R7C14    2      B  RES         I98
  U7C1   AH2  GPP_K7  LBG_CORE_QAT_EXT_D  I34

RMII_BMC_PCH_SPRNGVLLE_TXD0   @BASEBOARD_FAB2_LIB.BASEBOARD_FAB2(SCH_1):RMII_BMC_PCH_SPRNGVLLE_TXD0
  EU9E1    9  NC_SI_TXD0  SPRINGVILLE_SM1  I72
  R1R4     2      B  RES         I119
  R1T28    2      B  RES         I121
  U7C1   AM2  GPP_K1_LAN_NCSI_TXD0  LBG_CORE_QAT_EXT_D  I34

RMII_BMC_PCH_SPRNGVLLE_TXD0_R   @BASEBOARD_FAB2_LIB.BASEBOARD_FAB2(SCH_1):RMII_BMC_PCH_SPRNGVLLE_TXD0_R
  R1T28    1      A  RES         I121
  U9F4   A10  RGMII2TXD0_RMII2TXD0_GPIOU0  AST1250_BGA   I1

RMII_BMC_PCH_SPRNGVLLE_TXD1   @BASEBOARD_FAB2_LIB.BASEBOARD_FAB2(SCH_1):RMII_BMC_PCH_SPRNGVLLE_TXD1
  EU9E1    8  NC_SI_TXD1  SPRINGVILLE_SM1  I72
  R2T45    2      B  RES         I115
  R8F32    2      B  RES         I118
  U7C1   AK2  GPP_K2_LAN_NCSI_TXD1  LBG_CORE_QAT_EXT_D  I34

RMII_BMC_PCH_SPRNGVLLE_TXD1_R   @BASEBOARD_FAB2_LIB.BASEBOARD_FAB2(SCH_1):RMII_BMC_PCH_SPRNGVLLE_TXD1_R
  R2T45    1      A  RES         I115
  U9F4   B10  RGMII2TXD1_RMII2TXD1_GPIOU1  AST1250_BGA   I1

RMII_BMC_PCH_SPRNGVLLE_TXEN   @BASEBOARD_FAB2_LIB.BASEBOARD_FAB2(SCH_1):RMII_BMC_PCH_SPRNGVLLE_TXEN
  EU9E1    7  NC_SI_TX_EN  SPRINGVILLE_SM1  I72
  R8F33    2      B  RES         I116
  R9E13    1      A  RES         I212
  U7C1   AL3  GPP_K3_LAN_NCSI_TX_EN  LBG_CORE_QAT_EXT_D  I34

RMII_BMC_SPRNGVLLE_TXEN_R   @BASEBOARD_FAB2_LIB.BASEBOARD_FAB2(SCH_1):RMII_BMC_SPRNGVLLE_TXEN_R
  R8F33    1      A  RES         I116
  U9F4    D9  RGMII2TXCK_RMII2TXEN_GPIOT6  AST1250_BGA   I1

RMII_PCH_SPRNGVLLE_ARB_IN   @BASEBOARD_FAB2_LIB.BASEBOARD_FAB2(SCH_1):RMII_PCH_SPRNGVLLE_ARB_IN
  R9E16    2      B  RES         I235
  U7C1   AJ3  GPP_K8_LAN_NCSI_ARB_IN  LBG_CORE_QAT_EXT_D  I34

RMII_PCH_SPRNGVLLE_ARB_IN_R   @BASEBOARD_FAB2_LIB.BASEBOARD_FAB2(SCH_1):RMII_PCH_SPRNGVLLE_ARB_IN_R
  EU9E1   44  NC_SI_ARB_OUT  SPRINGVILLE_SM1  I72
  R9E16    1      A  RES         I235

RMII_PCH_SPRNGVLLE_ARB_OUT   @BASEBOARD_FAB2_LIB.BASEBOARD_FAB2(SCH_1):RMII_PCH_SPRNGVLLE_ARB_OUT
  EU9E1   43  NC_SI_ARB_IN  SPRINGVILLE_SM1  I72
  R7D1     1      A  RES         I70
  R8D11    1      A  RES         I101
  R8D16    2      B  RES         I71

RMII_PCH_SPRNGVLLE_ARB_OUT_R   @BASEBOARD_FAB2_LIB.BASEBOARD_FAB2(SCH_1):RMII_PCH_SPRNGVLLE_ARB_OUT_R
  R8D11    2      B  RES         I101
  U7C1   AK4  GPP_K9_LAN_NCSI_ARB_OUT  LBG_CORE_QAT_EXT_D  I34

RMII_SPRNGVLLE_BMC_PCH_RXD0   @BASEBOARD_FAB2_LIB.BASEBOARD_FAB2(SCH_1):RMII_SPRNGVLLE_BMC_PCH_RXD0
  R1R10    2      B  RES         I108
  R3P3     1      A  RES         I89
  R9E17    2      B  RES         I229
  U9F4    A9  RGMII2RXD0_RMII2RXD0_GPIOV4  AST1250_BGA   I1

RMII_SPRNGVLLE_BMC_PCH_RXD0_R   @BASEBOARD_FAB2_LIB.BASEBOARD_FAB2(SCH_1):RMII_SPRNGVLLE_BMC_PCH_RXD0_R
  EU9E1    6  NC_SI_RXD0  SPRINGVILLE_SM1  I72
  R9E17    1      A  RES         I229

RMII_SPRNGVLLE_BMC_PCH_RXD0_R1   @BASEBOARD_FAB2_LIB.BASEBOARD_FAB2(SCH_1):RMII_SPRNGVLLE_BMC_PCH_RXD0_R1
  R3P3     2      B  RES         I89
  U7C1   AL1  GPP_K5_LAN_NCSI_RXD0  LBG_CORE_QAT_EXT_D  I34

RMII_SPRNGVLLE_BMC_PCH_RXD1   @BASEBOARD_FAB2_LIB.BASEBOARD_FAB2(SCH_1):RMII_SPRNGVLLE_BMC_PCH_RXD1
  R1R13    2      B  RES         I109
  R2P1     1      A  RES         I91
  R9E19    2      B  RES         I228
  U9F4    E8  RGMII2RXD1_RMII2RXD1_GPIOV5  AST1250_BGA   I1

RMII_SPRNGVLLE_BMC_PCH_RXD1_R   @BASEBOARD_FAB2_LIB.BASEBOARD_FAB2(SCH_1):RMII_SPRNGVLLE_BMC_PCH_RXD1_R
  EU9E1    5  NC_SI_RXD1  SPRINGVILLE_SM1  I72
  R9E19    1      A  RES         I228

RMII_SPRNGVLLE_BMC_PCH_RXD1_R1   @BASEBOARD_FAB2_LIB.BASEBOARD_FAB2(SCH_1):RMII_SPRNGVLLE_BMC_PCH_RXD1_R1
  R2P1     2      B  RES         I91
  U7C1   AN1  GPP_K6_LAN_NCSI_RXD1  LBG_CORE_QAT_EXT_D  I34

RST_BMC_DDR3_BUF_IN_N   @BASEBOARD_FAB2_LIB.BASEBOARD_FAB2(SCH_1):RST_BMC_DDR3_BUF_IN_N
  R8D36    2      B  RES         I388
  U9F3     2      A  TTL1G07_A_SOP  I69

RST_BMC_DDR3_N   @BASEBOARD_FAB2_LIB.BASEBOARD_FAB2(SCH_1):RST_BMC_DDR3_N
  R9F34    2      B  RES         I70
  U9F5    T2  RESET_N  K4B1G16_BGA1   I1

RST_BMC_DDR3_R_N   @BASEBOARD_FAB2_LIB.BASEBOARD_FAB2(SCH_1):RST_BMC_DDR3_R_N
  R9F29    2      B  RES         I71
  R9F34    1      A  RES         I70
  U9F3     4      Y  TTL1G07_A_SOP  I69

RST_BMC_LVC3_N   @BASEBOARD_FAB2_LIB.BASEBOARD_FAB2(SCH_1):RST_BMC_LVC3_N
  R9F7     2      B  RES         I405
  U9F4   E19  GPIOB4_LPCRST_N  AST1250_BGA  I347

RST_BMC_SRST_N   @BASEBOARD_FAB2_LIB.BASEBOARD_FAB2(SCH_1):RST_BMC_SRST_N
  J8G2     3    IO3  CONN12_C73564003  I124
  R7D23    1      A  RES         I131
  R8D22    2      B  RES         I386
  R9E14    1      A  RES         I379
  U9F4   W20  SRST_N  AST1250_BGA  I100

RST_BMC_SRST_R2_N   @BASEBOARD_FAB2_LIB.BASEBOARD_FAB2(SCH_1):RST_BMC_SRST_R2_N
  R8D22    1      A  RES         I386
  R8D25    2      B  RES         I335
  R8D36    1      A  RES         I388
  U8D2     4      Y  TTL1G07_A_SOP  I374

RST_BMC_SRST_R_N   @BASEBOARD_FAB2_LIB.BASEBOARD_FAB2(SCH_1):RST_BMC_SRST_R_N
  R7D23    2      B  RES         I131
  U7C1   M11  GPD2_GBE_WAKE_N  LBG_CORE_QAT_EXT_D  I73

RST_BMC_SYSRST_BTN_OUT_B_N   @BASEBOARD_FAB2_LIB.BASEBOARD_FAB2(SCH_1):RST_BMC_SYSRST_BTN_OUT_B_N
  R2T18    2      B  RES         I288
  U7C1   BV19  SYS_RESET_N  LBG_CORE_QAT_EXT_D  I73
  U8D7   F14   PR4A  LCMXO2_A_256BGA  I59

RST_BMC_SYSRST_BTN_OUT_B_R_N   @BASEBOARD_FAB2_LIB.BASEBOARD_FAB2(SCH_1):RST_BMC_SYSRST_BTN_OUT_B_R_N
  R2T18    1      A  RES         I288
  R2T22    2      B  RES         I210
  U8F3     6     1Y  TTL2G07_SOT23LF  I201
  U8G1     6     1Y  TTL2G07_SOT23LF  I269

RST_BMC_SYSRST_BTN_OUT_N   @BASEBOARD_FAB2_LIB.BASEBOARD_FAB2(SCH_1):RST_BMC_SYSRST_BTN_OUT_N
  R2T35    2      B  RES         I207
  U8F3     1     1A  TTL2G07_SOT23LF  I201
  U9F4   B16  GPIOD5_SD2DAT3  AST1250_BGA  I100

RST_CD_CPU0_POR_N   @BASEBOARD_FAB2_LIB.BASEBOARD_FAB2(SCH_1):RST_CD_CPU0_POR_N
  R3R16    2      B  RES         I48
  U5D1   CF25  CD_POR_N  SKX_EXT_B_BGA1  I61
  U8D7    N3  PL14B  LCMXO2_A_256BGA  I179

RST_CD_CPU1_POR_N   @BASEBOARD_FAB2_LIB.BASEBOARD_FAB2(SCH_1):RST_CD_CPU1_POR_N
  R6M9     2      B  RES         I49
  U2D1   CF25  CD_POR_N  SKX_EXT_B_BGA1  I23
  U8D7   P10  PB19A  LCMXO2_A_256BGA  I179

RST_CPU0_G_N    @BASEBOARD_FAB2_LIB.BASEBOARD_FAB2(SCH_1):RST_CPU0_G_N
  R6D12    2      B  RES          I2
  U3P1     5     B2  GTL2014_SM  I42
  U5D1   AP21  RESET_N  SKX_EXT_B_BGA1  I259

RST_CPU0_LVC3_N   @BASEBOARD_FAB2_LIB.BASEBOARD_FAB2(SCH_1):RST_CPU0_LVC3_N
  R3P34    2      B  RES         I116
  U3P1    10     A2  GTL2014_SM  I42

RST_CPU0_LVC3_R1_N   @BASEBOARD_FAB2_LIB.BASEBOARD_FAB2(SCH_1):RST_CPU0_LVC3_R1_N
  R3P34    1      A  RES         I116
  U8D7   R10  PB19B  LCMXO2_A_256BGA  I179

RST_CPU1_G_N    @BASEBOARD_FAB2_LIB.BASEBOARD_FAB2(SCH_1):RST_CPU1_G_N
  R3D20    2      B  RES         I25
  U2D1   AP21  RESET_N  SKX_EXT_B_BGA1  I172
  U4C2     5     B2  GTL2014_SM  I46

RST_CPU1_LVC3_N   @BASEBOARD_FAB2_LIB.BASEBOARD_FAB2(SCH_1):RST_CPU1_LVC3_N
  R3P35    2      B  RES         I117
  U4C2    10     A2  GTL2014_SM  I46

RST_CPU1_LVC3_R1_N   @BASEBOARD_FAB2_LIB.BASEBOARD_FAB2(SCH_1):RST_CPU1_LVC3_R1_N
  R3P35    1      A  RES         I117
  U8D7   N10  PB19C  LCMXO2_A_256BGA  I179

RST_HFI0_CPU0_LVT2_N   @BASEBOARD_FAB2_LIB.BASEBOARD_FAB2(SCH_1):RST_HFI0_CPU0_LVT2_N
  J8B1     6    IO6  SCONN24_H46321001_SM   I1
  R8B8     2      B  RES         I14
  U5D1   BN24  CD_HFI0_RESET_N  SKX_EXT_B_BGA1  I61

RST_HFI1_CPU0_LVT2_N   @BASEBOARD_FAB2_LIB.BASEBOARD_FAB2(SCH_1):RST_HFI1_CPU0_LVT2_N
  J8B1    14   IO14  SCONN24_H46321001_SM   I1
  R8B16    2      B  RES         I17
  U5D1   BK23  CD_HFI1_RESET_N  SKX_EXT_B_BGA1  I61

RST_PCH_SYSRST_BTN_OUT_N   @BASEBOARD_FAB2_LIB.BASEBOARD_FAB2(SCH_1):RST_PCH_SYSRST_BTN_OUT_N
  R2U2     2      B  RES         I265
  U7C1   AD3  GPP_A18  LBG_CORE_QAT_EXT_D  I115
  U8G1     1     1A  TTL2G07_SOT23LF  I269

RST_PCIE_CPU_DEV0_N   @BASEBOARD_FAB2_LIB.BASEBOARD_FAB2(SCH_1):RST_PCIE_CPU_DEV0_N
  R1M14    1      A  RES         I220
  U8D7    D6  PT12A  LCMXO2_A_256BGA  I59

RST_PCIE_CPU_DEV0_R_N   @BASEBOARD_FAB2_LIB.BASEBOARD_FAB2(SCH_1):RST_PCIE_CPU_DEV0_R_N
  J9B3    33   IO33  SCONN120_A28699018_SM  I336
  R1M14    2      B  RES         I220

RST_PCIE_CPU_DEV1_N   @BASEBOARD_FAB2_LIB.BASEBOARD_FAB2(SCH_1):RST_PCIE_CPU_DEV1_N
  R9E10    2      B  RES         I145
  U8D7    C1   PL2C  LCMXO2_A_256BGA  I179

RST_PCIE_CPU_DEV1_R_N   @BASEBOARD_FAB2_LIB.BASEBOARD_FAB2(SCH_1):RST_PCIE_CPU_DEV1_R_N
  J8E3    75   IO75  SCONN80_E67482007_SM  I119
  R9E10    1      A  RES         I145

RST_PCIE_CPU_DEV2_N   @BASEBOARD_FAB2_LIB.BASEBOARD_FAB2(SCH_1):RST_PCIE_CPU_DEV2_N
  R9E11    2      B  RES         I150
  U8D7    H3   PL7A  LCMXO2_A_256BGA  I179

RST_PCIE_CPU_DEV2_R_N   @BASEBOARD_FAB2_LIB.BASEBOARD_FAB2(SCH_1):RST_PCIE_CPU_DEV2_R_N
  J8E3    77   IO77  SCONN80_E67482007_SM  I119
  R9E11    1      A  RES         I150

RST_PCIE_CPU_DEV3_N   @BASEBOARD_FAB2_LIB.BASEBOARD_FAB2(SCH_1):RST_PCIE_CPU_DEV3_N
  R9E12    2      B  RES         I153
  U8D7    H1   PL7B  LCMXO2_A_256BGA  I179

RST_PCIE_CPU_DEV3_R_N   @BASEBOARD_FAB2_LIB.BASEBOARD_FAB2(SCH_1):RST_PCIE_CPU_DEV3_R_N
  J8E3    79   IO79  SCONN80_E67482007_SM  I119
  R9E12    1      A  RES         I153

RST_PCIE_M2_DEV_N   @BASEBOARD_FAB2_LIB.BASEBOARD_FAB2(SCH_1):RST_PCIE_M2_DEV_N
  J8F1    50  PERST_N_NC  SCONN75K_H17033002_SMT1  I53
  U8D7    R6   PB6B  LCMXO2_A_256BGA  I179

RST_PCIE_MIDPLANE_N   @BASEBOARD_FAB2_LIB.BASEBOARD_FAB2(SCH_1):RST_PCIE_MIDPLANE_N
  J1F1    I5  GNDI5  CONN76_H22707001_THMT1  I111
  U8D7    D9  PT18B  LCMXO2_A_256BGA  I59

RST_PCIE_PCH_PERST_N   @BASEBOARD_FAB2_LIB.BASEBOARD_FAB2(SCH_1):RST_PCIE_PCH_PERST_N
  U7C1   AH4  GPP_K10_PE_RST_N  LBG_CORE_QAT_EXT_D  I34
  U8D7    B1   PL1C  LCMXO2_A_256BGA  I179

RST_PCIE_RISER1_PERST_N   @BASEBOARD_FAB2_LIB.BASEBOARD_FAB2(SCH_1):RST_PCIE_RISER1_PERST_N
  R2U37    1      A  RES         I173
  U8D7    M3  PL13A  LCMXO2_A_256BGA  I179

RST_PCIE_RISER1_PERST_R_N   @BASEBOARD_FAB2_LIB.BASEBOARD_FAB2(SCH_1):RST_PCIE_RISER1_PERST_R_N
  J8G1    29   IO29  SCONN200_H68296001_SM  I258
  R2U37    2      B  RES         I173

RST_PLTRST_BUF_N   @BASEBOARD_FAB2_LIB.BASEBOARD_FAB2(SCH_1):RST_PLTRST_BUF_N
  J8E1     2    IO2  SCONN11_H67026001_SM  I87
  Q8D2     1   GATE  FET_N        I4
  R9F4     1      A  RES         I208
  R9F7     1      A  RES         I405
  U8D7   K11  PR12C  LCMXO2_A_256BGA  I59
  U9F4   K19  PERST_N  AST1250_BGA  I100

RST_PLTRST_N    @BASEBOARD_FAB2_LIB.BASEBOARD_FAB2(SCH_1):RST_PLTRST_N
  Q8E1     1   GATE  FET_N       I134
  R1R1     1      A  RES         I195
  U7C1   BN18  GPP_B13_PLTRST_N  LBG_CORE_QAT_EXT_D  I115
  U8D7   E15   PR1B  LCMXO2_A_256BGA  I59

RST_PLTRST_SPRV_R_N   @BASEBOARD_FAB2_LIB.BASEBOARD_FAB2(SCH_1):RST_PLTRST_SPRV_R_N
  EU9E1   17  PE_RST_N  SPRINGVILLE_SM1  I72
  R1R1     2      B  RES         I195
  R9E4     2      B  RES         I200

RST_PLTRST_TOP_SWAP   @BASEBOARD_FAB2_LIB.BASEBOARD_FAB2(SCH_1):RST_PLTRST_TOP_SWAP
  Q8E1     3    DRN  FET_N       I134
  R8E14    2      B  RES         I133
  U8E3     1     OE  TTL1G126_A_SOT  I130

RST_RSMRST_DLY   @BASEBOARD_FAB2_LIB.BASEBOARD_FAB2(SCH_1):RST_RSMRST_DLY
  Q8E2     1   GATE  FET_N       I13
  U8D7    M1  PL12B_PCLKC3_0  LCMXO2_A_256BGA  I179

RST_RSMRST_N    @BASEBOARD_FAB2_LIB.BASEBOARD_FAB2(SCH_1):RST_RSMRST_N
  R2R2     2      B  RES         I338
  R7E18    2      B  RES         I55
  R9A15    1      A  RES         I60
  U7C1   P15  RSMRST_N  LBG_CORE_QAT_EXT_D  I73

RST_RSMRST_R_N   @BASEBOARD_FAB2_LIB.BASEBOARD_FAB2(SCH_1):RST_RSMRST_R_N
  R2R2     1      A  RES         I338
  U8D7    G4   PL4D  LCMXO2_A_256BGA  I179

RST_RTCRST_N    @BASEBOARD_FAB2_LIB.BASEBOARD_FAB2(SCH_1):RST_RTCRST_N
  C7C19    1      A  CAP_A       I14
  J9G1     4    IO4  CONN12_C73564003  I128
  R7C10    2      B  RES         I13
  R7C11    2      B  RES         I11
  U7C1   P11  RTCRST_N  LBG_CORE_QAT_EXT_D  I34

RST_SRTCRST_N   @BASEBOARD_FAB2_LIB.BASEBOARD_FAB2(SCH_1):RST_SRTCRST_N
  C3N32    1      A  CAP_A       I20
  R3N4     2      B  RES         I19
  U7C1   G18  SRTCRST_N  LBG_CORE_QAT_EXT_D  I34

RST_SYSTEM_BTN_BUF_N   @BASEBOARD_FAB2_LIB.BASEBOARD_FAB2(SCH_1):RST_SYSTEM_BTN_BUF_N
  R9A9     1      A  RES         I35
  U9A3     4   Y<0>  TTL2G14     I15

RST_SYSTEM_BTN_N   @BASEBOARD_FAB2_LIB.BASEBOARD_FAB2(SCH_1):RST_SYSTEM_BTN_N
  R9A9     2      B  RES         I35
  U7C1   BL11  GPP_B10_SRCCLKREQ5_N  LBG_CORE_QAT_EXT_D  I115
  U9F4   C16  GPIOD4_SD2DAT2  AST1250_BGA  I100

SATA6G_P0_RX_C_DN   @BASEBOARD_FAB2_LIB.BASEBOARD_FAB2(SCH_1):SATA6G_P0_RX_C_DN
  C2L17    2      B  CAP_A       I174
  J8A1   1B5  RXA0_DN  CONN72_G97614002_A_CP  I163

SATA6G_P0_RX_C_DP   @BASEBOARD_FAB2_LIB.BASEBOARD_FAB2(SCH_1):SATA6G_P0_RX_C_DP
  C2L19    2      B  CAP_A       I172
  J8A1   1B4  RXA0_DP  CONN72_G97614002_A_CP  I163

SATA6G_P0_TX_C_DN   @BASEBOARD_FAB2_LIB.BASEBOARD_FAB2(SCH_1):SATA6G_P0_TX_C_DN
  C2L40    1      A  CAP_A       I220
  J8A1   1D5  TXA0_DN  CONN72_G97614002_A_CP  I163

SATA6G_P0_TX_C_DP   @BASEBOARD_FAB2_LIB.BASEBOARD_FAB2(SCH_1):SATA6G_P0_TX_C_DP
  C2L39    1      A  CAP_A       I221
  J8A1   1D4  TXA0_DP  CONN72_G97614002_A_CP  I163

SATA6G_P10_RX_C_DN   @BASEBOARD_FAB2_LIB.BASEBOARD_FAB2(SCH_1):SATA6G_P10_RX_C_DN
  C2L36    2      B  CAP_A       I39
  J8A2    B8  RXA2_DN  CONN36_G97614001_CP  I26

SATA6G_P10_RX_C_DP   @BASEBOARD_FAB2_LIB.BASEBOARD_FAB2(SCH_1):SATA6G_P10_RX_C_DP
  C2L35    2      B  CAP_A       I31
  J8A2    B7  RXA2_DP  CONN36_G97614001_CP  I26

SATA6G_P10_TX_C_DN   @BASEBOARD_FAB2_LIB.BASEBOARD_FAB2(SCH_1):SATA6G_P10_TX_C_DN
  C1L13    1      A  CAP_A       I14
  J8A2    D8  TXA2_DN  CONN36_G97614001_CP  I26

SATA6G_P10_TX_C_DP   @BASEBOARD_FAB2_LIB.BASEBOARD_FAB2(SCH_1):SATA6G_P10_TX_C_DP
  C1L12    1      A  CAP_A       I19
  J8A2    D7  TXA2_DP  CONN36_G97614001_CP  I26

SATA6G_P11_RX_C_DN   @BASEBOARD_FAB2_LIB.BASEBOARD_FAB2(SCH_1):SATA6G_P11_RX_C_DN
  C2L34    2      B  CAP_A       I41
  J8A2    A8  RXA3_DN  CONN36_G97614001_CP  I26

SATA6G_P11_RX_C_DP   @BASEBOARD_FAB2_LIB.BASEBOARD_FAB2(SCH_1):SATA6G_P11_RX_C_DP
  C2L33    2      B  CAP_A       I40
  J8A2    A7  RXA3_DP  CONN36_G97614001_CP  I26

SATA6G_P11_TX_C_DN   @BASEBOARD_FAB2_LIB.BASEBOARD_FAB2(SCH_1):SATA6G_P11_TX_C_DN
  C1L15    1      A  CAP_A       I18
  J8A2    C8  TXA3_DN  CONN36_G97614001_CP  I26

SATA6G_P11_TX_C_DP   @BASEBOARD_FAB2_LIB.BASEBOARD_FAB2(SCH_1):SATA6G_P11_TX_C_DP
  C1L14    1      A  CAP_A       I20
  J8A2    C7  TXA3_DP  CONN36_G97614001_CP  I26

SATA6G_P1_RX_C_DN   @BASEBOARD_FAB2_LIB.BASEBOARD_FAB2(SCH_1):SATA6G_P1_RX_C_DN
  C2L6     2      B  CAP_A       I166
  J8A1   1A5  RXA1_DN  CONN72_G97614002_A_CP  I163

SATA6G_P1_RX_C_DP   @BASEBOARD_FAB2_LIB.BASEBOARD_FAB2(SCH_1):SATA6G_P1_RX_C_DP
  C2L10    2      B  CAP_A       I173
  J8A1   1A4  RXA1_DP  CONN72_G97614002_A_CP  I163

SATA6G_P1_TX_C_DN   @BASEBOARD_FAB2_LIB.BASEBOARD_FAB2(SCH_1):SATA6G_P1_TX_C_DN
  C2L44    1      A  CAP_A       I228
  J8A1   1C5  TXA1_DN  CONN72_G97614002_A_CP  I163

SATA6G_P1_TX_C_DP   @BASEBOARD_FAB2_LIB.BASEBOARD_FAB2(SCH_1):SATA6G_P1_TX_C_DP
  C2L43    1      A  CAP_A       I222
  J8A1   1C4  TXA1_DP  CONN72_G97614002_A_CP  I163

SATA6G_P2_RX_C_DN   @BASEBOARD_FAB2_LIB.BASEBOARD_FAB2(SCH_1):SATA6G_P2_RX_C_DN
  C2L13    2      B  CAP_A       I165
  J8A1   1B8  RXA2_DN  CONN72_G97614002_A_CP  I163

SATA6G_P2_RX_C_DP   @BASEBOARD_FAB2_LIB.BASEBOARD_FAB2(SCH_1):SATA6G_P2_RX_C_DP
  C2L15    2      B  CAP_A       I191
  J8A1   1B7  RXA2_DP  CONN72_G97614002_A_CP  I163

SATA6G_P2_TX_C_DN   @BASEBOARD_FAB2_LIB.BASEBOARD_FAB2(SCH_1):SATA6G_P2_TX_C_DN
  C2L42    1      A  CAP_A       I233
  J8A1   1D8  TXA2_DN  CONN72_G97614002_A_CP  I163

SATA6G_P2_TX_C_DP   @BASEBOARD_FAB2_LIB.BASEBOARD_FAB2(SCH_1):SATA6G_P2_TX_C_DP
  C2L41    1      A  CAP_A       I242
  J8A1   1D7  TXA2_DP  CONN72_G97614002_A_CP  I163

SATA6G_P3_RX_C_DN   @BASEBOARD_FAB2_LIB.BASEBOARD_FAB2(SCH_1):SATA6G_P3_RX_C_DN
  C2L3     2      B  CAP_A       I194
  J8A1   1A8  RXA3_DN  CONN72_G97614002_A_CP  I163

SATA6G_P3_RX_C_DP   @BASEBOARD_FAB2_LIB.BASEBOARD_FAB2(SCH_1):SATA6G_P3_RX_C_DP
  C2L4     2      B  CAP_A       I192
  J8A1   1A7  RXA3_DP  CONN72_G97614002_A_CP  I163

SATA6G_P3_TX_C_DN   @BASEBOARD_FAB2_LIB.BASEBOARD_FAB2(SCH_1):SATA6G_P3_TX_C_DN
  C2L22    1      A  CAP_A       I234
  J8A1   1C8  TXA3_DN  CONN72_G97614002_A_CP  I163

SATA6G_P3_TX_C_DP   @BASEBOARD_FAB2_LIB.BASEBOARD_FAB2(SCH_1):SATA6G_P3_TX_C_DP
  C2L23    1      A  CAP_A       I241
  J8A1   1C7  TXA3_DP  CONN72_G97614002_A_CP  I163

SATA6G_P4_RX_C_DN   @BASEBOARD_FAB2_LIB.BASEBOARD_FAB2(SCH_1):SATA6G_P4_RX_C_DN
  C2L18    2      B  CAP_A       I197
  J8A1   2B5  RXB0_DN  CONN72_G97614002_A_CP  I163

SATA6G_P4_RX_C_DP   @BASEBOARD_FAB2_LIB.BASEBOARD_FAB2(SCH_1):SATA6G_P4_RX_C_DP
  C2L20    2      B  CAP_A       I195
  J8A1   2B4  RXB0_DP  CONN72_G97614002_A_CP  I163

SATA6G_P4_TX_C_DN   @BASEBOARD_FAB2_LIB.BASEBOARD_FAB2(SCH_1):SATA6G_P4_TX_C_DN
  C2L37    1      A  CAP_A       I238
  J8A1   2D5  TXB0_DN  CONN72_G97614002_A_CP  I163

SATA6G_P4_TX_C_DP   @BASEBOARD_FAB2_LIB.BASEBOARD_FAB2(SCH_1):SATA6G_P4_TX_C_DP
  C2L47    1      A  CAP_A       I239
  J8A1   2D4  TXB0_DP  CONN72_G97614002_A_CP  I163

SATA6G_P5_RX_C_DN   @BASEBOARD_FAB2_LIB.BASEBOARD_FAB2(SCH_1):SATA6G_P5_RX_C_DN
  C2L9     2      B  CAP_A       I207
  J8A1   2A5  RXB1_DN  CONN72_G97614002_A_CP  I163

SATA6G_P5_RX_C_DP   @BASEBOARD_FAB2_LIB.BASEBOARD_FAB2(SCH_1):SATA6G_P5_RX_C_DP
  C2L12    2      B  CAP_A       I196
  J8A1   2A4  RXB1_DP  CONN72_G97614002_A_CP  I163

SATA6G_P5_TX_C_DN   @BASEBOARD_FAB2_LIB.BASEBOARD_FAB2(SCH_1):SATA6G_P5_TX_C_DN
  C2L26    1      A  CAP_A       I255
  J8A1   2C5  TXB1_DN  CONN72_G97614002_A_CP  I163

SATA6G_P5_TX_C_DP   @BASEBOARD_FAB2_LIB.BASEBOARD_FAB2(SCH_1):SATA6G_P5_TX_C_DP
  C2L27    1      A  CAP_A       I240
  J8A1   2C4  TXB1_DP  CONN72_G97614002_A_CP  I163

SATA6G_P6_RX_C_DN   @BASEBOARD_FAB2_LIB.BASEBOARD_FAB2(SCH_1):SATA6G_P6_RX_C_DN
  C2L14    2      B  CAP_A       I208
  J8A1   2B8  RXB2_DN  CONN72_G97614002_A_CP  I163

SATA6G_P6_RX_C_DP   @BASEBOARD_FAB2_LIB.BASEBOARD_FAB2(SCH_1):SATA6G_P6_RX_C_DP
  C2L16    2      B  CAP_A       I205
  J8A1   2B7  RXB2_DP  CONN72_G97614002_A_CP  I163

SATA6G_P6_TX_C_DN   @BASEBOARD_FAB2_LIB.BASEBOARD_FAB2(SCH_1):SATA6G_P6_TX_C_DN
  C2L38    1      A  CAP_A       I256
  J8A1   2D8  TXB2_DN  CONN72_G97614002_A_CP  I163

SATA6G_P6_TX_C_DP   @BASEBOARD_FAB2_LIB.BASEBOARD_FAB2(SCH_1):SATA6G_P6_TX_C_DP
  C2L48    1      A  CAP_A       I257
  J8A1   2D7  TXB2_DP  CONN72_G97614002_A_CP  I163

SATA6G_P7_RX_C_DN   @BASEBOARD_FAB2_LIB.BASEBOARD_FAB2(SCH_1):SATA6G_P7_RX_C_DN
  C2L5     2      B  CAP_A       I209
  J8A1   2A8  RXB3_DN  CONN72_G97614002_A_CP  I163

SATA6G_P7_RX_C_DP   @BASEBOARD_FAB2_LIB.BASEBOARD_FAB2(SCH_1):SATA6G_P7_RX_C_DP
  C2L7     2      B  CAP_A       I206
  J8A1   2A7  RXB3_DP  CONN72_G97614002_A_CP  I163

SATA6G_P7_TX_C_DN   @BASEBOARD_FAB2_LIB.BASEBOARD_FAB2(SCH_1):SATA6G_P7_TX_C_DN
  C2L21    1      A  CAP_A       I259
  J8A1   2C8  TXB3_DN  CONN72_G97614002_A_CP  I163

SATA6G_P7_TX_C_DP   @BASEBOARD_FAB2_LIB.BASEBOARD_FAB2(SCH_1):SATA6G_P7_TX_C_DP
  C2L24    1      A  CAP_A       I258
  J8A1   2C7  TXB3_DP  CONN72_G97614002_A_CP  I163

SATA6G_P8_RX_C_DN   @BASEBOARD_FAB2_LIB.BASEBOARD_FAB2(SCH_1):SATA6G_P8_RX_C_DN
  C2L31    2      B  CAP_A       I29
  J8A2    B5  RXA0_DN  CONN36_G97614001_CP  I26

SATA6G_P8_RX_C_DP   @BASEBOARD_FAB2_LIB.BASEBOARD_FAB2(SCH_1):SATA6G_P8_RX_C_DP
  C2L30    2      B  CAP_A       I28
  J8A2    B4  RXA0_DP  CONN36_G97614001_CP  I26

SATA6G_P8_TX_C_DN   @BASEBOARD_FAB2_LIB.BASEBOARD_FAB2(SCH_1):SATA6G_P8_TX_C_DN
  C1L3     1      A  CAP_A        I8
  J8A2    D5  TXA0_DN  CONN36_G97614001_CP  I26

SATA6G_P8_TX_C_DP   @BASEBOARD_FAB2_LIB.BASEBOARD_FAB2(SCH_1):SATA6G_P8_TX_C_DP
  C1L2     1      A  CAP_A        I9
  J8A2    D4  TXA0_DP  CONN36_G97614001_CP  I26

SATA6G_P9_RX_C_DN   @BASEBOARD_FAB2_LIB.BASEBOARD_FAB2(SCH_1):SATA6G_P9_RX_C_DN
  C2L29    2      B  CAP_A       I32
  J8A2    A5  RXA1_DN  CONN36_G97614001_CP  I26

SATA6G_P9_RX_C_DP   @BASEBOARD_FAB2_LIB.BASEBOARD_FAB2(SCH_1):SATA6G_P9_RX_C_DP
  C2L28    2      B  CAP_A       I30
  J8A2    A4  RXA1_DP  CONN36_G97614001_CP  I26

SATA6G_P9_TX_C_DN   @BASEBOARD_FAB2_LIB.BASEBOARD_FAB2(SCH_1):SATA6G_P9_TX_C_DN
  C1L7     1      A  CAP_A       I12
  J8A2    C5  TXA1_DN  CONN36_G97614001_CP  I26

SATA6G_P9_TX_C_DP   @BASEBOARD_FAB2_LIB.BASEBOARD_FAB2(SCH_1):SATA6G_P9_TX_C_DP
  C1L6     1      A  CAP_A       I13
  J8A2    C4  TXA1_DP  CONN36_G97614001_CP  I26

SATA6G_PCH_PCIE_UP_SATA_RXN<0>   @BASEBOARD_FAB2_LIB.BASEBOARD_FAB2(SCH_1):SATA6G_PCH_PCIE_UP_SATA_RXN<0>
  C2L17    1      A  CAP_A       I174
  U7C1   AR61  PCIE12_UP0_SATA0_RXN  LBG_CORE_QAT_EXT_D  I220

SATA6G_PCH_PCIE_UP_SATA_RXN<1>   @BASEBOARD_FAB2_LIB.BASEBOARD_FAB2(SCH_1):SATA6G_PCH_PCIE_UP_SATA_RXN<1>
  C2L6     1      A  CAP_A       I166
  U7C1   AL66  PCIE13_UP1_SATA1_RXN  LBG_CORE_QAT_EXT_D  I220

SATA6G_PCH_PCIE_UP_SATA_RXN<2>   @BASEBOARD_FAB2_LIB.BASEBOARD_FAB2(SCH_1):SATA6G_PCH_PCIE_UP_SATA_RXN<2>
  C2L13    1      A  CAP_A       I165
  U7C1   AK65  PCIE14_UP2_SATA2_RXN  LBG_CORE_QAT_EXT_D  I220

SATA6G_PCH_PCIE_UP_SATA_RXN<3>   @BASEBOARD_FAB2_LIB.BASEBOARD_FAB2(SCH_1):SATA6G_PCH_PCIE_UP_SATA_RXN<3>
  C2L3     1      A  CAP_A       I194
  U7C1   AP63  PCIE15_UP3_SATA3_RXN  LBG_CORE_QAT_EXT_D  I220

SATA6G_PCH_PCIE_UP_SATA_RXN<4>   @BASEBOARD_FAB2_LIB.BASEBOARD_FAB2(SCH_1):SATA6G_PCH_PCIE_UP_SATA_RXN<4>
  C2L18    1      A  CAP_A       I197
  U7C1   AF65  PCIE16_UP4_SATA4_RXN  LBG_CORE_QAT_EXT_D  I220

SATA6G_PCH_PCIE_UP_SATA_RXN<5>   @BASEBOARD_FAB2_LIB.BASEBOARD_FAB2(SCH_1):SATA6G_PCH_PCIE_UP_SATA_RXN<5>
  C2L9     1      A  CAP_A       I207
  U7C1   AH61  PCIE17_UP5_SATA5_RXN  LBG_CORE_QAT_EXT_D  I220

SATA6G_PCH_PCIE_UP_SATA_RXN<6>   @BASEBOARD_FAB2_LIB.BASEBOARD_FAB2(SCH_1):SATA6G_PCH_PCIE_UP_SATA_RXN<6>
  C2L14    1      A  CAP_A       I208
  U7C1   AP59  PCIE18_UP6_SATA6_RXN  LBG_CORE_QAT_EXT_D  I220

SATA6G_PCH_PCIE_UP_SATA_RXN<7>   @BASEBOARD_FAB2_LIB.BASEBOARD_FAB2(SCH_1):SATA6G_PCH_PCIE_UP_SATA_RXN<7>
  C2L5     1      A  CAP_A       I209
  U7C1   AA61  PCIE19_UP7_SATA7_RXN  LBG_CORE_QAT_EXT_D  I220

SATA6G_PCH_PCIE_UP_SATA_RXP<0>   @BASEBOARD_FAB2_LIB.BASEBOARD_FAB2(SCH_1):SATA6G_PCH_PCIE_UP_SATA_RXP<0>
  C2L19    1      A  CAP_A       I172
  U7C1   AT63  PCIE12_UP0_SATA0_RXP  LBG_CORE_QAT_EXT_D  I220

SATA6G_PCH_PCIE_UP_SATA_RXP<1>   @BASEBOARD_FAB2_LIB.BASEBOARD_FAB2(SCH_1):SATA6G_PCH_PCIE_UP_SATA_RXP<1>
  C2L10    1      A  CAP_A       I173
  U7C1   AN65  PCIE13_UP1_SATA1_RXP  LBG_CORE_QAT_EXT_D  I220

SATA6G_PCH_PCIE_UP_SATA_RXP<2>   @BASEBOARD_FAB2_LIB.BASEBOARD_FAB2(SCH_1):SATA6G_PCH_PCIE_UP_SATA_RXP<2>
  C2L15    1      A  CAP_A       I191
  U7C1   AJ63  PCIE14_UP2_SATA2_RXP  LBG_CORE_QAT_EXT_D  I220

SATA6G_PCH_PCIE_UP_SATA_RXP<3>   @BASEBOARD_FAB2_LIB.BASEBOARD_FAB2(SCH_1):SATA6G_PCH_PCIE_UP_SATA_RXP<3>
  C2L4     1      A  CAP_A       I192
  U7C1   AL63  PCIE15_UP3_SATA3_RXP  LBG_CORE_QAT_EXT_D  I220

SATA6G_PCH_PCIE_UP_SATA_RXP<4>   @BASEBOARD_FAB2_LIB.BASEBOARD_FAB2(SCH_1):SATA6G_PCH_PCIE_UP_SATA_RXP<4>
  C2L20    1      A  CAP_A       I195
  U7C1   AH65  PCIE16_UP4_SATA4_RXP  LBG_CORE_QAT_EXT_D  I220

SATA6G_PCH_PCIE_UP_SATA_RXP<5>   @BASEBOARD_FAB2_LIB.BASEBOARD_FAB2(SCH_1):SATA6G_PCH_PCIE_UP_SATA_RXP<5>
  C2L12    1      A  CAP_A       I196
  U7C1   AG63  PCIE17_UP5_SATA5_RXP  LBG_CORE_QAT_EXT_D  I220

SATA6G_PCH_PCIE_UP_SATA_RXP<6>   @BASEBOARD_FAB2_LIB.BASEBOARD_FAB2(SCH_1):SATA6G_PCH_PCIE_UP_SATA_RXP<6>
  C2L16    1      A  CAP_A       I205
  U7C1   AN61  PCIE18_UP6_SATA6_RXP  LBG_CORE_QAT_EXT_D  I220

SATA6G_PCH_PCIE_UP_SATA_RXP<7>   @BASEBOARD_FAB2_LIB.BASEBOARD_FAB2(SCH_1):SATA6G_PCH_PCIE_UP_SATA_RXP<7>
  C2L7     1      A  CAP_A       I206
  U7C1   AD61  PCIE19_UP7_SATA7_RXP  LBG_CORE_QAT_EXT_D  I220

SATA6G_PCH_PCIE_UP_SATA_TXN<0>   @BASEBOARD_FAB2_LIB.BASEBOARD_FAB2(SCH_1):SATA6G_PCH_PCIE_UP_SATA_TXN<0>
  C2L40    2      B  CAP_A       I220
  U7C1   W69  PCIE12_UP0_SATA0_TXN  LBG_CORE_QAT_EXT_D  I220

SATA6G_PCH_PCIE_UP_SATA_TXN<1>   @BASEBOARD_FAB2_LIB.BASEBOARD_FAB2(SCH_1):SATA6G_PCH_PCIE_UP_SATA_TXN<1>
  C2L44    2      B  CAP_A       I228
  U7C1   V70  PCIE13_UP1_SATA1_TXN  LBG_CORE_QAT_EXT_D  I220

SATA6G_PCH_PCIE_UP_SATA_TXN<2>   @BASEBOARD_FAB2_LIB.BASEBOARD_FAB2(SCH_1):SATA6G_PCH_PCIE_UP_SATA_TXN<2>
  C2L42    2      B  CAP_A       I233
  U7C1   T69  PCIE14_UP2_SATA2_TXN  LBG_CORE_QAT_EXT_D  I220

SATA6G_PCH_PCIE_UP_SATA_TXN<3>   @BASEBOARD_FAB2_LIB.BASEBOARD_FAB2(SCH_1):SATA6G_PCH_PCIE_UP_SATA_TXN<3>
  C2L22    2      B  CAP_A       I234
  U7C1   R70  PCIE15_UP3_SATA3_TXN  LBG_CORE_QAT_EXT_D  I220

SATA6G_PCH_PCIE_UP_SATA_TXN<4>   @BASEBOARD_FAB2_LIB.BASEBOARD_FAB2(SCH_1):SATA6G_PCH_PCIE_UP_SATA_TXN<4>
  C2L37    2      B  CAP_A       I238
  U7C1   P69  PCIE16_UP4_SATA4_TXN  LBG_CORE_QAT_EXT_D  I220

SATA6G_PCH_PCIE_UP_SATA_TXN<5>   @BASEBOARD_FAB2_LIB.BASEBOARD_FAB2(SCH_1):SATA6G_PCH_PCIE_UP_SATA_TXN<5>
  C2L26    2      B  CAP_A       I255
  U7C1   N70  PCIE17_UP5_SATA5_TXN  LBG_CORE_QAT_EXT_D  I220

SATA6G_PCH_PCIE_UP_SATA_TXN<6>   @BASEBOARD_FAB2_LIB.BASEBOARD_FAB2(SCH_1):SATA6G_PCH_PCIE_UP_SATA_TXN<6>
  C2L38    2      B  CAP_A       I256
  U7C1   M69  PCIE18_UP6_SATA6_TXN  LBG_CORE_QAT_EXT_D  I220

SATA6G_PCH_PCIE_UP_SATA_TXN<7>   @BASEBOARD_FAB2_LIB.BASEBOARD_FAB2(SCH_1):SATA6G_PCH_PCIE_UP_SATA_TXN<7>
  C2L21    2      B  CAP_A       I259
  U7C1   L70  PCIE19_UP7_SATA7_TXN  LBG_CORE_QAT_EXT_D  I220

SATA6G_PCH_PCIE_UP_SATA_TXP<0>   @BASEBOARD_FAB2_LIB.BASEBOARD_FAB2(SCH_1):SATA6G_PCH_PCIE_UP_SATA_TXP<0>
  C2L39    2      B  CAP_A       I221
  U7C1   W71  PCIE12_UP0_SATA0_TXP  LBG_CORE_QAT_EXT_D  I220

SATA6G_PCH_PCIE_UP_SATA_TXP<1>   @BASEBOARD_FAB2_LIB.BASEBOARD_FAB2(SCH_1):SATA6G_PCH_PCIE_UP_SATA_TXP<1>
  C2L43    2      B  CAP_A       I222
  U7C1   V72  PCIE13_UP1_SATA1_TXP  LBG_CORE_QAT_EXT_D  I220

SATA6G_PCH_PCIE_UP_SATA_TXP<2>   @BASEBOARD_FAB2_LIB.BASEBOARD_FAB2(SCH_1):SATA6G_PCH_PCIE_UP_SATA_TXP<2>
  C2L41    2      B  CAP_A       I242
  U7C1   T71  PCIE14_UP2_SATA2_TXP  LBG_CORE_QAT_EXT_D  I220

SATA6G_PCH_PCIE_UP_SATA_TXP<3>   @BASEBOARD_FAB2_LIB.BASEBOARD_FAB2(SCH_1):SATA6G_PCH_PCIE_UP_SATA_TXP<3>
  C2L23    2      B  CAP_A       I241
  U7C1   R72  PCIE15_UP3_SATA3_TXP  LBG_CORE_QAT_EXT_D  I220

SATA6G_PCH_PCIE_UP_SATA_TXP<4>   @BASEBOARD_FAB2_LIB.BASEBOARD_FAB2(SCH_1):SATA6G_PCH_PCIE_UP_SATA_TXP<4>
  C2L47    2      B  CAP_A       I239
  U7C1   P71  PCIE16_UP4_SATA4_TXP  LBG_CORE_QAT_EXT_D  I220

SATA6G_PCH_PCIE_UP_SATA_TXP<5>   @BASEBOARD_FAB2_LIB.BASEBOARD_FAB2(SCH_1):SATA6G_PCH_PCIE_UP_SATA_TXP<5>
  C2L27    2      B  CAP_A       I240
  U7C1   N72  PCIE17_UP5_SATA5_TXP  LBG_CORE_QAT_EXT_D  I220

SATA6G_PCH_PCIE_UP_SATA_TXP<6>   @BASEBOARD_FAB2_LIB.BASEBOARD_FAB2(SCH_1):SATA6G_PCH_PCIE_UP_SATA_TXP<6>
  C2L48    2      B  CAP_A       I257
  U7C1   M71  PCIE18_UP6_SATA6_TXP  LBG_CORE_QAT_EXT_D  I220

SATA6G_PCH_PCIE_UP_SATA_TXP<7>   @BASEBOARD_FAB2_LIB.BASEBOARD_FAB2(SCH_1):SATA6G_PCH_PCIE_UP_SATA_TXP<7>
  C2L24    2      B  CAP_A       I258
  U7C1   L72  PCIE19_UP7_SATA7_TXP  LBG_CORE_QAT_EXT_D  I220

SATA6G_RX_DN<0>   @BASEBOARD_FAB2_LIB.BASEBOARD_FAB2(SCH_1):SATA6G_RX_DN<0>
  C2L31    1      A  CAP_A       I29
  U7C1   BA65  PCIE8_SSATA2_GBE_RXN  LBG_CORE_QAT_EXT_D  I220

SATA6G_RX_DN<1>   @BASEBOARD_FAB2_LIB.BASEBOARD_FAB2(SCH_1):SATA6G_RX_DN<1>
  C2L29    1      A  CAP_A       I32
  U7C1   AW65  PCIE9_SSATA3_RXN  LBG_CORE_QAT_EXT_D  I220

SATA6G_RX_DN<2>   @BASEBOARD_FAB2_LIB.BASEBOARD_FAB2(SCH_1):SATA6G_RX_DN<2>
  C2L36    1      A  CAP_A       I39
  U7C1   AV63  PCIE10_SSATA4_RXN  LBG_CORE_QAT_EXT_D  I220

SATA6G_RX_DN<3>   @BASEBOARD_FAB2_LIB.BASEBOARD_FAB2(SCH_1):SATA6G_RX_DN<3>
  C2L34    1      A  CAP_A       I41
  U7C1   AT66  PCIE11_SSATA5_GBE_RXN  LBG_CORE_QAT_EXT_D  I220

SATA6G_RX_DP<0>   @BASEBOARD_FAB2_LIB.BASEBOARD_FAB2(SCH_1):SATA6G_RX_DP<0>
  C2L30    1      A  CAP_A       I28
  U7C1   BD65  PCIE8_SSATA2_GBE_RXP  LBG_CORE_QAT_EXT_D  I220

SATA6G_RX_DP<1>   @BASEBOARD_FAB2_LIB.BASEBOARD_FAB2(SCH_1):SATA6G_RX_DP<1>
  C2L28    1      A  CAP_A       I30
  U7C1   AY66  PCIE9_SSATA3_RXP  LBG_CORE_QAT_EXT_D  I220

SATA6G_RX_DP<2>   @BASEBOARD_FAB2_LIB.BASEBOARD_FAB2(SCH_1):SATA6G_RX_DP<2>
  C2L35    1      A  CAP_A       I31
  U7C1   AU65  PCIE10_SSATA4_RXP  LBG_CORE_QAT_EXT_D  I220

SATA6G_RX_DP<3>   @BASEBOARD_FAB2_LIB.BASEBOARD_FAB2(SCH_1):SATA6G_RX_DP<3>
  C2L33    1      A  CAP_A       I40
  U7C1   AV66  PCIE11_SSATA5_GBE_RXP  LBG_CORE_QAT_EXT_D  I220

SATA6G_S0_RX_DN   @BASEBOARD_FAB2_LIB.BASEBOARD_FAB2(SCH_1):SATA6G_S0_RX_DN
  C8F15    1      A  CAP_A       I90
  U7C1   BB63  PCIE6_SSATA0_RXN  LBG_CORE_QAT_EXT_D  I220

SATA6G_S0_RX_DP   @BASEBOARD_FAB2_LIB.BASEBOARD_FAB2(SCH_1):SATA6G_S0_RX_DP
  C8F13    1      A  CAP_A       I99
  U7C1   BD61  PCIE6_SSATA0_RXP  LBG_CORE_QAT_EXT_D  I220

SATA6G_S0_TX_DN   @BASEBOARD_FAB2_LIB.BASEBOARD_FAB2(SCH_1):SATA6G_S0_TX_DN
  C8F11    1      A  CAP_A       I97
  U7C1   AJ70  PCIE6_SSATA0_TXN  LBG_CORE_QAT_EXT_D  I220

SATA6G_S0_TX_DP   @BASEBOARD_FAB2_LIB.BASEBOARD_FAB2(SCH_1):SATA6G_S0_TX_DP
  C8F6     1      A  CAP_A       I95
  U7C1   AJ72  PCIE6_SSATA0_TXP  LBG_CORE_QAT_EXT_D  I220

SATA6G_S1_RX_C_DN   @BASEBOARD_FAB2_LIB.BASEBOARD_FAB2(SCH_1):SATA6G_S1_RX_C_DN
  C2L50    1      A  CAP_A        I7
  J2M1     5  SATA_RXN  CONN7_E82125014_PIP_TH  I52
  J8A3     5  SATA_RXN  CONN7_E82125014_PIP_TH  I17

SATA6G_S1_RX_C_DP   @BASEBOARD_FAB2_LIB.BASEBOARD_FAB2(SCH_1):SATA6G_S1_RX_C_DP
  C2L49    1      A  CAP_A        I5
  J2M1     6  SATA_RXP  CONN7_E82125014_PIP_TH  I52
  J8A3     6  SATA_RXP  CONN7_E82125014_PIP_TH  I17

SATA6G_S1_RX_DN   @BASEBOARD_FAB2_LIB.BASEBOARD_FAB2(SCH_1):SATA6G_S1_RX_DN
  C2L50    2      B  CAP_A        I7
  U7C1   AY59  PCIE7_SSATA1_RXN  LBG_CORE_QAT_EXT_D  I220

SATA6G_S1_RX_DP   @BASEBOARD_FAB2_LIB.BASEBOARD_FAB2(SCH_1):SATA6G_S1_RX_DP
  C2L49    2      B  CAP_A        I5
  U7C1   BA61  PCIE7_SSATA1_RXP  LBG_CORE_QAT_EXT_D  I220

SATA6G_S1_TX_C_DN   @BASEBOARD_FAB2_LIB.BASEBOARD_FAB2(SCH_1):SATA6G_S1_TX_C_DN
  C2L51    1      A  CAP_A        I8
  J2M1     3  SATA_TXN  CONN7_E82125014_PIP_TH  I52
  J8A3     3  SATA_TXN  CONN7_E82125014_PIP_TH  I17

SATA6G_S1_TX_C_DP   @BASEBOARD_FAB2_LIB.BASEBOARD_FAB2(SCH_1):SATA6G_S1_TX_C_DP
  C2L52    1      A  CAP_A        I6
  J2M1     2  SATA_TXP  CONN7_E82125014_PIP_TH  I52
  J8A3     2  SATA_TXP  CONN7_E82125014_PIP_TH  I17

SATA6G_S1_TX_DN   @BASEBOARD_FAB2_LIB.BASEBOARD_FAB2(SCH_1):SATA6G_S1_TX_DN
  C2L51    2      B  CAP_A        I8
  U7C1   AH69  PCIE7_SSATA1_TXN  LBG_CORE_QAT_EXT_D  I220

SATA6G_S1_TX_DP   @BASEBOARD_FAB2_LIB.BASEBOARD_FAB2(SCH_1):SATA6G_S1_TX_DP
  C2L52    2      B  CAP_A        I6
  U7C1   AH71  PCIE7_SSATA1_TXP  LBG_CORE_QAT_EXT_D  I220

SATA6G_TX_DN<0>   @BASEBOARD_FAB2_LIB.BASEBOARD_FAB2(SCH_1):SATA6G_TX_DN<0>
  C1L3     2      B  CAP_A        I8
  U7C1   AF70  PCIE8_SSATA2_GBE_TXN  LBG_CORE_QAT_EXT_D  I220

SATA6G_TX_DN<1>   @BASEBOARD_FAB2_LIB.BASEBOARD_FAB2(SCH_1):SATA6G_TX_DN<1>
  C1L7     2      B  CAP_A       I12
  U7C1   AE69  PCIE9_SSATA3_TXN  LBG_CORE_QAT_EXT_D  I220

SATA6G_TX_DN<2>   @BASEBOARD_FAB2_LIB.BASEBOARD_FAB2(SCH_1):SATA6G_TX_DN<2>
  C1L13    2      B  CAP_A       I14
  U7C1   AD70  PCIE10_SSATA4_TXN  LBG_CORE_QAT_EXT_D  I220

SATA6G_TX_DN<3>   @BASEBOARD_FAB2_LIB.BASEBOARD_FAB2(SCH_1):SATA6G_TX_DN<3>
  C1L15    2      B  CAP_A       I18
  U7C1   AC69  PCIE11_SSATA5_GBE_TXN  LBG_CORE_QAT_EXT_D  I220

SATA6G_TX_DP<0>   @BASEBOARD_FAB2_LIB.BASEBOARD_FAB2(SCH_1):SATA6G_TX_DP<0>
  C1L2     2      B  CAP_A        I9
  U7C1   AF72  PCIE8_SSATA2_GBE_TXP  LBG_CORE_QAT_EXT_D  I220

SATA6G_TX_DP<1>   @BASEBOARD_FAB2_LIB.BASEBOARD_FAB2(SCH_1):SATA6G_TX_DP<1>
  C1L6     2      B  CAP_A       I13
  U7C1   AE71  PCIE9_SSATA3_TXP  LBG_CORE_QAT_EXT_D  I220

SATA6G_TX_DP<2>   @BASEBOARD_FAB2_LIB.BASEBOARD_FAB2(SCH_1):SATA6G_TX_DP<2>
  C1L12    2      B  CAP_A       I19
  U7C1   AD72  PCIE10_SSATA4_TXP  LBG_CORE_QAT_EXT_D  I220

SATA6G_TX_DP<3>   @BASEBOARD_FAB2_LIB.BASEBOARD_FAB2(SCH_1):SATA6G_TX_DP<3>
  C1L14    2      B  CAP_A       I20
  U7C1   AC71  PCIE11_SSATA5_GBE_TXP  LBG_CORE_QAT_EXT_D  I220

SGPIO_BMC_CLK   @BASEBOARD_FAB2_LIB.BASEBOARD_FAB2(SCH_1):SGPIO_BMC_CLK
  R1U14    2      B  RES         I548
  U8D7    J1  PL7C_PCLKT4_0  LCMXO2_A_256BGA  I179

SGPIO_BMC_CLK_R   @BASEBOARD_FAB2_LIB.BASEBOARD_FAB2(SCH_1):SGPIO_BMC_CLK_R
  R1U14    1      A  RES         I548
  U9F4    J5  GPIOJ0_SGPMCK  AST1250_BGA  I347

SGPIO_BMC_DIN   @BASEBOARD_FAB2_LIB.BASEBOARD_FAB2(SCH_1):SGPIO_BMC_DIN
  R2R6     2      B  RES         I166
  U9F4    J3  GPIOJ3_SGPMI  AST1250_BGA  I347

SGPIO_BMC_DIN_R   @BASEBOARD_FAB2_LIB.BASEBOARD_FAB2(SCH_1):SGPIO_BMC_DIN_R
  R2R6     1      A  RES         I166
  U8D7    F8  PT18A  LCMXO2_A_256BGA  I59

SGPIO_BMC_DOUT   @BASEBOARD_FAB2_LIB.BASEBOARD_FAB2(SCH_1):SGPIO_BMC_DOUT
  R1U13    2      B  RES         I546
  U8D7    J2   PL9A  LCMXO2_A_256BGA  I179

SGPIO_BMC_DOUT_R   @BASEBOARD_FAB2_LIB.BASEBOARD_FAB2(SCH_1):SGPIO_BMC_DOUT_R
  R1U13    1      A  RES         I546
  U9F4    K5  GPIOJ2_SGPMO  AST1250_BGA  I347

SGPIO_BMC_LD_N   @BASEBOARD_FAB2_LIB.BASEBOARD_FAB2(SCH_1):SGPIO_BMC_LD_N
  R1U12    2      B  RES         I547
  U8D7    K4  PL11C  LCMXO2_A_256BGA  I179

SGPIO_BMC_LD_R_N   @BASEBOARD_FAB2_LIB.BASEBOARD_FAB2(SCH_1):SGPIO_BMC_LD_R_N
  R1U12    1      A  RES         I547
  U9F4    J4  GPIOJ1_SGPMLD  AST1250_BGA  I347

SGPIO_PCH_SATA_CLOCK   @BASEBOARD_FAB2_LIB.BASEBOARD_FAB2(SCH_1):SGPIO_PCH_SATA_CLOCK
  R2N31    1      A  RES         I11
  U7C1   AL7  GPP_F10_SATA_SCLOCK  LBG_CORE_QAT_EXT_D  I147

SGPIO_PCH_SATA_CLOCK_R   @BASEBOARD_FAB2_LIB.BASEBOARD_FAB2(SCH_1):SGPIO_PCH_SATA_CLOCK_R
  J8A1   1A2  SIDEBANDA_0  CONN72_G97614002_A_CP  I163
  R2L11    2      B  RES         I13
  R2N31    2      B  RES         I11

SGPIO_PCH_SATA_DOUT0   @BASEBOARD_FAB2_LIB.BASEBOARD_FAB2(SCH_1):SGPIO_PCH_SATA_DOUT0
  R8D19    1      A  RES          I8
  U7C1   AP11  GPP_F13_SATA_SDATAOUT0  LBG_CORE_QAT_EXT_D  I147

SGPIO_PCH_SATA_DOUT0_R   @BASEBOARD_FAB2_LIB.BASEBOARD_FAB2(SCH_1):SGPIO_PCH_SATA_DOUT0_R
  J8A1   1C1  SIDEBANDA_4  CONN72_G97614002_A_CP  I163
  R2L15    2      B  RES         I12
  R8D19    2      B  RES          I8

SGPIO_PCH_SATA_LOAD   @BASEBOARD_FAB2_LIB.BASEBOARD_FAB2(SCH_1):SGPIO_PCH_SATA_LOAD
  R8D20    1      A  RES          I1
  U7C1   AR9  GPP_F11_SATA_SLOAD  LBG_CORE_QAT_EXT_D  I147

SGPIO_PCH_SATA_LOAD_R   @BASEBOARD_FAB2_LIB.BASEBOARD_FAB2(SCH_1):SGPIO_PCH_SATA_LOAD_R
  J8A1   1B2  SIDEBANDA_1  CONN72_G97614002_A_CP  I163
  R2L12    2      B  RES          I2
  R8D20    2      B  RES          I1

SGPIO_PCH_SSATA_CLOCK   @BASEBOARD_FAB2_LIB.BASEBOARD_FAB2(SCH_1):SGPIO_PCH_SSATA_CLOCK
  R2N22    1      A  RES         I23
  U7C1   AP18  GPP_F22_SSATA_SCLOCK  LBG_CORE_QAT_EXT_D  I147

SGPIO_PCH_SSATA_CLOCK_R   @BASEBOARD_FAB2_LIB.BASEBOARD_FAB2(SCH_1):SGPIO_PCH_SSATA_CLOCK_R
  J8A2    A2  SIDEBAND0  CONN36_G97614001_CP  I26
  R2L6     2      B  RES         I17
  R2N22    2      B  RES         I23

SGPIO_PCH_SSATA_DOUT0   @BASEBOARD_FAB2_LIB.BASEBOARD_FAB2(SCH_1):SGPIO_PCH_SSATA_DOUT0
  R8B29    1      A  RES         I21
  U7C1   BW43  GPP_D15_SSATA_SDATAOUT0  LBG_CORE_QAT_EXT_D  I115

SGPIO_PCH_SSATA_DOUT0_R   @BASEBOARD_FAB2_LIB.BASEBOARD_FAB2(SCH_1):SGPIO_PCH_SSATA_DOUT0_R
  J8A2    C1  SIDEBAND4  CONN36_G97614001_CP  I26
  R2L4     2      B  RES         I18
  R8B29    2      B  RES         I21

SGPIO_PCH_SSATA_LOAD   @BASEBOARD_FAB2_LIB.BASEBOARD_FAB2(SCH_1):SGPIO_PCH_SSATA_LOAD
  R2N19    1      A  RES         I22
  U7C1   AU17  GPP_F23_SSATA_SLOAD  LBG_CORE_QAT_EXT_D  I147

SGPIO_PCH_SSATA_LOAD_R   @BASEBOARD_FAB2_LIB.BASEBOARD_FAB2(SCH_1):SGPIO_PCH_SSATA_LOAD_R
  J8A2    B2  SIDEBAND1  CONN36_G97614001_CP  I26
  R2L5     2      B  RES         I20
  R2N19    2      B  RES         I22

SMB_3V3SB_HSC_SCL_R   @BASEBOARD_FAB2_LIB.BASEBOARD_FAB2(SCH_1):SMB_3V3SB_HSC_SCL_R
  EU1D2   16    SCL  ADM1278_SM  I10
  R1D24    2      B  RES         I27

SMB_3V3SB_HSC_SDA_R   @BASEBOARD_FAB2_LIB.BASEBOARD_FAB2(SCH_1):SMB_3V3SB_HSC_SDA_R
  EU1D2   15    SDA  ADM1278_SM  I10
  R1D25    2      B  RES         I28

SMB_BMC_PMBUS_STBY_LVC3_SCL   @BASEBOARD_FAB2_LIB.BASEBOARD_FAB2(SCH_1):SMB_BMC_PMBUS_STBY_LVC3_SCL
  J1F1    C6   IOC6  CONN76_H22707001_THMT1  I111
  J1F3     7    IO7  CONN8_H62179001_PIP  I189
  R1D24    1      A  RES         I27
  R2T54    2      B  RES         I84
  R2T56    2      B  RES         I160
  R2U1     2      B  RES         I218

SMB_BMC_PMBUS_STBY_LVC3_SCL_R   @BASEBOARD_FAB2_LIB.BASEBOARD_FAB2(SCH_1):SMB_BMC_PMBUS_STBY_LVC3_SCL_R
  R2U1     1      A  RES         I218
  U9F4    G5  GPIOK6_SCL8  AST1250_BGA  I347

SMB_BMC_PMBUS_STBY_LVC3_SDA   @BASEBOARD_FAB2_LIB.BASEBOARD_FAB2(SCH_1):SMB_BMC_PMBUS_STBY_LVC3_SDA
  J1F1    B6   IOB6  CONN76_H22707001_THMT1  I111
  J1F3     6    IO6  CONN8_H62179001_PIP  I189
  R1D25    1      A  RES         I28
  R2T49    2      B  RES         I219
  R2T53    2      B  RES         I83
  R2T55    2      B  RES         I116

SMB_BMC_PMBUS_STBY_LVC3_SDA_R   @BASEBOARD_FAB2_LIB.BASEBOARD_FAB2(SCH_1):SMB_BMC_PMBUS_STBY_LVC3_SDA_R
  R2T49    1      A  RES         I219
  U9F4    F3  GPIOK7_SDA8  AST1250_BGA  I347

SMB_CPU1_PE_HP_GTL_R_SCL   @BASEBOARD_FAB2_LIB.BASEBOARD_FAB2(SCH_1):SMB_CPU1_PE_HP_GTL_R_SCL
  R6N8     2      B  RES          I2
  R9M19    2      B  RES          I7
  U1B2     2   SCLA  PCA9517_SM   I1

SMB_CPU1_PE_HP_GTL_R_SDA   @BASEBOARD_FAB2_LIB.BASEBOARD_FAB2(SCH_1):SMB_CPU1_PE_HP_GTL_R_SDA
  R6N9     2      B  RES          I3
  R9M18    2      B  RES          I6
  U1B2     3   SDAA  PCA9517_SM   I1

SMB_CPU1_PE_HP_GTL_SCL   @BASEBOARD_FAB2_LIB.BASEBOARD_FAB2(SCH_1):SMB_CPU1_PE_HP_GTL_SCL
  R6N8     1      A  RES          I2
  U2D1   AM19  PE_HP_SCL  SKX_EXT_B_BGA1  I172

SMB_CPU1_PE_HP_GTL_SDA   @BASEBOARD_FAB2_LIB.BASEBOARD_FAB2(SCH_1):SMB_CPU1_PE_HP_GTL_SDA
  R6N9     1      A  RES          I3
  U2D1   AL18  PE_HP_SDA  SKX_EXT_B_BGA1  I172

SMB_DDR_ABC_SCL_G   @BASEBOARD_FAB2_LIB.BASEBOARD_FAB2(SCH_1):SMB_DDR_ABC_SCL_G
  R4T3     2      B  RES         I83
  R4T5     2      B  RES         I19
  U6F1     2   SCLA  PCA9617_SSOP  I15

SMB_DDR_ABC_SCL_G_R   @BASEBOARD_FAB2_LIB.BASEBOARD_FAB2(SCH_1):SMB_DDR_ABC_SCL_G_R
  R4T3     1      A  RES         I83
  U5D1   AJ18  DDR012_SPDSCL  SKX_EXT_B_BGA1  I259

SMB_DDR_ABC_SDA_G   @BASEBOARD_FAB2_LIB.BASEBOARD_FAB2(SCH_1):SMB_DDR_ABC_SDA_G
  R4T4     2      B  RES         I20
  R4T6     2      B  RES         I17
  U6F1     3   SDAA  PCA9617_SSOP  I15

SMB_DDR_ABC_SDA_G_R   @BASEBOARD_FAB2_LIB.BASEBOARD_FAB2(SCH_1):SMB_DDR_ABC_SDA_G_R
  R4T4     1      A  RES         I20
  U5D1   AF17  DDR012_SPDSDA  SKX_EXT_B_BGA1  I259

SMB_DDR_ABC_VPP_SCL   @BASEBOARD_FAB2_LIB.BASEBOARD_FAB2(SCH_1):SMB_DDR_ABC_VPP_SCL
  J4G1   141    SCL  SCONN288_H44441004_PIP   I1
  J4G2   141    SCL  SCONN288_H44441004_PIP  I111
  J4G3   141    SCL  SCONN288_H44441004_PIP  I111
  J6T1   141    SCL  SCONN288_H44441003_PIP  I13
  J6U1   141    SCL  SCONN288_H44441003_PIP  I14
  J6U2   141    SCL  SCONN288_H44441003_PIP  I111
  R4T9     2      B  RES          I9

SMB_DDR_ABC_VPP_SCL_R   @BASEBOARD_FAB2_LIB.BASEBOARD_FAB2(SCH_1):SMB_DDR_ABC_VPP_SCL_R
  R4T7     2      B  RES         I13
  R4T9     1      A  RES          I9
  U6F1     7   SCLB  PCA9617_SSOP  I15

SMB_DDR_ABC_VPP_SDA   @BASEBOARD_FAB2_LIB.BASEBOARD_FAB2(SCH_1):SMB_DDR_ABC_VPP_SDA
  J4G1   285    SDA  SCONN288_H44441004_PIP   I1
  J4G2   285    SDA  SCONN288_H44441004_PIP  I111
  J4G3   285    SDA  SCONN288_H44441004_PIP  I111
  J6T1   285    SDA  SCONN288_H44441003_PIP  I13
  J6U1   285    SDA  SCONN288_H44441003_PIP  I14
  J6U2   285    SDA  SCONN288_H44441003_PIP  I111
  R4T10    2      B  RES         I10

SMB_DDR_ABC_VPP_SDA_R   @BASEBOARD_FAB2_LIB.BASEBOARD_FAB2(SCH_1):SMB_DDR_ABC_VPP_SDA_R
  R4T8     2      B  RES         I11
  R4T10    1      A  RES         I10
  U6F1     6   SDAB  PCA9617_SSOP  I15

SMB_DDR_DEF_SCL_G   @BASEBOARD_FAB2_LIB.BASEBOARD_FAB2(SCH_1):SMB_DDR_DEF_SCL_G
  R3P60    2      B  RES         I67
  R3R7     2      B  RES         I88
  U7E1     2   SCLA  PCA9617_SSOP  I61

SMB_DDR_DEF_SCL_G_R   @BASEBOARD_FAB2_LIB.BASEBOARD_FAB2(SCH_1):SMB_DDR_DEF_SCL_G_R
  R3R7     1      A  RES         I88
  U5D1   AE18  DDR345_SPDSCL  SKX_EXT_B_BGA1  I259

SMB_DDR_DEF_SDA_G   @BASEBOARD_FAB2_LIB.BASEBOARD_FAB2(SCH_1):SMB_DDR_DEF_SDA_G
  R3R13    2      B  RES         I65
  R3R14    2      B  RES         I110
  U7E1     3   SDAA  PCA9617_SSOP  I61

SMB_DDR_DEF_SDA_G_R   @BASEBOARD_FAB2_LIB.BASEBOARD_FAB2(SCH_1):SMB_DDR_DEF_SDA_G_R
  R3R14    1      A  RES         I110
  U5D1   AD17  DDR345_SPDSDA  SKX_EXT_B_BGA1  I259

SMB_DDR_DEF_VPP_SCL   @BASEBOARD_FAB2_LIB.BASEBOARD_FAB2(SCH_1):SMB_DDR_DEF_VPP_SCL
  J4A1   141    SCL  SCONN288_H44441004_PIP  I111
  J4A2   141    SCL  SCONN288_H44441004_PIP  I111
  J4B1   141    SCL  SCONN288_H44441004_PIP  I111
  J6L1   141    SCL  SCONN288_H44441003_PIP  I111
  J6L2   141    SCL  SCONN288_H44441003_PIP  I12
  J6M1   141    SCL  SCONN288_H44441003_PIP  I158
  R3R8     2      B  RES         I35

SMB_DDR_DEF_VPP_SCL_R   @BASEBOARD_FAB2_LIB.BASEBOARD_FAB2(SCH_1):SMB_DDR_DEF_VPP_SCL_R
  R3R5     2      B  RES         I103
  R3R8     1      A  RES         I35
  U7E1     7   SCLB  PCA9617_SSOP  I61

SMB_DDR_DEF_VPP_SDA   @BASEBOARD_FAB2_LIB.BASEBOARD_FAB2(SCH_1):SMB_DDR_DEF_VPP_SDA
  J4A1   285    SDA  SCONN288_H44441004_PIP  I111
  J4A2   285    SDA  SCONN288_H44441004_PIP  I111
  J4B1   285    SDA  SCONN288_H44441004_PIP  I111
  J6L1   285    SDA  SCONN288_H44441003_PIP  I111
  J6L2   285    SDA  SCONN288_H44441003_PIP  I12
  J6M1   285    SDA  SCONN288_H44441003_PIP  I158
  R3R9     2      B  RES         I34

SMB_DDR_DEF_VPP_SDA_R   @BASEBOARD_FAB2_LIB.BASEBOARD_FAB2(SCH_1):SMB_DDR_DEF_VPP_SDA_R
  R3R9     1      A  RES         I34
  R3R12    2      B  RES         I101
  U7E1     6   SDAB  PCA9617_SSOP  I61

SMB_DDR_GHJ_SCL_G   @BASEBOARD_FAB2_LIB.BASEBOARD_FAB2(SCH_1):SMB_DDR_GHJ_SCL_G
  R6T2     2      B  RES         I72
  R6T3     2      B  RES         I92
  U4G1     2   SCLA  PCA9617_SSOP  I63

SMB_DDR_GHJ_SCL_G_R   @BASEBOARD_FAB2_LIB.BASEBOARD_FAB2(SCH_1):SMB_DDR_GHJ_SCL_G_R
  R6T3     1      A  RES         I92
  U2D1   AJ18  DDR012_SPDSCL  SKX_EXT_B_BGA1  I172

SMB_DDR_GHJ_SDA_G   @BASEBOARD_FAB2_LIB.BASEBOARD_FAB2(SCH_1):SMB_DDR_GHJ_SDA_G
  R6T1     2      B  RES         I70
  R6T4     2      B  RES         I111
  U4G1     3   SDAA  PCA9617_SSOP  I63

SMB_DDR_GHJ_SDA_G_R   @BASEBOARD_FAB2_LIB.BASEBOARD_FAB2(SCH_1):SMB_DDR_GHJ_SDA_G_R
  R6T4     1      A  RES         I111
  U2D1   AF17  DDR012_SPDSDA  SKX_EXT_B_BGA1  I172

SMB_DDR_GHJ_VPP_SCL   @BASEBOARD_FAB2_LIB.BASEBOARD_FAB2(SCH_1):SMB_DDR_GHJ_VPP_SCL
  J1G1   141    SCL  SCONN288_H44441004_PIP  I111
  J1G2   141    SCL  SCONN288_H44441004_PIP  I111
  J1G3   141    SCL  SCONN288_H44441004_PIP  I186
  J9T1   141    SCL  SCONN288_H44441003_PIP  I13
  J9U1   141    SCL  SCONN288_H44441003_PIP  I24
  J9U2   141    SCL  SCONN288_H44441003_PIP  I187
  R6U13    2      B  RES         I42

SMB_DDR_GHJ_VPP_SCL_R   @BASEBOARD_FAB2_LIB.BASEBOARD_FAB2(SCH_1):SMB_DDR_GHJ_VPP_SCL_R
  R6U13    1      A  RES         I42
  R6U17    2      B  RES         I106
  U4G1     7   SCLB  PCA9617_SSOP  I63

SMB_DDR_GHJ_VPP_SDA   @BASEBOARD_FAB2_LIB.BASEBOARD_FAB2(SCH_1):SMB_DDR_GHJ_VPP_SDA
  J1G1   285    SDA  SCONN288_H44441004_PIP  I111
  J1G2   285    SDA  SCONN288_H44441004_PIP  I111
  J1G3   285    SDA  SCONN288_H44441004_PIP  I186
  J9T1   285    SDA  SCONN288_H44441003_PIP  I13
  J9U1   285    SDA  SCONN288_H44441003_PIP  I24
  J9U2   285    SDA  SCONN288_H44441003_PIP  I187
  R6U14    2      B  RES         I43

SMB_DDR_GHJ_VPP_SDA_R   @BASEBOARD_FAB2_LIB.BASEBOARD_FAB2(SCH_1):SMB_DDR_GHJ_VPP_SDA_R
  R6U14    1      A  RES         I43
  R6U18    2      B  RES         I104
  U4G1     6   SDAB  PCA9617_SSOP  I63

SMB_DDR_KLM_SCL_G   @BASEBOARD_FAB2_LIB.BASEBOARD_FAB2(SCH_1):SMB_DDR_KLM_SCL_G
  R7M2     2      B  RES         I79
  R7M3     2      B  RES         I98
  U3B1     2   SCLA  PCA9617_SSOP  I75

SMB_DDR_KLM_SCL_G_R   @BASEBOARD_FAB2_LIB.BASEBOARD_FAB2(SCH_1):SMB_DDR_KLM_SCL_G_R
  R7M3     1      A  RES         I98
  U2D1   AE18  DDR345_SPDSCL  SKX_EXT_B_BGA1  I172

SMB_DDR_KLM_SDA_G   @BASEBOARD_FAB2_LIB.BASEBOARD_FAB2(SCH_1):SMB_DDR_KLM_SDA_G
  R7M7     2      B  RES         I77
  R7M8     2      B  RES         I112
  U3B1     3   SDAA  PCA9617_SSOP  I75

SMB_DDR_KLM_SDA_G_R   @BASEBOARD_FAB2_LIB.BASEBOARD_FAB2(SCH_1):SMB_DDR_KLM_SDA_G_R
  R7M8     1      A  RES         I112
  U2D1   AD17  DDR345_SPDSDA  SKX_EXT_B_BGA1  I172

SMB_DDR_KLM_VPP_SCL   @BASEBOARD_FAB2_LIB.BASEBOARD_FAB2(SCH_1):SMB_DDR_KLM_VPP_SCL
  J1A1   141    SCL  SCONN288_H44441004_PIP  I186
  J1A2   141    SCL  SCONN288_H44441004_PIP  I111
  J1B1   141    SCL  SCONN288_H44441004_PIP  I111
  J9L1   141    SCL  SCONN288_H44441003_PIP  I111
  J9L2   141    SCL  SCONN288_H44441003_PIP  I12
  J9M1   141    SCL  SCONN288_H44441003_PIP  I14
  R7M4     2      B  RES         I56

SMB_DDR_KLM_VPP_SCL_R   @BASEBOARD_FAB2_LIB.BASEBOARD_FAB2(SCH_1):SMB_DDR_KLM_VPP_SCL_R
  R7M1     2      B  RES         I109
  R7M4     1      A  RES         I56
  U3B1     7   SCLB  PCA9617_SSOP  I75

SMB_DDR_KLM_VPP_SDA   @BASEBOARD_FAB2_LIB.BASEBOARD_FAB2(SCH_1):SMB_DDR_KLM_VPP_SDA
  J1A1   285    SDA  SCONN288_H44441004_PIP  I186
  J1A2   285    SDA  SCONN288_H44441004_PIP  I111
  J1B1   285    SDA  SCONN288_H44441004_PIP  I111
  J9L1   285    SDA  SCONN288_H44441003_PIP  I111
  J9L2   285    SDA  SCONN288_H44441003_PIP  I12
  J9M1   285    SDA  SCONN288_H44441003_PIP  I14
  R7M5     2      B  RES         I55

SMB_DDR_KLM_VPP_SDA_R   @BASEBOARD_FAB2_LIB.BASEBOARD_FAB2(SCH_1):SMB_DDR_KLM_VPP_SDA_R
  R7M5     1      A  RES         I55
  R7M6     2      B  RES         I107
  U3B1     6   SDAB  PCA9617_SSOP  I75

SMB_HFI0_CPU0_LVC2_SCL   @BASEBOARD_FAB2_LIB.BASEBOARD_FAB2(SCH_1):SMB_HFI0_CPU0_LVC2_SCL
  J8B1     2    IO2  SCONN24_H46321001_SM   I1
  R8B6     2      B  RES         I37
  U5D1   BN22  CD_HFI0_I2CCLK  SKX_EXT_B_BGA1  I61

SMB_HFI0_CPU0_LVC2_SDA   @BASEBOARD_FAB2_LIB.BASEBOARD_FAB2(SCH_1):SMB_HFI0_CPU0_LVC2_SDA
  J8B1     4    IO4  SCONN24_H46321001_SM   I1
  R8B7     2      B  RES         I36
  U5D1   BP23  CD_HFI0_I2CDAT  SKX_EXT_B_BGA1  I61

SMB_HFI1_CPU0_LVC2_SCL   @BASEBOARD_FAB2_LIB.BASEBOARD_FAB2(SCH_1):SMB_HFI1_CPU0_LVC2_SCL
  J8B1    10   IO10  SCONN24_H46321001_SM   I1
  R8B11    2      B  RES         I35
  U5D1   BJ22  CD_HFI1_I2CCLK  SKX_EXT_B_BGA1  I61

SMB_HFI1_CPU0_LVC2_SDA   @BASEBOARD_FAB2_LIB.BASEBOARD_FAB2(SCH_1):SMB_HFI1_CPU0_LVC2_SDA
  J8B1    12   IO12  SCONN24_H46321001_SM   I1
  R8B13    2      B  RES         I34
  U5D1   BH23  CD_HFI1_I2CDAT  SKX_EXT_B_BGA1  I61

SMB_HOST_STBY_LVC3_SCL   @BASEBOARD_FAB2_LIB.BASEBOARD_FAB2(SCH_1):SMB_HOST_STBY_LVC3_SCL
  EU8F2   38  SMBCLK  ICS9FGP204_MLFP  I34
  J8C1     3    IO3  CONN3_C95678002_PIP  I285
  J9A3    53   IO53  SCONN60_C21100002  I26
  R2U34    2      B  RES         I230
  R4D37    1      A  RES         I87
  R8C14    2      B  RES         I168
  R8C15    2      B  RES         I92

SMB_HOST_STBY_LVC3_SCL_R   @BASEBOARD_FAB2_LIB.BASEBOARD_FAB2(SCH_1):SMB_HOST_STBY_LVC3_SCL_R
  R2U34    1      A  RES         I230
  U9F4    B1  GPIOQ2_SCL4  AST1250_BGA  I347

SMB_HOST_STBY_LVC3_SCL_R1   @BASEBOARD_FAB2_LIB.BASEBOARD_FAB2(SCH_1):SMB_HOST_STBY_LVC3_SCL_R1
  R8C14    1      A  RES         I168
  U7C1   BW28  GPP_C0_SMBCLK  LBG_CORE_QAT_EXT_D  I115

SMB_HOST_STBY_LVC3_SCL_R2   @BASEBOARD_FAB2_LIB.BASEBOARD_FAB2(SCH_1):SMB_HOST_STBY_LVC3_SCL_R2
  EU4D2   13    SCL  NB3W1200L_LCC   I1
  R4D37    2      B  RES         I87

SMB_HOST_STBY_LVC3_SDA   @BASEBOARD_FAB2_LIB.BASEBOARD_FAB2(SCH_1):SMB_HOST_STBY_LVC3_SDA
  EU8F2   39  SMBDAT  ICS9FGP204_MLFP  I34
  J8C1     1    IO1  CONN3_C95678002_PIP  I285
  J9A3    51   IO51  SCONN60_C21100002  I26
  R2U33    2      B  RES         I231
  R4D36    1      A  RES         I82
  R8C16    2      B  RES         I91
  R8C20    2      B  RES         I167

SMB_HOST_STBY_LVC3_SDA_R   @BASEBOARD_FAB2_LIB.BASEBOARD_FAB2(SCH_1):SMB_HOST_STBY_LVC3_SDA_R
  R2U33    1      A  RES         I231
  U9F4    F5  GPIOQ3_SDA4  AST1250_BGA  I347

SMB_HOST_STBY_LVC3_SDA_R1   @BASEBOARD_FAB2_LIB.BASEBOARD_FAB2(SCH_1):SMB_HOST_STBY_LVC3_SDA_R1
  R8C20    1      A  RES         I167
  U7C1   BV27  GPP_C1_SMBDATA  LBG_CORE_QAT_EXT_D  I115

SMB_HOST_STBY_LVC3_SDA_R2   @BASEBOARD_FAB2_LIB.BASEBOARD_FAB2(SCH_1):SMB_HOST_STBY_LVC3_SDA_R2
  EU4D2   12    SDA  NB3W1200L_LCC   I1
  R4D36    2      B  RES         I82

SMB_LAN_STBY_LVC3_SCL   @BASEBOARD_FAB2_LIB.BASEBOARD_FAB2(SCH_1):SMB_LAN_STBY_LVC3_SCL
  J1C1    E5   IOE5  CONN76_H22707001_THMT1  I18
  R1C11    1      A  RES         I97
  R2N21    2      B  RES         I175
  R2U3     2      B  RES         I98
  R2U6     2      B  RES         I166
  R2U8     1      A  RES         I158
  R4A9     1      A  RES         I324
  R9F22    2      B  RES         I52
  R9M20    1      A  RES         I323

SMB_LAN_STBY_LVC3_SCL_R   @BASEBOARD_FAB2_LIB.BASEBOARD_FAB2(SCH_1):SMB_LAN_STBY_LVC3_SCL_R
  R9F22    1      A  RES         I52
  U9F4   K21  SCL<1>  AST1250_BGA  I347

SMB_LAN_STBY_LVC3_SCL_R1   @BASEBOARD_FAB2_LIB.BASEBOARD_FAB2(SCH_1):SMB_LAN_STBY_LVC3_SCL_R1
  R2U6     1      A  RES         I166
  U7C1   BF1  GPP_H16_SML4CLK_IE  LBG_CORE_QAT_EXT_D  I147

SMB_LAN_STBY_LVC3_SCL_R2   @BASEBOARD_FAB2_LIB.BASEBOARD_FAB2(SCH_1):SMB_LAN_STBY_LVC3_SCL_R2
  R2N21    1      A  RES         I175
  U7C1   AU9  GPP_F19_LAN_SMBCLK  LBG_CORE_QAT_EXT_D  I147

SMB_LAN_STBY_LVC3_SDA   @BASEBOARD_FAB2_LIB.BASEBOARD_FAB2(SCH_1):SMB_LAN_STBY_LVC3_SDA
  J1C1    D5   IOD5  CONN76_H22707001_THMT1  I18
  R1C10    1      A  RES         I101
  R2N20    2      B  RES         I171
  R2U9     2      B  RES         I165
  R2U11    2      B  RES         I97
  R2U12    1      A  RES         I159
  R4A8     1      A  RES         I322
  R9F23    2      B  RES         I51
  R9M21    1      A  RES         I321

SMB_LAN_STBY_LVC3_SDA_R   @BASEBOARD_FAB2_LIB.BASEBOARD_FAB2(SCH_1):SMB_LAN_STBY_LVC3_SDA_R
  R9F23    1      A  RES         I51
  U9F4   K22  SDA<1>  AST1250_BGA  I347

SMB_LAN_STBY_LVC3_SDA_R1   @BASEBOARD_FAB2_LIB.BASEBOARD_FAB2(SCH_1):SMB_LAN_STBY_LVC3_SDA_R1
  R2U9     1      A  RES         I165
  U7C1   BE4  GPP_H17_SML4DATA_IE  LBG_CORE_QAT_EXT_D  I147

SMB_LAN_STBY_LVC3_SDA_R2   @BASEBOARD_FAB2_LIB.BASEBOARD_FAB2(SCH_1):SMB_LAN_STBY_LVC3_SDA_R2
  R2N20    1      A  RES         I171
  U7C1   AU20  GPP_F20_LAN_SMBDATA  LBG_CORE_QAT_EXT_D  I147

SMB_OCP_FRU_STBY_LVC3_SCL   @BASEBOARD_FAB2_LIB.BASEBOARD_FAB2(SCH_1):SMB_OCP_FRU_STBY_LVC3_SCL
  J8B1    22   IO22  SCONN24_H46321001_SM   I1
  J8E4     1    IO1  SCONN64_H87568002_A_SMT  I27
  J9B3    30   IO30  SCONN120_A28699018_SM  I336
  R2U7     2      B  RES         I220
  R2U8     2      B  RES         I158

SMB_OCP_FRU_STBY_LVC3_SCL_R   @BASEBOARD_FAB2_LIB.BASEBOARD_FAB2(SCH_1):SMB_OCP_FRU_STBY_LVC3_SCL_R
  R2U5     2      B  RES         I214
  R2U7     1      A  RES         I220
  U9F4    C5  GPIOA4_TIMER5_SCL9  AST1250_BGA  I347

SMB_OCP_FRU_STBY_LVC3_SDA   @BASEBOARD_FAB2_LIB.BASEBOARD_FAB2(SCH_1):SMB_OCP_FRU_STBY_LVC3_SDA
  J8B1    24   IO24  SCONN24_H46321001_SM   I1
  J8E4     2    IO2  SCONN64_H87568002_A_SMT  I27
  J9B3    32   IO32  SCONN120_A28699018_SM  I336
  R2U10    2      B  RES         I221
  R2U12    2      B  RES         I159

SMB_OCP_FRU_STBY_LVC3_SDA_R   @BASEBOARD_FAB2_LIB.BASEBOARD_FAB2(SCH_1):SMB_OCP_FRU_STBY_LVC3_SDA_R
  R2U10    1      A  RES         I221
  R2U13    2      B  RES         I216
  U9F4    B4  GPIOA5_TIMER6_SDA9  AST1250_BGA  I347

SMB_OCP_LAN_STBY_LVC3_SCL   @BASEBOARD_FAB2_LIB.BASEBOARD_FAB2(SCH_1):SMB_OCP_LAN_STBY_LVC3_SCL
  J9B3    35   IO35  SCONN120_A28699018_SM  I336
  R8G4     2      B  RES         I229
  R9G13    1      A  RES         I227

SMB_OCP_LAN_STBY_LVC3_SCL_R   @BASEBOARD_FAB2_LIB.BASEBOARD_FAB2(SCH_1):SMB_OCP_LAN_STBY_LVC3_SCL_R
  R8G3     2      B  RES         I210
  R8G4     1      A  RES         I229
  U9F4    D3  GPIOQ0_SCL3  AST1250_BGA  I347

SMB_OCP_LAN_STBY_LVC3_SDA   @BASEBOARD_FAB2_LIB.BASEBOARD_FAB2(SCH_1):SMB_OCP_LAN_STBY_LVC3_SDA
  J9B3    37   IO37  SCONN120_A28699018_SM  I336
  R8G5     2      B  RES         I228
  R9G12    1      A  RES         I224

SMB_OCP_LAN_STBY_LVC3_SDA_R   @BASEBOARD_FAB2_LIB.BASEBOARD_FAB2(SCH_1):SMB_OCP_LAN_STBY_LVC3_SDA_R
  R8G5     1      A  RES         I228
  R8G6     2      B  RES         I212
  U9F4    C2  GPIOQ1_SDA3  AST1250_BGA  I347

SMB_PCH_MEZZ_LOM0_SCL   @BASEBOARD_FAB2_LIB.BASEBOARD_FAB2(SCH_1):SMB_PCH_MEZZ_LOM0_SCL
  J8E4    20   IO20  SCONN64_H87568002_A_SMT  I27
  R1R18    2      B  RES         I88
  U7C1   BM4  GPP_J8_LAN_I2C_SCL_MDC_P0  LBG_CORE_QAT_EXT_D  I147

SMB_PCH_MEZZ_LOM0_SDA   @BASEBOARD_FAB2_LIB.BASEBOARD_FAB2(SCH_1):SMB_PCH_MEZZ_LOM0_SDA
  J8E4    21   IO21  SCONN64_H87568002_A_SMT  I27
  R1R19    2      B  RES         I89
  U7C1   BN3  GPP_J9_LAN_I2C_SDA_MDIO_P0  LBG_CORE_QAT_EXT_D  I147

SMB_PCH_MEZZ_LOM1_SCL   @BASEBOARD_FAB2_LIB.BASEBOARD_FAB2(SCH_1):SMB_PCH_MEZZ_LOM1_SCL
  J8E4    26   IO26  SCONN64_H87568002_A_SMT  I27
  R1R20    2      B  RES         I91
  U7C1   BW5  GPP_J10_LAN_I2C_SCL_MDC_P1  LBG_CORE_QAT_EXT_D  I147

SMB_PCH_MEZZ_LOM1_SDA   @BASEBOARD_FAB2_LIB.BASEBOARD_FAB2(SCH_1):SMB_PCH_MEZZ_LOM1_SDA
  J8E4    27   IO27  SCONN64_H87568002_A_SMT  I27
  R1R21    2      B  RES         I90
  U7C1   BV8  GPP_J11_LAN_I2C_SDA_MDIO_P1  LBG_CORE_QAT_EXT_D  I147

SMB_PCH_MEZZ_LOM2_SCL   @BASEBOARD_FAB2_LIB.BASEBOARD_FAB2(SCH_1):SMB_PCH_MEZZ_LOM2_SCL
  J8E4    61   IO61  SCONN64_H87568002_A_SMT  I27
  R1R16    2      B  RES         I93
  U7C1   BT5  GPP_J12_LAN_I2C_SCL_MDC_P2  LBG_CORE_QAT_EXT_D  I147

SMB_PCH_MEZZ_LOM2_SDA   @BASEBOARD_FAB2_LIB.BASEBOARD_FAB2(SCH_1):SMB_PCH_MEZZ_LOM2_SDA
  J8E4    62   IO62  SCONN64_H87568002_A_SMT  I27
  R1R17    2      B  RES         I94
  U7C1   BW11  GPP_J13_LAN_I2C_SDA_MDIO_P2  LBG_CORE_QAT_EXT_D  I147

SMB_PCH_MEZZ_LOM3_SCL   @BASEBOARD_FAB2_LIB.BASEBOARD_FAB2(SCH_1):SMB_PCH_MEZZ_LOM3_SCL
  J8E4    29   IO29  SCONN64_H87568002_A_SMT  I27
  R1R23    2      B  RES         I95
  U7C1   BW6  GPP_J14_LAN_I2C_SCL_MDC_P3  LBG_CORE_QAT_EXT_D  I147

SMB_PCH_MEZZ_LOM3_SDA   @BASEBOARD_FAB2_LIB.BASEBOARD_FAB2(SCH_1):SMB_PCH_MEZZ_LOM3_SDA
  J8E4    30   IO30  SCONN64_H87568002_A_SMT  I27
  R1R22    2      B  RES         I92
  U7C1   BW9  GPP_J15_LAN_I2C_SDA_MDIO_P3  LBG_CORE_QAT_EXT_D  I147

SMB_PEHPCPU1_STBY_LVC3_R_SCL   @BASEBOARD_FAB2_LIB.BASEBOARD_FAB2(SCH_1):SMB_PEHPCPU1_STBY_LVC3_R_SCL
  R9M14    1      A  RES         I20
  R9M15    1      A  RES         I25
  R9M17    2      B  RES         I15
  U1B2     7   SCLB  PCA9517_SM   I1

SMB_PEHPCPU1_STBY_LVC3_R_SDA   @BASEBOARD_FAB2_LIB.BASEBOARD_FAB2(SCH_1):SMB_PEHPCPU1_STBY_LVC3_R_SDA
  R9M12    1      A  RES         I24
  R9M13    1      A  RES         I21
  R9M16    2      B  RES         I16
  U1B2     6   SDAB  PCA9517_SM   I1

SMB_PEHPCPU1_STBY_LVC3_SCL   @BASEBOARD_FAB2_LIB.BASEBOARD_FAB2(SCH_1):SMB_PEHPCPU1_STBY_LVC3_SCL
  J1C1    C6   IOC6  CONN76_H22707001_THMT1  I18
  R9M14    2      B  RES         I20

SMB_PEHPCPU1_STBY_LVC3_SDA   @BASEBOARD_FAB2_LIB.BASEBOARD_FAB2(SCH_1):SMB_PEHPCPU1_STBY_LVC3_SDA
  J1C1    B6   IOB6  CONN76_H22707001_THMT1  I18
  R9M13    2      B  RES         I21

SMB_PIROM_CPU0_SCL   @BASEBOARD_FAB2_LIB.BASEBOARD_FAB2(SCH_1):SMB_PIROM_CPU0_SCL
  R4A9     2      B  RES         I324
  U5D1   CT59  SMBCLK  SKX_EXT_B_BGA1  I259

SMB_PIROM_CPU0_SDA   @BASEBOARD_FAB2_LIB.BASEBOARD_FAB2(SCH_1):SMB_PIROM_CPU0_SDA
  R4A8     2      B  RES         I322
  U5D1   CW58  SMBDAT  SKX_EXT_B_BGA1  I259

SMB_PIROM_CPU1_SCL   @BASEBOARD_FAB2_LIB.BASEBOARD_FAB2(SCH_1):SMB_PIROM_CPU1_SCL
  R9M20    2      B  RES         I323
  U2D1   CT59  SMBCLK  SKX_EXT_B_BGA1  I172

SMB_PIROM_CPU1_SDA   @BASEBOARD_FAB2_LIB.BASEBOARD_FAB2(SCH_1):SMB_PIROM_CPU1_SDA
  R9M21    2      B  RES         I321
  U2D1   CW58  SMBDAT  SKX_EXT_B_BGA1  I172

SMB_PMBUS_BMC_STBY_LVC3_SCL_R1   @BASEBOARD_FAB2_LIB.BASEBOARD_FAB2(SCH_1):SMB_PMBUS_BMC_STBY_LVC3_SCL_R1
  R2T56    1      A  RES         I160
  U7C1   CA28  GPP_C6_SML1CLK_IE  LBG_CORE_QAT_EXT_D  I115

SMB_PMBUS_BMC_STBY_LVC3_SDA_R1   @BASEBOARD_FAB2_LIB.BASEBOARD_FAB2(SCH_1):SMB_PMBUS_BMC_STBY_LVC3_SDA_R1
  R2T55    1      A  RES         I116
  U7C1   BV35  GPP_C7_SML1DATA_IE  LBG_CORE_QAT_EXT_D  I115

SMB_SENSOR_BMC_STBY_LVC3_SCL   @BASEBOARD_FAB2_LIB.BASEBOARD_FAB2(SCH_1):SMB_SENSOR_BMC_STBY_LVC3_SCL
  R9G14    1      A  RES         I77
  U9F4    E2  GPIOK4_SCL7  AST1250_BGA  I347

SMB_SENSOR_BMC_STBY_LVC3_SDA   @BASEBOARD_FAB2_LIB.BASEBOARD_FAB2(SCH_1):SMB_SENSOR_BMC_STBY_LVC3_SDA
  R9G15    1      A  RES         I58
  U9F4    D1  GPIOK5_SDA7  AST1250_BGA  I347

SMB_SENSOR_PCH_STBY_LVC3_SCL   @BASEBOARD_FAB2_LIB.BASEBOARD_FAB2(SCH_1):SMB_SENSOR_PCH_STBY_LVC3_SCL
  EU9G1    3    SCL  ADC128D818_SM  I52
  R1U25    1      A  RES         I79
  R8D3     2      B  RES         I161

SMB_SENSOR_PCH_STBY_LVC3_SDA   @BASEBOARD_FAB2_LIB.BASEBOARD_FAB2(SCH_1):SMB_SENSOR_PCH_STBY_LVC3_SDA
  EU9G1    2    SDA  ADC128D818_SM  I52
  R1U31    1      A  RES         I78
  R8D6     2      B  RES         I162

SMB_SENSOR_STBY_LVC3_SCL   @BASEBOARD_FAB2_LIB.BASEBOARD_FAB2(SCH_1):SMB_SENSOR_STBY_LVC3_SCL
  J8E1    10   IO10  SCONN11_H67026001_SM  I87
  R1M8     2      B  RES         I74
  R1U25    2      B  RES         I79
  R2U38    2      B  RES         I80
  R8D24    1      A  RES         I84
  R9G14    2      B  RES         I77
  R9R7     2      B  RES         I75
  U8D7    A9  PT18C_SCL_PCLKT0_0  LCMXO2_A_256BGA  I59

SMB_SENSOR_STBY_LVC3_SCL_R1   @BASEBOARD_FAB2_LIB.BASEBOARD_FAB2(SCH_1):SMB_SENSOR_STBY_LVC3_SCL_R1
  R8D3     1      A  RES         I161
  U7C1   AY1  GPP_H13_SML3CLK_IE  LBG_CORE_QAT_EXT_D  I147

SMB_SENSOR_STBY_LVC3_SCL_R2   @BASEBOARD_FAB2_LIB.BASEBOARD_FAB2(SCH_1):SMB_SENSOR_STBY_LVC3_SCL_R2
  R8D24    2      B  RES         I84
  U8D4     6    SCL  AT24C64     I49

SMB_SENSOR_STBY_LVC3_SDA   @BASEBOARD_FAB2_LIB.BASEBOARD_FAB2(SCH_1):SMB_SENSOR_STBY_LVC3_SDA
  J8E1     6    IO6  SCONN11_H67026001_SM  I87
  R1M9     2      B  RES          I8
  R1U31    2      B  RES         I78
  R2U39    2      B  RES         I83
  R8D23    2      B  RES         I85
  R9G15    2      B  RES         I58
  R9R8     2      B  RES         I76
  U8D7    C9  PT18D_SDA_PCLKC0_0  LCMXO2_A_256BGA  I59

SMB_SENSOR_STBY_LVC3_SDA_R1   @BASEBOARD_FAB2_LIB.BASEBOARD_FAB2(SCH_1):SMB_SENSOR_STBY_LVC3_SDA_R1
  R8D6     1      A  RES         I162
  U7C1   BC2  GPP_H14_SML3DATA_IE  LBG_CORE_QAT_EXT_D  I147

SMB_SENSOR_STBY_LVC3_SDA_R2   @BASEBOARD_FAB2_LIB.BASEBOARD_FAB2(SCH_1):SMB_SENSOR_STBY_LVC3_SDA_R2
  R8D23    1      A  RES         I85
  U8D4     5    SDA  AT24C64     I49

SMB_SENSOR_TMP421_1_SCL   @BASEBOARD_FAB2_LIB.BASEBOARD_FAB2(SCH_1):SMB_SENSOR_TMP421_1_SCL
  R1M8     1      A  RES         I74
  U9B4     7    SCL  TMP421_TSSOP   I1

SMB_SENSOR_TMP421_1_SDA   @BASEBOARD_FAB2_LIB.BASEBOARD_FAB2(SCH_1):SMB_SENSOR_TMP421_1_SDA
  R1M9     1      A  RES          I8
  U9B4     6    SDA  TMP421_TSSOP   I1

SMB_SENSOR_TMP421_2_SCL   @BASEBOARD_FAB2_LIB.BASEBOARD_FAB2(SCH_1):SMB_SENSOR_TMP421_2_SCL
  R9R7     1      A  RES         I75
  U1E1     7    SCL  TMP421_TSSOP  I30

SMB_SENSOR_TMP421_2_SDA   @BASEBOARD_FAB2_LIB.BASEBOARD_FAB2(SCH_1):SMB_SENSOR_TMP421_2_SDA
  R9R8     1      A  RES         I76
  U1E1     6    SDA  TMP421_TSSOP  I30

SMB_SLOTX24_BMC_STBY_LVC3_SCL   @BASEBOARD_FAB2_LIB.BASEBOARD_FAB2(SCH_1):SMB_SLOTX24_BMC_STBY_LVC3_SCL
  R1T7     2      B  RES         I50
  R2U32    1      A  RES         I339
  R9M15    2      B  RES         I25

SMB_SLOTX24_BMC_STBY_LVC3_SDA   @BASEBOARD_FAB2_LIB.BASEBOARD_FAB2(SCH_1):SMB_SLOTX24_BMC_STBY_LVC3_SDA
  R1T8     2      B  RES          I4
  R2U31    1      A  RES         I330
  R9M12    2      B  RES         I24

SMB_SLOTX24_PCH_STBY_LVC3_SCL   @BASEBOARD_FAB2_LIB.BASEBOARD_FAB2(SCH_1):SMB_SLOTX24_PCH_STBY_LVC3_SCL
  EU9F3   17    SCL  PI7C9X1172_QFN   I1
  R2U36    1      A  RES         I340
  R8B26    2      B  RES         I96
  R8B28    2      B  RES         I174
  U8D7    H5   PL9C  LCMXO2_A_256BGA  I179

SMB_SLOTX24_PCH_STBY_LVC3_SDA   @BASEBOARD_FAB2_LIB.BASEBOARD_FAB2(SCH_1):SMB_SLOTX24_PCH_STBY_LVC3_SDA
  EU9F3    3    SDA  PI7C9X1172_QFN   I1
  R2U35    1      A  RES         I320
  R8B24    2      B  RES         I95
  R8B27    2      B  RES         I173
  U8D7    J4   PL9D  LCMXO2_A_256BGA  I179

SMB_SLOTX24_STBY_LVC3_SCL_R   @BASEBOARD_FAB2_LIB.BASEBOARD_FAB2(SCH_1):SMB_SLOTX24_STBY_LVC3_SCL_R
  R1T2     2      B  RES         I49
  R1T7     1      A  RES         I50
  U9F4   J19  SCL<2>  AST1250_BGA  I347

SMB_SLOTX24_STBY_LVC3_SCL_R1   @BASEBOARD_FAB2_LIB.BASEBOARD_FAB2(SCH_1):SMB_SLOTX24_STBY_LVC3_SCL_R1
  R8B28    1      A  RES         I174
  U7C1   BY44  GPP_D13_SML0BCLK_IE  LBG_CORE_QAT_EXT_D  I115

SMB_SLOTX24_STBY_LVC3_SCL_R2   @BASEBOARD_FAB2_LIB.BASEBOARD_FAB2(SCH_1):SMB_SLOTX24_STBY_LVC3_SCL_R2
  J8G1    17   IO17  SCONN200_H68296001_SM  I258
  R2U32    2      B  RES         I339
  R2U36    2      B  RES         I340

SMB_SLOTX24_STBY_LVC3_SDA_R   @BASEBOARD_FAB2_LIB.BASEBOARD_FAB2(SCH_1):SMB_SLOTX24_STBY_LVC3_SDA_R
  R1T3     2      B  RES         I46
  R1T8     1      A  RES          I4
  U9F4   J18  SDA<2>  AST1250_BGA  I347

SMB_SLOTX24_STBY_LVC3_SDA_R1   @BASEBOARD_FAB2_LIB.BASEBOARD_FAB2(SCH_1):SMB_SLOTX24_STBY_LVC3_SDA_R1
  R8B27    1      A  RES         I173
  U7C1   BL44  GPP_D14_SML0BDATA_IE  LBG_CORE_QAT_EXT_D  I115

SMB_SLOTX24_STBY_LVC3_SDA_R2   @BASEBOARD_FAB2_LIB.BASEBOARD_FAB2(SCH_1):SMB_SLOTX24_STBY_LVC3_SDA_R2
  J8G1    15   IO15  SCONN200_H68296001_SM  I258
  R2U31    2      B  RES         I330
  R2U35    2      B  RES         I320

SMB_SMLINK0_STBY_LVC3_SCL   @BASEBOARD_FAB2_LIB.BASEBOARD_FAB2(SCH_1):SMB_SMLINK0_STBY_LVC3_SCL
  J9B2     3    IO3  CONN3_C95678002_PIP  I281
  R1U9     2      B  RES         I232
  R1U19    1      A  RES         I226
  R2N5     2      B  RES         I90
  R8C12    2      B  RES         I170

SMB_SMLINK0_STBY_LVC3_SCL_R   @BASEBOARD_FAB2_LIB.BASEBOARD_FAB2(SCH_1):SMB_SMLINK0_STBY_LVC3_SCL_R
  R1U9     1      A  RES         I232
  U9F4    E3  GPIOK0_SCL5  AST1250_BGA  I347

SMB_SMLINK0_STBY_LVC3_SCL_R1   @BASEBOARD_FAB2_LIB.BASEBOARD_FAB2(SCH_1):SMB_SMLINK0_STBY_LVC3_SCL_R1
  R8C12    1      A  RES         I170
  U7C1   BV29  GPP_C3_SML0CLK_IE  LBG_CORE_QAT_EXT_D  I115

SMB_SMLINK0_STBY_LVC3_SDA   @BASEBOARD_FAB2_LIB.BASEBOARD_FAB2(SCH_1):SMB_SMLINK0_STBY_LVC3_SDA
  J9B2     1    IO1  CONN3_C95678002_PIP  I281
  R1U10    2      B  RES         I233
  R1U20    1      A  RES         I225
  R2N8     2      B  RES         I89
  R8C11    2      B  RES         I169

SMB_SMLINK0_STBY_LVC3_SDA_R   @BASEBOARD_FAB2_LIB.BASEBOARD_FAB2(SCH_1):SMB_SMLINK0_STBY_LVC3_SDA_R
  R1U10    1      A  RES         I233
  U9F4    D2  GPIOK1_SDA5  AST1250_BGA  I347

SMB_SMLINK0_STBY_LVC3_SDA_R1   @BASEBOARD_FAB2_LIB.BASEBOARD_FAB2(SCH_1):SMB_SMLINK0_STBY_LVC3_SDA_R1
  R8C11    1      A  RES         I169
  U7C1   BW30  GPP_C4_SML0DATA_IE  LBG_CORE_QAT_EXT_D  I115

SMB_SPRINGVILLE_STBY_LVC3_SCL   @BASEBOARD_FAB2_LIB.BASEBOARD_FAB2(SCH_1):SMB_SPRINGVILLE_STBY_LVC3_SCL
  EU9E1   34  SMB_CLK  SPRINGVILLE_SM1  I72
  R1U19    2      B  RES         I226
  R9G13    2      B  RES         I227

SMB_SPRINGVILLE_STBY_LVC3_SDA   @BASEBOARD_FAB2_LIB.BASEBOARD_FAB2(SCH_1):SMB_SPRINGVILLE_STBY_LVC3_SDA
  EU9E1   36  SMB_DATA  SPRINGVILLE_SM1  I72
  R1U20    2      B  RES         I225
  R9G12    2      B  RES         I224

SMB_VR_SCL_PVCCIO_CPU0   @BASEBOARD_FAB2_LIB.BASEBOARD_FAB2(SCH_1):SMB_VR_SCL_PVCCIO_CPU0
  EU3P1    7    SCL  PXE1110B_QFN  I93
  R3P24    2      B  RES         I46

SMB_VR_SCL_PVCCIO_CPU1   @BASEBOARD_FAB2_LIB.BASEBOARD_FAB2(SCH_1):SMB_VR_SCL_PVCCIO_CPU1
  EU4D5    7    SCL  PXE1110B_QFN  I96
  R4D43    2      B  RES         I39

SMB_VR_SCL_PVNN_PCH   @BASEBOARD_FAB2_LIB.BASEBOARD_FAB2(SCH_1):SMB_VR_SCL_PVNN_PCH
  EU8A1    7    SCL  PXE1110B_QFN  I229
  R8A9     2      B  RES         I173

SMB_VR_SCL_R    @BASEBOARD_FAB2_LIB.BASEBOARD_FAB2(SCH_1):SMB_VR_SCL_R
  EU4D4    9    SCL  PXE1610B_QFN  I155
  R4D53    1      A  RES         I31

SMB_VR_SCL_R1   @BASEBOARD_FAB2_LIB.BASEBOARD_FAB2(SCH_1):SMB_VR_SCL_R1
  EU1C2    9    SCL  PXE1610B_QFN  I130
  R1C25    1      A  RES         I28

SMB_VR_SCL_VDDQ_ABC   @BASEBOARD_FAB2_LIB.BASEBOARD_FAB2(SCH_1):SMB_VR_SCL_VDDQ_ABC
  EU7G1    7    SCL  PXM1310B_QFN  I358
  R7F25    1      A  RES         I298

SMB_VR_SCL_VDDQ_DEF   @BASEBOARD_FAB2_LIB.BASEBOARD_FAB2(SCH_1):SMB_VR_SCL_VDDQ_DEF
  EU7A5    7    SCL  PXM1310B_QFN  I75
  R7B3     1      A  RES         I21

SMB_VR_SCL_VDDQ_GHJ   @BASEBOARD_FAB2_LIB.BASEBOARD_FAB2(SCH_1):SMB_VR_SCL_VDDQ_GHJ
  EU1G2    7    SCL  PXM1310B_QFN  I90
  R1G19    1      A  RES         I21

SMB_VR_SCL_VDDQ_KLM   @BASEBOARD_FAB2_LIB.BASEBOARD_FAB2(SCH_1):SMB_VR_SCL_VDDQ_KLM
  EU1B1    7    SCL  PXM1310B_QFN  I90
  R1B6     1      A  RES         I21

SMB_VR_SDA_PVCCIO_CPU0   @BASEBOARD_FAB2_LIB.BASEBOARD_FAB2(SCH_1):SMB_VR_SDA_PVCCIO_CPU0
  EU3P1    6    SDA  PXE1110B_QFN  I93
  R3P23    2      B  RES         I47

SMB_VR_SDA_PVCCIO_CPU1   @BASEBOARD_FAB2_LIB.BASEBOARD_FAB2(SCH_1):SMB_VR_SDA_PVCCIO_CPU1
  EU4D5    6    SDA  PXE1110B_QFN  I96
  R4D44    2      B  RES         I38

SMB_VR_SDA_PVNN_PCH   @BASEBOARD_FAB2_LIB.BASEBOARD_FAB2(SCH_1):SMB_VR_SDA_PVNN_PCH
  EU8A1    6    SDA  PXE1110B_QFN  I229
  R8A8     2      B  RES         I172

SMB_VR_SDA_R    @BASEBOARD_FAB2_LIB.BASEBOARD_FAB2(SCH_1):SMB_VR_SDA_R
  EU4D4    8    SDA  PXE1610B_QFN  I155
  R4D50    1      A  RES         I28

SMB_VR_SDA_R1   @BASEBOARD_FAB2_LIB.BASEBOARD_FAB2(SCH_1):SMB_VR_SDA_R1
  EU1C2    8    SDA  PXE1610B_QFN  I130
  R1C23    1      A  RES         I27

SMB_VR_SDA_VDDQ_ABC   @BASEBOARD_FAB2_LIB.BASEBOARD_FAB2(SCH_1):SMB_VR_SDA_VDDQ_ABC
  EU7G1    6    SDA  PXM1310B_QFN  I358
  R7F26    1      A  RES         I304

SMB_VR_SDA_VDDQ_DEF   @BASEBOARD_FAB2_LIB.BASEBOARD_FAB2(SCH_1):SMB_VR_SDA_VDDQ_DEF
  EU7A5    6    SDA  PXM1310B_QFN  I75
  R7B2     1      A  RES         I24

SMB_VR_SDA_VDDQ_GHJ   @BASEBOARD_FAB2_LIB.BASEBOARD_FAB2(SCH_1):SMB_VR_SDA_VDDQ_GHJ
  EU1G2    6    SDA  PXM1310B_QFN  I90
  R1G21    1      A  RES         I22

SMB_VR_SDA_VDDQ_KLM   @BASEBOARD_FAB2_LIB.BASEBOARD_FAB2(SCH_1):SMB_VR_SDA_VDDQ_KLM
  EU1B1    6    SDA  PXM1310B_QFN  I90
  R1B7     1      A  RES         I22

SMB_VR_STBY_LVC3_SCL   @BASEBOARD_FAB2_LIB.BASEBOARD_FAB2(SCH_1):SMB_VR_STBY_LVC3_SCL
  J4B2   A18  IOA18  SCONN120_H61426002_SM  I46
  J6B1   A18  IOA18  SCONN120_H61426002_SM  I56
  J8D4     3    IO3  CONN3_C95678002_PIP  I122
  R1B6     2      B  RES         I21
  R1C25    2      B  RES         I28
  R1G19    2      B  RES         I21
  R1U11    2      B  RES         I222
  R3P24    1      A  RES         I46
  R4D43    1      A  RES         I39
  R4D53    2      B  RES         I31
  R6P37    2      B  RES         I103
  R7B3     2      B  RES         I21
  R7F25    2      B  RES         I298
  R8A9     1      A  RES         I173
  R8D4     2      B  RES         I164
  R8D15    2      B  RES         I88

SMB_VR_STBY_LVC3_SCL_R   @BASEBOARD_FAB2_LIB.BASEBOARD_FAB2(SCH_1):SMB_VR_STBY_LVC3_SCL_R
  R1U11    1      A  RES         I222
  U9F4    C1  GPIOK2_SCL6  AST1250_BGA  I347

SMB_VR_STBY_LVC3_SCL_R1   @BASEBOARD_FAB2_LIB.BASEBOARD_FAB2(SCH_1):SMB_VR_STBY_LVC3_SCL_R1
  R8D4     1      A  RES         I164
  U7C1   BA4  GPP_H10_SML2CLK_IE  LBG_CORE_QAT_EXT_D  I147

SMB_VR_STBY_LVC3_SDA   @BASEBOARD_FAB2_LIB.BASEBOARD_FAB2(SCH_1):SMB_VR_STBY_LVC3_SDA
  J4B2   B18  IOB18  SCONN120_H61426002_SM  I46
  J6B1   B18  IOB18  SCONN120_H61426002_SM  I56
  J8D4     1    IO1  CONN3_C95678002_PIP  I122
  R1B7     2      B  RES         I22
  R1C23    2      B  RES         I27
  R1G21    2      B  RES         I22
  R1U8     2      B  RES         I223
  R3P23    1      A  RES         I47
  R4D44    1      A  RES         I38
  R4D50    2      B  RES         I28
  R6P32    2      B  RES         I102
  R7B2     2      B  RES         I24
  R7F26    2      B  RES         I304
  R8A8     1      A  RES         I172
  R8D7     2      B  RES         I163
  R8D17    2      B  RES         I87

SMB_VR_STBY_LVC3_SDA_R   @BASEBOARD_FAB2_LIB.BASEBOARD_FAB2(SCH_1):SMB_VR_STBY_LVC3_SDA_R
  R1U8     1      A  RES         I223
  U9F4    F4  GPIOK3_SDA6  AST1250_BGA  I347

SMB_VR_STBY_LVC3_SDA_R1   @BASEBOARD_FAB2_LIB.BASEBOARD_FAB2(SCH_1):SMB_VR_STBY_LVC3_SDA_R1
  R8D7     1      A  RES         I163
  U7C1   BD1  GPP_H11_SML2DATA_IE  LBG_CORE_QAT_EXT_D  I147

SP1_BMC_HOST_UART_RX   @BASEBOARD_FAB2_LIB.BASEBOARD_FAB2(SCH_1):SP1_BMC_HOST_UART_RX
  R9F54    1      A  RES         I52
  U8D7    K3  PL10A  LCMXO2_A_256BGA  I179
  U9F1     3     B2  FSA3357_SM  I75
  U9F4    U5  GPIOL7_RXD1_VPIB1  AST1250_BGA  I100

SP1_BMC_HOST_UART_TX   @BASEBOARD_FAB2_LIB.BASEBOARD_FAB2(SCH_1):SP1_BMC_HOST_UART_TX
  R9F56    2      B  RES         I49
  U8D7    K2  PL10B  LCMXO2_A_256BGA  I179
  U9F2     3     B2  FSA3357_SM  I74
  U9F4    W1  GPIOL6_TXD1_VPIB0  AST1250_BGA  I100

SP1_HOST_BRIDGE_UART_RX   @BASEBOARD_FAB2_LIB.BASEBOARD_FAB2(SCH_1):SP1_HOST_BRIDGE_UART_RX
  EU9F3    5    RXA  PI7C9X1172_QFN   I1
  R9F54    2      B  RES         I52

SP1_HOST_BRIDGE_UART_TX   @BASEBOARD_FAB2_LIB.BASEBOARD_FAB2(SCH_1):SP1_HOST_BRIDGE_UART_TX
  EU9F3    6    TXA  PI7C9X1172_QFN   I1
  R9F56    1      A  RES         I49

SP2_BMC_CM_UART_RX   @BASEBOARD_FAB2_LIB.BASEBOARD_FAB2(SCH_1):SP2_BMC_CM_UART_RX
  R9F24    2      B  RES         I100
  R9F68    2      B  RES         I141
  U7C1   BV44  GPP_D21_IE_UART_RX  LBG_CORE_QAT_EXT_D  I115
  U9F4    V5  GPIOM7_RXD2_VPIB9  AST1250_BGA  I100

SP2_BMC_CM_UART_RX_R   @BASEBOARD_FAB2_LIB.BASEBOARD_FAB2(SCH_1):SP2_BMC_CM_UART_RX_R
  R9F68    1      A  RES         I141
  R9F69    1      A  RES         I146
  U9F1     1     B0  FSA3357_SM  I75

SP2_BMC_CM_UART_RX_R1   @BASEBOARD_FAB2_LIB.BASEBOARD_FAB2(SCH_1):SP2_BMC_CM_UART_RX_R1
  R9F67    1      A  RES         I276
  R9F69    2      B  RES         I146

SP2_BMC_CM_UART_TX   @BASEBOARD_FAB2_LIB.BASEBOARD_FAB2(SCH_1):SP2_BMC_CM_UART_TX
  R9F26    1      A  RES         I99
  R9F66    1      A  RES         I138
  U7C1   BR46  GPP_D22_IE_UART_TX  LBG_CORE_QAT_EXT_D  I115
  U9F4   AA1  GPIOM6_TXD2_VPIB8  AST1250_BGA  I100

SP2_BMC_CM_UART_TX_R   @BASEBOARD_FAB2_LIB.BASEBOARD_FAB2(SCH_1):SP2_BMC_CM_UART_TX_R
  R9F65    2      B  RES         I145
  R9F66    2      B  RES         I138
  U9F2     1     B0  FSA3357_SM  I74

SP2_BMC_CM_UART_TX_R1   @BASEBOARD_FAB2_LIB.BASEBOARD_FAB2(SCH_1):SP2_BMC_CM_UART_TX_R1
  R9F64    1      A  RES         I277
  R9F65    1      A  RES         I145

SPA_5V_SIN_SW   @BASEBOARD_FAB2_LIB.BASEBOARD_FAB2(SCH_1):SPA_5V_SIN_SW
  J9A2    10   IO10  CONN14_H54902001_PIP  I171
  R9A6     2      B  RES         I191
  U9A1     2      A  TTL1G07_A_SOP  I178

SPA_MID_DBG_RX   @BASEBOARD_FAB2_LIB.BASEBOARD_FAB2(SCH_1):SPA_MID_DBG_RX
  R9A8     2      B  RES         I53
  R9F24    1      A  RES         I100
  R9F25    1      A  RES         I86
  R9F63    1      A  RES         I271

SPA_MID_DBG_RX_R   @BASEBOARD_FAB2_LIB.BASEBOARD_FAB2(SCH_1):SPA_MID_DBG_RX_R
  J1F1    H3   IOH3  CONN76_H22707001_THMT1  I111
  R9F63    2      B  RES         I271
  R9F64    2      B  RES         I277

SPA_MID_DBG_TX   @BASEBOARD_FAB2_LIB.BASEBOARD_FAB2(SCH_1):SPA_MID_DBG_TX
  J9A2     9    IO9  CONN14_H54902001_PIP  I171
  R9F26    2      B  RES         I99
  R9F27    2      B  RES         I91
  R9F70    1      A  RES         I270

SPA_MID_DBG_TX_R   @BASEBOARD_FAB2_LIB.BASEBOARD_FAB2(SCH_1):SPA_MID_DBG_TX_R
  J1F1    G3   IOG3  CONN76_H22707001_THMT1  I111
  R9F67    2      B  RES         I276
  R9F70    2      B  RES         I270

SPA_SIN_SW_R    @BASEBOARD_FAB2_LIB.BASEBOARD_FAB2(SCH_1):SPA_SIN_SW_R
  R9A7     2      B  RES         I80
  R9A8     1      A  RES         I53
  U9A1     4      Y  TTL1G07_A_SOP  I178

SPI_BIOS_SOCKET_IO2   @BASEBOARD_FAB2_LIB.BASEBOARD_FAB2(SCH_1):SPI_BIOS_SOCKET_IO2
  R3U1     1      A  RES         I156
  R7F37    1      A  RES         I108
  U2T1     4     YA  PI3B3257A_TSSOPLF  I75

SPI_BIOS_SOCKET_IO3   @BASEBOARD_FAB2_LIB.BASEBOARD_FAB2(SCH_1):SPI_BIOS_SOCKET_IO3
  R3T1     1      A  RES         I157
  R7F3     1      A  RES         I109
  U2T1     7     YB  PI3B3257A_TSSOPLF  I75

SPI_BMC_BT_CLK   @BASEBOARD_FAB2_LIB.BASEBOARD_FAB2(SCH_1):SPI_BMC_BT_CLK
  R9F21    2      B  RES         I109
  U8F2    16    CLK  W25Q128_SKT16  I32

SPI_BMC_BT_CLK_R   @BASEBOARD_FAB2_LIB.BASEBOARD_FAB2(SCH_1):SPI_BMC_BT_CLK_R
  R9F21    1      A  RES         I109
  U9F4   T22  ROMD0  AST1250_BGA   I1

SPI_BMC_BT_CS_N   @BASEBOARD_FAB2_LIB.BASEBOARD_FAB2(SCH_1):SPI_BMC_BT_CS_N
  R1T26    1      A  RES         I35
  R8F13    2      B  RES         I23
  U8F2     7   CS_N  W25Q128_SKT16  I32

SPI_BMC_BT_CS_R_N   @BASEBOARD_FAB2_LIB.BASEBOARD_FAB2(SCH_1):SPI_BMC_BT_CS_R_N
  R1T26    2      B  RES         I35
  U9F4   R19  ROMCS0_N  AST1250_BGA   I1

SPI_BMC_BT_DI   @BASEBOARD_FAB2_LIB.BASEBOARD_FAB2(SCH_1):SPI_BMC_BT_DI
  R8F12    1      A  RES         I13
  U9F4   T20  ROMD2  AST1250_BGA   I1

SPI_BMC_BT_DI_R   @BASEBOARD_FAB2_LIB.BASEBOARD_FAB2(SCH_1):SPI_BMC_BT_DI_R
  R8F12    2      B  RES         I13
  U8F2     8  DO_IO<1>  W25Q128_SKT16  I32

SPI_BMC_BT_DO   @BASEBOARD_FAB2_LIB.BASEBOARD_FAB2(SCH_1):SPI_BMC_BT_DO
  R9F41    2      B  RES         I108
  U8F2    15  DI_IO<0>  W25Q128_SKT16  I32

SPI_BMC_BT_DO_R   @BASEBOARD_FAB2_LIB.BASEBOARD_FAB2(SCH_1):SPI_BMC_BT_DO_R
  R9F41    1      A  RES         I108
  U9F4   T21  ROMD1  AST1250_BGA   I1

SPI_BMC_CLK     @BASEBOARD_FAB2_LIB.BASEBOARD_FAB2(SCH_1):SPI_BMC_CLK
  U8F1     3    IA1  PI3B3257A_TSSOPLF  I74
  U9F4   G19  GPIOI5_SPICK_VBCK  AST1250_BGA  I347

SPI_BMC_CS0_N   @BASEBOARD_FAB2_LIB.BASEBOARD_FAB2(SCH_1):SPI_BMC_CS0_N
  U8F1    10    IC1  PI3B3257A_TSSOPLF  I74
  U9F4   B22  GPIOI4_SPICS0_N_VBCS_N  AST1250_BGA  I347

SPI_BMC_DI      @BASEBOARD_FAB2_LIB.BASEBOARD_FAB2(SCH_1):SPI_BMC_DI
  U8F1    13    ID1  PI3B3257A_TSSOPLF  I74
  U9F4   E20  GPIOI7_SPIDI_VBDI  AST1250_BGA  I347

SPI_BMC_DO      @BASEBOARD_FAB2_LIB.BASEBOARD_FAB2(SCH_1):SPI_BMC_DO
  U8F1     6    IB1  PI3B3257A_TSSOPLF  I74
  U9F4   C18  GPIOI6_SPIDO_VBDO  AST1250_BGA  I347

SPI_CLK_R0      @BASEBOARD_FAB2_LIB.BASEBOARD_FAB2(SCH_1):SPI_CLK_R0
  R8F8     2      B  RES         I166
  U7F1    16    CLK  W25Q256_XSOI  I146

SPI_CLK_R1      @BASEBOARD_FAB2_LIB.BASEBOARD_FAB2(SCH_1):SPI_CLK_R1
  R8F7     2      B  RES         I167
  U3T1    16    CLK  W25Q256_XSOI  I165

SPI_CS0_PRIMARY_N   @BASEBOARD_FAB2_LIB.BASEBOARD_FAB2(SCH_1):SPI_CS0_PRIMARY_N
  R2T13    1      A  RES         I101
  U2T3     4      Y  TTL1G32_A   I99

SPI_CS0_PRIMARY_R_N   @BASEBOARD_FAB2_LIB.BASEBOARD_FAB2(SCH_1):SPI_CS0_PRIMARY_R_N
  R2T13    2      B  RES         I101
  R7F5     2      B  RES         I94
  U7F1     7   CS_N  W25Q256_XSOI  I146

SPI_CS0_SECONDARY_N   @BASEBOARD_FAB2_LIB.BASEBOARD_FAB2(SCH_1):SPI_CS0_SECONDARY_N
  R2T9     1      A  RES         I62
  U2T2     4      Y  TTL1G32_A   I100

SPI_CS0_SECONDARY_R_N   @BASEBOARD_FAB2_LIB.BASEBOARD_FAB2(SCH_1):SPI_CS0_SECONDARY_R_N
  R2T9     2      B  RES         I62
  R3T5     2      B  RES         I152
  U3T1     7   CS_N  W25Q256_XSOI  I165

SPI_MISO_R0     @BASEBOARD_FAB2_LIB.BASEBOARD_FAB2(SCH_1):SPI_MISO_R0
  R7F4     2      B  RES         I98
  U7F1     8  DO_IO<1>  W25Q256_XSOI  I146

SPI_MISO_R1     @BASEBOARD_FAB2_LIB.BASEBOARD_FAB2(SCH_1):SPI_MISO_R1
  R3T2     2      B  RES         I155
  U3T1     8  DO_IO<1>  W25Q256_XSOI  I165

SPI_NIC_CS_N    @BASEBOARD_FAB2_LIB.BASEBOARD_FAB2(SCH_1):SPI_NIC_CS_N
  R9E5     2      B  RES         I129
  U9E1     1    S_N  M25PE16_SM   I1

SPI_NIC_CS_R_N   @BASEBOARD_FAB2_LIB.BASEBOARD_FAB2(SCH_1):SPI_NIC_CS_R_N
  EU9E1   15  NVM_CS_N  SPRINGVILLE_SM1  I72
  R9E5     1      A  RES         I129

SPI_NIC_MISO    @BASEBOARD_FAB2_LIB.BASEBOARD_FAB2(SCH_1):SPI_NIC_MISO
  EU9E1   14  NVM_SO  SPRINGVILLE_SM1  I72
  R9E6     2      B  RES         I17

SPI_NIC_MISO_R   @BASEBOARD_FAB2_LIB.BASEBOARD_FAB2(SCH_1):SPI_NIC_MISO_R
  R9E6     1      A  RES         I17
  U9E1     2    DQ1  M25PE16_SM   I1

SPI_NIC_MOSI    @BASEBOARD_FAB2_LIB.BASEBOARD_FAB2(SCH_1):SPI_NIC_MOSI
  R1R6     1      A  RES         I14
  R1R7     2      B  RES         I12
  R9E9     2      B  RES         I128
  U9E1     5    DQ0  M25PE16_SM   I1

SPI_NIC_MOSI_R   @BASEBOARD_FAB2_LIB.BASEBOARD_FAB2(SCH_1):SPI_NIC_MOSI_R
  EU9E1   12  NVM_SI  SPRINGVILLE_SM1  I72
  R9E9     1      A  RES         I128

SPI_NIC_SCLK    @BASEBOARD_FAB2_LIB.BASEBOARD_FAB2(SCH_1):SPI_NIC_SCLK
  R9E8     2      B  RES         I130
  U9E1     6      C  M25PE16_SM   I1

SPI_NIC_SCLK_R   @BASEBOARD_FAB2_LIB.BASEBOARD_FAB2(SCH_1):SPI_NIC_SCLK_R
  EU9E1   13  NVM_SK  SPRINGVILLE_SM1  I72
  R9E8     1      A  RES         I130

SPI_PCH_CLK     @BASEBOARD_FAB2_LIB.BASEBOARD_FAB2(SCH_1):SPI_PCH_CLK
  R8E9     1      A  RES         I88
  U7C1    K2  SPI0_CLK  LBG_CORE_QAT_EXT_D  I34
  U8F1     2    IA0  PI3B3257A_TSSOPLF  I74

SPI_PCH_CS0_N   @BASEBOARD_FAB2_LIB.BASEBOARD_FAB2(SCH_1):SPI_PCH_CS0_N
  R7C16    2      B  RES         I33
  U8F1    11    IC0  PI3B3257A_TSSOPLF  I74

SPI_PCH_CS0_R_N   @BASEBOARD_FAB2_LIB.BASEBOARD_FAB2(SCH_1):SPI_PCH_CS0_R_N
  R7C16    1      A  RES         I33
  U7C1    J3  SPI0_FLASH_CS0_N  LBG_CORE_QAT_EXT_D  I34

SPI_PCH_IO2     @BASEBOARD_FAB2_LIB.BASEBOARD_FAB2(SCH_1):SPI_PCH_IO2
  R2P2     1      A  RES         I37
  R2R11    1      A  RES         I11
  R2R12    1      A  RES         I93
  U7C1    F5  SPI0_IO2  LBG_CORE_QAT_EXT_D  I34

SPI_PCH_IO2_R1   @BASEBOARD_FAB2_LIB.BASEBOARD_FAB2(SCH_1):SPI_PCH_IO2_R1
  R2R12    2      B  RES         I93
  U2T1     2    IA0  PI3B3257A_TSSOPLF  I75

SPI_PCH_IO3     @BASEBOARD_FAB2_LIB.BASEBOARD_FAB2(SCH_1):SPI_PCH_IO3
  R2T1     1      A  RES         I15
  R2T2     1      A  RES         I92
  R3N17    2      B  RES         I78
  U7C1    L1  SPI0_IO3  LBG_CORE_QAT_EXT_D  I34

SPI_PCH_IO3_R1   @BASEBOARD_FAB2_LIB.BASEBOARD_FAB2(SCH_1):SPI_PCH_IO3_R1
  R2T2     2      B  RES         I92
  U2T1     5    IB0  PI3B3257A_TSSOPLF  I75

SPI_PCH_MISO    @BASEBOARD_FAB2_LIB.BASEBOARD_FAB2(SCH_1):SPI_PCH_MISO
  R8E13    1      A  RES         I93
  R8F6     1      A  RES         I119
  U7C1    L3  SPI0_MISO_IO1  LBG_CORE_QAT_EXT_D  I34

SPI_PCH_MISO_R   @BASEBOARD_FAB2_LIB.BASEBOARD_FAB2(SCH_1):SPI_PCH_MISO_R
  R8F6     2      B  RES         I119
  U8F1    14    ID0  PI3B3257A_TSSOPLF  I74

SPI_PCH_MOSI    @BASEBOARD_FAB2_LIB.BASEBOARD_FAB2(SCH_1):SPI_PCH_MOSI
  R7C15    2      B  RES         I31
  R8E2     2      B  RES         I89
  R8E4     1      A  RES         I24
  R8E6     2      B  RES         I21
  R8E10    1      A  RES         I95
  U8F1     5    IB0  PI3B3257A_TSSOPLF  I74

SPI_PCH_MOSI_R   @BASEBOARD_FAB2_LIB.BASEBOARD_FAB2(SCH_1):SPI_PCH_MOSI_R
  R7C15    1      A  RES         I31
  U7C1    H4  SPI0_MOSI_IO0  LBG_CORE_QAT_EXT_D  I34

SPI_PCH_TPM_CLK_R   @BASEBOARD_FAB2_LIB.BASEBOARD_FAB2(SCH_1):SPI_PCH_TPM_CLK_R
  J8E1     1    IO1  SCONN11_H67026001_SM  I87
  R8E9     2      B  RES         I88

SPI_PCH_TPM_CS_N   @BASEBOARD_FAB2_LIB.BASEBOARD_FAB2(SCH_1):SPI_PCH_TPM_CS_N
  R8D35    1      A  RES         I92
  U7C1    K4  SPI0_TPM_CS_N  LBG_CORE_QAT_EXT_D  I34

SPI_PCH_TPM_CS_R_N   @BASEBOARD_FAB2_LIB.BASEBOARD_FAB2(SCH_1):SPI_PCH_TPM_CS_R_N
  J8E1     5    IO5  SCONN11_H67026001_SM  I87
  R8D35    2      B  RES         I92

SPI_PCH_TPM_MISO_R   @BASEBOARD_FAB2_LIB.BASEBOARD_FAB2(SCH_1):SPI_PCH_TPM_MISO_R
  J8E1     4    IO4  SCONN11_H67026001_SM  I87
  R8E13    2      B  RES         I93

SPI_PCH_TPM_MOSI_R   @BASEBOARD_FAB2_LIB.BASEBOARD_FAB2(SCH_1):SPI_PCH_TPM_MOSI_R
  J8E1     3    IO3  SCONN11_H67026001_SM  I87
  R8E10    2      B  RES         I95

SPI_SWITCH_CLK   @BASEBOARD_FAB2_LIB.BASEBOARD_FAB2(SCH_1):SPI_SWITCH_CLK
  R8F7     1      A  RES         I167
  R8F8     1      A  RES         I166
  U8F1     4     YA  PI3B3257A_TSSOPLF  I74

SPI_SWITCH_CS0_N   @BASEBOARD_FAB2_LIB.BASEBOARD_FAB2(SCH_1):SPI_SWITCH_CS0_N
  R2T8     2      B  RES         I106
  U2T2     2      B  TTL1G32_A   I100
  U2T3     2      B  TTL1G32_A   I99
  U8F1     9     YC  PI3B3257A_TSSOPLF  I74

SPI_SWITCH_MISO   @BASEBOARD_FAB2_LIB.BASEBOARD_FAB2(SCH_1):SPI_SWITCH_MISO
  R3T2     1      A  RES         I155
  R7F4     1      A  RES         I98
  U8F1    12     YD  PI3B3257A_TSSOPLF  I74

SPI_SWITCH_MOSI   @BASEBOARD_FAB2_LIB.BASEBOARD_FAB2(SCH_1):SPI_SWITCH_MOSI
  R3T10    1      A  RES         I184
  R7F29    1      A  RES         I181
  U8F1     7     YB  PI3B3257A_TSSOPLF  I74

SPI_SWITCH_MOSI_R0   @BASEBOARD_FAB2_LIB.BASEBOARD_FAB2(SCH_1):SPI_SWITCH_MOSI_R0
  R7F29    2      B  RES         I181
  U7F1    15  DI_IO<0>  W25Q256_XSOI  I146

SPI_SWITCH_MOSI_R1   @BASEBOARD_FAB2_LIB.BASEBOARD_FAB2(SCH_1):SPI_SWITCH_MOSI_R1
  R3T10    2      B  RES         I184
  U3T1    15  DI_IO<0>  W25Q256_XSOI  I165

SVID_ALERT0_CPU0_N   @BASEBOARD_FAB2_LIB.BASEBOARD_FAB2(SCH_1):SVID_ALERT0_CPU0_N
  R6N10    1      A  RES         I149
  U5D1   DE44  SVIDALERT_N<0>  SKX_EXT_B_BGA1  I259

SVID_ALERT0_CPU0_R_N   @BASEBOARD_FAB2_LIB.BASEBOARD_FAB2(SCH_1):SVID_ALERT0_CPU0_R_N
  J6B1   A19  IOA19  SCONN120_H61426002_SM  I56
  R3P1     2      B  RES         I61
  R4D67    2      B  RES         I26
  R6N1     1      A  RES         I164
  R6N10    2      B  RES         I149

SVID_ALERT0_CPU1_N   @BASEBOARD_FAB2_LIB.BASEBOARD_FAB2(SCH_1):SVID_ALERT0_CPU1_N
  R3B1     1      A  RES         I27
  U2D1   DE44  SVIDALERT_N<0>  SKX_EXT_B_BGA1  I172

SVID_ALERT0_CPU1_R_N   @BASEBOARD_FAB2_LIB.BASEBOARD_FAB2(SCH_1):SVID_ALERT0_CPU1_R_N
  J4B2   A19  IOA19  SCONN120_H61426002_SM  I46
  R1D3     2      B  RES         I37
  R3B1     2      B  RES         I27
  R3B2     1      A  RES         I19
  R4D56    2      B  RES         I16

SVID_ALERT1_CPU0_N   @BASEBOARD_FAB2_LIB.BASEBOARD_FAB2(SCH_1):SVID_ALERT1_CPU0_N
  R6B3     1      A  RES         I152
  U5D1   DL44  SVIDALERT_N<1>  SKX_EXT_B_BGA1  I259

SVID_ALERT1_CPU0_R_N   @BASEBOARD_FAB2_LIB.BASEBOARD_FAB2(SCH_1):SVID_ALERT1_CPU0_R_N
  J6B1   B19  IOB19  SCONN120_H61426002_SM  I56
  R6B1     2      B  RES         I161
  R6B3     2      B  RES         I152
  R7A11    2      B  RES         I15
  R7G4     2      B  RES         I302

SVID_ALERT1_CPU1_N   @BASEBOARD_FAB2_LIB.BASEBOARD_FAB2(SCH_1):SVID_ALERT1_CPU1_N
  R1C1     1      A  RES         I26
  U2D1   DL44  SVIDALERT_N<1>  SKX_EXT_B_BGA1  I172

SVID_ALERT1_CPU1_R_N   @BASEBOARD_FAB2_LIB.BASEBOARD_FAB2(SCH_1):SVID_ALERT1_CPU1_R_N
  J4B2   B19  IOB19  SCONN120_H61426002_SM  I46
  R1B11    2      B  RES         I16
  R1C1     2      B  RES         I26
  R1G9     2      B  RES         I16
  R9N1     2      B  RES          I4

SVID_ALERT_PVCCIO_CPU0   @BASEBOARD_FAB2_LIB.BASEBOARD_FAB2(SCH_1):SVID_ALERT_PVCCIO_CPU0
  EU3P1   17  VALRT_N  PXE1110B_QFN  I93
  R3P1     1      A  RES         I61

SVID_ALERT_PVCCIO_CPU1   @BASEBOARD_FAB2_LIB.BASEBOARD_FAB2(SCH_1):SVID_ALERT_PVCCIO_CPU1
  EU4D5   17  VALRT_N  PXE1110B_QFN  I96
  R4D56    1      A  RES         I16

SVID_ALERT_PVDDQ_ABC   @BASEBOARD_FAB2_LIB.BASEBOARD_FAB2(SCH_1):SVID_ALERT_PVDDQ_ABC
  EU7G1   17  VALRT_N  PXM1310B_QFN  I358
  R7G4     1      A  RES         I302

SVID_ALERT_PVDDQ_DEF   @BASEBOARD_FAB2_LIB.BASEBOARD_FAB2(SCH_1):SVID_ALERT_PVDDQ_DEF
  EU7A5   17  VALRT_N  PXM1310B_QFN  I75
  R7A11    1      A  RES         I15

SVID_ALERT_PVDDQ_GHJ   @BASEBOARD_FAB2_LIB.BASEBOARD_FAB2(SCH_1):SVID_ALERT_PVDDQ_GHJ
  EU1G2   17  VALRT_N  PXM1310B_QFN  I90
  R1G9     1      A  RES         I16

SVID_ALERT_PVDDQ_KLM   @BASEBOARD_FAB2_LIB.BASEBOARD_FAB2(SCH_1):SVID_ALERT_PVDDQ_KLM
  EU1B1   17  VALRT_N  PXM1310B_QFN  I90
  R1B11    1      A  RES         I16

SVID_CLK0_CPU0   @BASEBOARD_FAB2_LIB.BASEBOARD_FAB2(SCH_1):SVID_CLK0_CPU0
  R6N12    1      A  RES         I150
  U5D1   DC44  SVIDCLK<0>  SKX_EXT_B_BGA1  I259

SVID_CLK0_CPU0_R   @BASEBOARD_FAB2_LIB.BASEBOARD_FAB2(SCH_1):SVID_CLK0_CPU0_R
  J6B1   A20  IOA20  SCONN120_H61426002_SM  I56
  R3P15    1      A  RES         I29
  R3P17    2      B  RES         I28
  R4E6     1      A  RES         I56
  R4E9     2      B  RES         I52
  R6N12    2      B  RES         I150

SVID_CLK0_CPU1   @BASEBOARD_FAB2_LIB.BASEBOARD_FAB2(SCH_1):SVID_CLK0_CPU1
  R3B5     1      A  RES         I28
  U2D1   DC44  SVIDCLK<0>  SKX_EXT_B_BGA1  I172

SVID_CLK0_CPU1_R   @BASEBOARD_FAB2_LIB.BASEBOARD_FAB2(SCH_1):SVID_CLK0_CPU1_R
  J4B2   A20  IOA20  SCONN120_H61426002_SM  I46
  R1D9     1      A  RES         I54
  R3B5     2      B  RES         I28
  R4D51    1      A  RES         I46
  R6P33    2      B  RES         I30
  R9P2     2      B  RES         I53

SVID_CLK1_CPU0   @BASEBOARD_FAB2_LIB.BASEBOARD_FAB2(SCH_1):SVID_CLK1_CPU0
  R6B5     1      A  RES         I153
  U5D1   DG44  SVIDCLK<1>  SKX_EXT_B_BGA1  I259

SVID_CLK1_CPU0_R   @BASEBOARD_FAB2_LIB.BASEBOARD_FAB2(SCH_1):SVID_CLK1_CPU0_R
  J6B1   E20  IOE20  SCONN120_H61426002_SM  I56
  R3L13    2      B  RES         I47
  R3T11    2      B  RES         I330
  R6B5     2      B  RES         I153
  R7A17    1      A  RES         I48
  R7G24    1      A  RES         I331

SVID_CLK1_CPU1   @BASEBOARD_FAB2_LIB.BASEBOARD_FAB2(SCH_1):SVID_CLK1_CPU1
  R1C3     1      A  RES         I25
  U2D1   DG44  SVIDCLK<1>  SKX_EXT_B_BGA1  I172

SVID_CLK1_CPU1_R   @BASEBOARD_FAB2_LIB.BASEBOARD_FAB2(SCH_1):SVID_CLK1_CPU1_R
  J4B2   E20  IOE20  SCONN120_H61426002_SM  I46
  R1B8     1      A  RES         I53
  R1C3     2      B  RES         I25
  R1G7     1      A  RES         I53
  R9M6     2      B  RES         I50
  R9U4     2      B  RES         I50

SVID_CLK_PVCCIO_CPU0   @BASEBOARD_FAB2_LIB.BASEBOARD_FAB2(SCH_1):SVID_CLK_PVCCIO_CPU0
  EU3P1   15   VCLK  PXE1110B_QFN  I93
  R3P15    2      B  RES         I29

SVID_CLK_PVCCIO_CPU1   @BASEBOARD_FAB2_LIB.BASEBOARD_FAB2(SCH_1):SVID_CLK_PVCCIO_CPU1
  EU4D5   15   VCLK  PXE1110B_QFN  I96
  R4D51    2      B  RES         I46

SVID_CLK_PVDDQ_ABC   @BASEBOARD_FAB2_LIB.BASEBOARD_FAB2(SCH_1):SVID_CLK_PVDDQ_ABC
  EU7G1   15   VCLK  PXM1310B_QFN  I358
  R7G24    2      B  RES         I331

SVID_CLK_PVDDQ_DEF   @BASEBOARD_FAB2_LIB.BASEBOARD_FAB2(SCH_1):SVID_CLK_PVDDQ_DEF
  EU7A5   15   VCLK  PXM1310B_QFN  I75
  R7A17    2      B  RES         I48

SVID_CLK_PVDDQ_GHJ   @BASEBOARD_FAB2_LIB.BASEBOARD_FAB2(SCH_1):SVID_CLK_PVDDQ_GHJ
  EU1G2   15   VCLK  PXM1310B_QFN  I90
  R1G7     2      B  RES         I53

SVID_CLK_PVDDQ_KLM   @BASEBOARD_FAB2_LIB.BASEBOARD_FAB2(SCH_1):SVID_CLK_PVDDQ_KLM
  EU1B1   15   VCLK  PXM1310B_QFN  I90
  R1B8     2      B  RES         I53

SVID_DIO0_CPU0   @BASEBOARD_FAB2_LIB.BASEBOARD_FAB2(SCH_1):SVID_DIO0_CPU0
  R6N11    1      A  RES         I151
  U5D1   DB45  SVIDDATA<0>  SKX_EXT_B_BGA1  I259

SVID_DIO0_CPU0_R   @BASEBOARD_FAB2_LIB.BASEBOARD_FAB2(SCH_1):SVID_DIO0_CPU0_R
  J6B1   B20  IOB20  SCONN120_H61426002_SM  I56
  R3P11    1      A  RES         I16
  R3P13    2      B  RES         I17
  R4D66    2      B  RES         I98
  R4E10    2      B  RES         I20
  R6N2     1      A  RES         I163
  R6N11    2      B  RES         I151

SVID_DIO0_CPU1   @BASEBOARD_FAB2_LIB.BASEBOARD_FAB2(SCH_1):SVID_DIO0_CPU1
  R3B3     1      A  RES         I29
  U2D1   DB45  SVIDDATA<0>  SKX_EXT_B_BGA1  I172

SVID_DIO0_CPU1_R   @BASEBOARD_FAB2_LIB.BASEBOARD_FAB2(SCH_1):SVID_DIO0_CPU1_R
  J4B2   B20  IOB20  SCONN120_H61426002_SM  I46
  R1D2     2      B  RES         I38
  R3B3     2      B  RES         I29
  R3B4     1      A  RES         I21
  R4D54    1      A  RES         I37
  R6P35    2      B  RES         I27
  R9P1     2      B  RES          I4

SVID_DIO1_CPU0   @BASEBOARD_FAB2_LIB.BASEBOARD_FAB2(SCH_1):SVID_DIO1_CPU0
  R6B4     1      A  RES         I154
  U5D1   DJ44  SVIDDATA<1>  SKX_EXT_B_BGA1  I259

SVID_DIO1_CPU0_R   @BASEBOARD_FAB2_LIB.BASEBOARD_FAB2(SCH_1):SVID_DIO1_CPU0_R
  J6B1   F20  IOF20  SCONN120_H61426002_SM  I56
  R3L11    2      B  RES          I7
  R3U2     2      B  RES         I295
  R6B2     2      B  RES         I159
  R6B4     2      B  RES         I154
  R7A12    2      B  RES         I25
  R7G2     2      B  RES         I307

SVID_DIO1_CPU1   @BASEBOARD_FAB2_LIB.BASEBOARD_FAB2(SCH_1):SVID_DIO1_CPU1
  R1C2     1      A  RES         I24
  U2D1   DJ44  SVIDDATA<1>  SKX_EXT_B_BGA1  I172

SVID_DIO1_CPU1_R   @BASEBOARD_FAB2_LIB.BASEBOARD_FAB2(SCH_1):SVID_DIO1_CPU1_R
  J4B2   F20  IOF20  SCONN120_H61426002_SM  I46
  R1B10    2      B  RES         I23
  R1C2     2      B  RES         I24
  R1G10    2      B  RES         I23
  R9M7     2      B  RES          I8
  R9N2     2      B  RES          I7
  R9U3     2      B  RES          I8

SVID_VALERT_VCCIN_CPU0   @BASEBOARD_FAB2_LIB.BASEBOARD_FAB2(SCH_1):SVID_VALERT_VCCIN_CPU0
  EU4D4   19  VALRT_N  PXE1610B_QFN  I155
  R4D67    1      A  RES         I26

SVID_VALERT_VCCIN_CPU1   @BASEBOARD_FAB2_LIB.BASEBOARD_FAB2(SCH_1):SVID_VALERT_VCCIN_CPU1
  EU1C2   19  VALRT_N  PXE1610B_QFN  I130
  R1D3     1      A  RES         I37

SVID_VCLK_PVCCIN_CPU0   @BASEBOARD_FAB2_LIB.BASEBOARD_FAB2(SCH_1):SVID_VCLK_PVCCIN_CPU0
  EU4D4   17   VCLK  PXE1610B_QFN  I155
  R4E6     2      B  RES         I56

SVID_VCLK_PVCCIN_CPU1   @BASEBOARD_FAB2_LIB.BASEBOARD_FAB2(SCH_1):SVID_VCLK_PVCCIN_CPU1
  EU1C2   17   VCLK  PXE1610B_QFN  I130
  R1D9     2      B  RES         I54

SVID_VDIO_PVCCIN_CPU0   @BASEBOARD_FAB2_LIB.BASEBOARD_FAB2(SCH_1):SVID_VDIO_PVCCIN_CPU0
  EU4D4   18   VDIO  PXE1610B_QFN  I155
  R4D66    1      A  RES         I98

SVID_VDIO_PVCCIN_CPU1   @BASEBOARD_FAB2_LIB.BASEBOARD_FAB2(SCH_1):SVID_VDIO_PVCCIN_CPU1
  EU1C2   18   VDIO  PXE1610B_QFN  I130
  R1D2     1      A  RES         I38

SVID_VDIO_PVCCIO_CPU0   @BASEBOARD_FAB2_LIB.BASEBOARD_FAB2(SCH_1):SVID_VDIO_PVCCIO_CPU0
  EU3P1   16   VDIO  PXE1110B_QFN  I93
  R3P11    2      B  RES         I16

SVID_VDIO_PVCCIO_CPU1   @BASEBOARD_FAB2_LIB.BASEBOARD_FAB2(SCH_1):SVID_VDIO_PVCCIO_CPU1
  EU4D5   16   VDIO  PXE1110B_QFN  I96
  R4D54    2      B  RES         I37

SVID_VDIO_PVDDQ_ABC   @BASEBOARD_FAB2_LIB.BASEBOARD_FAB2(SCH_1):SVID_VDIO_PVDDQ_ABC
  EU7G1   16   VDIO  PXM1310B_QFN  I358
  R7G2     1      A  RES         I307

SVID_VDIO_PVDDQ_DEF   @BASEBOARD_FAB2_LIB.BASEBOARD_FAB2(SCH_1):SVID_VDIO_PVDDQ_DEF
  EU7A5   16   VDIO  PXM1310B_QFN  I75
  R7A12    1      A  RES         I25

SVID_VDIO_PVDDQ_GHJ   @BASEBOARD_FAB2_LIB.BASEBOARD_FAB2(SCH_1):SVID_VDIO_PVDDQ_GHJ
  EU1G2   16   VDIO  PXM1310B_QFN  I90
  R1G10    1      A  RES         I23

SVID_VDIO_PVDDQ_KLM   @BASEBOARD_FAB2_LIB.BASEBOARD_FAB2(SCH_1):SVID_VDIO_PVDDQ_KLM
  EU1B1   16   VDIO  PXM1310B_QFN  I90
  R1B10    1      A  RES         I23

TP_10GBE_KR0_MON_DN   @BASEBOARD_FAB2_LIB.BASEBOARD_FAB2(SCH_1):TP_10GBE_KR0_MON_DN
  U7C1   BL26  RSVD<39>  LBG_CORE_QAT_EXT_D  I73

TP_10GBE_KR0_MON_DP   @BASEBOARD_FAB2_LIB.BASEBOARD_FAB2(SCH_1):TP_10GBE_KR0_MON_DP
  U7C1   BN26  RSVD<40>  LBG_CORE_QAT_EXT_D  I73

TP_10GBE_KR1_MON_DN   @BASEBOARD_FAB2_LIB.BASEBOARD_FAB2(SCH_1):TP_10GBE_KR1_MON_DN
  U7C1   BL33  RSVD<43>  LBG_CORE_QAT_EXT_D  I73

TP_10GBE_KR1_MON_DP   @BASEBOARD_FAB2_LIB.BASEBOARD_FAB2(SCH_1):TP_10GBE_KR1_MON_DP
  U7C1   BN33  RSVD<44>  LBG_CORE_QAT_EXT_D  I73

TP_33P_33M_SMBADR   @BASEBOARD_FAB2_LIB.BASEBOARD_FAB2(SCH_1):TP_33P_33M_SMBADR
  EU8F2   22  33MHZ_SMBADR  ICS9FGP204_MLFP  I34

TP_ADC128_VREF   @BASEBOARD_FAB2_LIB.BASEBOARD_FAB2(SCH_1):TP_ADC128_VREF
  EU9G1    1   VREF  ADC128D818_SM  I52

TP_BIOS_RECOVER_BOOT   @BASEBOARD_FAB2_LIB.BASEBOARD_FAB2(SCH_1):TP_BIOS_RECOVER_BOOT
  J7G3     8    IO8  CONN12_C73564003  I174

TP_BIOS_USB_RECOVERY   @BASEBOARD_FAB2_LIB.BASEBOARD_FAB2(SCH_1):TP_BIOS_USB_RECOVERY
  J7G3     2    IO2  CONN12_C73564003  I174

TP_BMC_DISABLE   @BASEBOARD_FAB2_LIB.BASEBOARD_FAB2(SCH_1):TP_BMC_DISABLE
  J9G1     1    IO1  CONN12_C73564003  I128

TP_CD_HFI1_CPU1_I2CDAT   @BASEBOARD_FAB2_LIB.BASEBOARD_FAB2(SCH_1):TP_CD_HFI1_CPU1_I2CDAT
  U2D1   BH23  CD_HFI1_I2CDAT  SKX_EXT_B_BGA1  I23

TP_CD_HFI1_CPU1_I2CLK   @BASEBOARD_FAB2_LIB.BASEBOARD_FAB2(SCH_1):TP_CD_HFI1_CPU1_I2CLK
  U2D1   BJ22  CD_HFI1_I2CCLK  SKX_EXT_B_BGA1  I23

TP_CD_HFI1_CPU1_INT_N   @BASEBOARD_FAB2_LIB.BASEBOARD_FAB2(SCH_1):TP_CD_HFI1_CPU1_INT_N
  U2D1   BM21  CD_HFI1_INT_N  SKX_EXT_B_BGA1  I23

TP_CD_HFI1_CPU1_LED_N   @BASEBOARD_FAB2_LIB.BASEBOARD_FAB2(SCH_1):TP_CD_HFI1_CPU1_LED_N
  U2D1   BM23  CD_HFI1_LED_N  SKX_EXT_B_BGA1  I23

TP_CD_HFI1_CPU1_MODPRST_N   @BASEBOARD_FAB2_LIB.BASEBOARD_FAB2(SCH_1):TP_CD_HFI1_CPU1_MODPRST_N
  U2D1   BT19  CD_HFI1_MODPRST_N  SKX_EXT_B_BGA1  I23

TP_CD_HFI1_CPU1_RESET_N   @BASEBOARD_FAB2_LIB.BASEBOARD_FAB2(SCH_1):TP_CD_HFI1_CPU1_RESET_N
  U2D1   BK23  CD_HFI1_RESET_N  SKX_EXT_B_BGA1  I23

TP_CH_A_DIMM_A0_RFU_0   @BASEBOARD_FAB2_LIB.BASEBOARD_FAB2(SCH_1):TP_CH_A_DIMM_A0_RFU_0
  J4G1   205  RFU<0>  SCONN288_H44441004_PIP   I1

TP_CH_A_DIMM_A0_RFU_1   @BASEBOARD_FAB2_LIB.BASEBOARD_FAB2(SCH_1):TP_CH_A_DIMM_A0_RFU_1
  J4G1   227  RFU<1>  SCONN288_H44441004_PIP   I1

TP_CH_A_DIMM_A0_RFU_2   @BASEBOARD_FAB2_LIB.BASEBOARD_FAB2(SCH_1):TP_CH_A_DIMM_A0_RFU_2
  J4G1   144  RFU<2>  SCONN288_H44441004_PIP   I1

TP_CH_A_DIMM_A1_RFU_0   @BASEBOARD_FAB2_LIB.BASEBOARD_FAB2(SCH_1):TP_CH_A_DIMM_A1_RFU_0
  J6T1   205  RFU<0>  SCONN288_H44441003_PIP  I13

TP_CH_A_DIMM_A1_RFU_1   @BASEBOARD_FAB2_LIB.BASEBOARD_FAB2(SCH_1):TP_CH_A_DIMM_A1_RFU_1
  J6T1   227  RFU<1>  SCONN288_H44441003_PIP  I13

TP_CH_A_DIMM_A1_RFU_2   @BASEBOARD_FAB2_LIB.BASEBOARD_FAB2(SCH_1):TP_CH_A_DIMM_A1_RFU_2
  J6T1   144  RFU<2>  SCONN288_H44441003_PIP  I13

TP_CH_B_DIMM_B0_RFU_0   @BASEBOARD_FAB2_LIB.BASEBOARD_FAB2(SCH_1):TP_CH_B_DIMM_B0_RFU_0
  J4G2   205  RFU<0>  SCONN288_H44441004_PIP  I111

TP_CH_B_DIMM_B0_RFU_1   @BASEBOARD_FAB2_LIB.BASEBOARD_FAB2(SCH_1):TP_CH_B_DIMM_B0_RFU_1
  J4G2   227  RFU<1>  SCONN288_H44441004_PIP  I111

TP_CH_B_DIMM_B0_RFU_2   @BASEBOARD_FAB2_LIB.BASEBOARD_FAB2(SCH_1):TP_CH_B_DIMM_B0_RFU_2
  J4G2   144  RFU<2>  SCONN288_H44441004_PIP  I111

TP_CH_B_DIMM_B1_RFU_0   @BASEBOARD_FAB2_LIB.BASEBOARD_FAB2(SCH_1):TP_CH_B_DIMM_B1_RFU_0
  J6U1   205  RFU<0>  SCONN288_H44441003_PIP  I14

TP_CH_B_DIMM_B1_RFU_1   @BASEBOARD_FAB2_LIB.BASEBOARD_FAB2(SCH_1):TP_CH_B_DIMM_B1_RFU_1
  J6U1   227  RFU<1>  SCONN288_H44441003_PIP  I14

TP_CH_B_DIMM_B1_RFU_2   @BASEBOARD_FAB2_LIB.BASEBOARD_FAB2(SCH_1):TP_CH_B_DIMM_B1_RFU_2
  J6U1   144  RFU<2>  SCONN288_H44441003_PIP  I14

TP_CH_C_DIMM_C0_RFU_0   @BASEBOARD_FAB2_LIB.BASEBOARD_FAB2(SCH_1):TP_CH_C_DIMM_C0_RFU_0
  J4G3   205  RFU<0>  SCONN288_H44441004_PIP  I111

TP_CH_C_DIMM_C0_RFU_1   @BASEBOARD_FAB2_LIB.BASEBOARD_FAB2(SCH_1):TP_CH_C_DIMM_C0_RFU_1
  J4G3   227  RFU<1>  SCONN288_H44441004_PIP  I111

TP_CH_C_DIMM_C0_RFU_2   @BASEBOARD_FAB2_LIB.BASEBOARD_FAB2(SCH_1):TP_CH_C_DIMM_C0_RFU_2
  J4G3   144  RFU<2>  SCONN288_H44441004_PIP  I111

TP_CH_C_DIMM_C1_RFU_0   @BASEBOARD_FAB2_LIB.BASEBOARD_FAB2(SCH_1):TP_CH_C_DIMM_C1_RFU_0
  J6U2   205  RFU<0>  SCONN288_H44441003_PIP  I111

TP_CH_C_DIMM_C1_RFU_1   @BASEBOARD_FAB2_LIB.BASEBOARD_FAB2(SCH_1):TP_CH_C_DIMM_C1_RFU_1
  J6U2   227  RFU<1>  SCONN288_H44441003_PIP  I111

TP_CH_C_DIMM_C1_RFU_2   @BASEBOARD_FAB2_LIB.BASEBOARD_FAB2(SCH_1):TP_CH_C_DIMM_C1_RFU_2
  J6U2   144  RFU<2>  SCONN288_H44441003_PIP  I111

TP_CH_D_DIMM_D0_RFU_0   @BASEBOARD_FAB2_LIB.BASEBOARD_FAB2(SCH_1):TP_CH_D_DIMM_D0_RFU_0
  J4B1   205  RFU<0>  SCONN288_H44441004_PIP  I111

TP_CH_D_DIMM_D0_RFU_1   @BASEBOARD_FAB2_LIB.BASEBOARD_FAB2(SCH_1):TP_CH_D_DIMM_D0_RFU_1
  J4B1   227  RFU<1>  SCONN288_H44441004_PIP  I111

TP_CH_D_DIMM_D0_RFU_2   @BASEBOARD_FAB2_LIB.BASEBOARD_FAB2(SCH_1):TP_CH_D_DIMM_D0_RFU_2
  J4B1   144  RFU<2>  SCONN288_H44441004_PIP  I111

TP_CH_D_DIMM_D1_RFU_0   @BASEBOARD_FAB2_LIB.BASEBOARD_FAB2(SCH_1):TP_CH_D_DIMM_D1_RFU_0
  J6M1   205  RFU<0>  SCONN288_H44441003_PIP  I158

TP_CH_D_DIMM_D1_RFU_1   @BASEBOARD_FAB2_LIB.BASEBOARD_FAB2(SCH_1):TP_CH_D_DIMM_D1_RFU_1
  J6M1   227  RFU<1>  SCONN288_H44441003_PIP  I158

TP_CH_D_DIMM_D1_RFU_2   @BASEBOARD_FAB2_LIB.BASEBOARD_FAB2(SCH_1):TP_CH_D_DIMM_D1_RFU_2
  J6M1   144  RFU<2>  SCONN288_H44441003_PIP  I158

TP_CH_E_DIMM_E0_RFU_0   @BASEBOARD_FAB2_LIB.BASEBOARD_FAB2(SCH_1):TP_CH_E_DIMM_E0_RFU_0
  J4A2   205  RFU<0>  SCONN288_H44441004_PIP  I111

TP_CH_E_DIMM_E0_RFU_1   @BASEBOARD_FAB2_LIB.BASEBOARD_FAB2(SCH_1):TP_CH_E_DIMM_E0_RFU_1
  J4A2   227  RFU<1>  SCONN288_H44441004_PIP  I111

TP_CH_E_DIMM_E0_RFU_2   @BASEBOARD_FAB2_LIB.BASEBOARD_FAB2(SCH_1):TP_CH_E_DIMM_E0_RFU_2
  J4A2   144  RFU<2>  SCONN288_H44441004_PIP  I111

TP_CH_E_DIMM_E1_RFU_0   @BASEBOARD_FAB2_LIB.BASEBOARD_FAB2(SCH_1):TP_CH_E_DIMM_E1_RFU_0
  J6L2   205  RFU<0>  SCONN288_H44441003_PIP  I12

TP_CH_E_DIMM_E1_RFU_1   @BASEBOARD_FAB2_LIB.BASEBOARD_FAB2(SCH_1):TP_CH_E_DIMM_E1_RFU_1
  J6L2   227  RFU<1>  SCONN288_H44441003_PIP  I12

TP_CH_E_DIMM_E1_RFU_2   @BASEBOARD_FAB2_LIB.BASEBOARD_FAB2(SCH_1):TP_CH_E_DIMM_E1_RFU_2
  J6L2   144  RFU<2>  SCONN288_H44441003_PIP  I12

TP_CH_F_DIMM_F0_RFU_0   @BASEBOARD_FAB2_LIB.BASEBOARD_FAB2(SCH_1):TP_CH_F_DIMM_F0_RFU_0
  J4A1   205  RFU<0>  SCONN288_H44441004_PIP  I111

TP_CH_F_DIMM_F0_RFU_1   @BASEBOARD_FAB2_LIB.BASEBOARD_FAB2(SCH_1):TP_CH_F_DIMM_F0_RFU_1
  J4A1   227  RFU<1>  SCONN288_H44441004_PIP  I111

TP_CH_F_DIMM_F0_RFU_2   @BASEBOARD_FAB2_LIB.BASEBOARD_FAB2(SCH_1):TP_CH_F_DIMM_F0_RFU_2
  J4A1   144  RFU<2>  SCONN288_H44441004_PIP  I111

TP_CH_F_DIMM_F1_RFU_0   @BASEBOARD_FAB2_LIB.BASEBOARD_FAB2(SCH_1):TP_CH_F_DIMM_F1_RFU_0
  J6L1   205  RFU<0>  SCONN288_H44441003_PIP  I111

TP_CH_F_DIMM_F1_RFU_1   @BASEBOARD_FAB2_LIB.BASEBOARD_FAB2(SCH_1):TP_CH_F_DIMM_F1_RFU_1
  J6L1   227  RFU<1>  SCONN288_H44441003_PIP  I111

TP_CH_F_DIMM_F1_RFU_2   @BASEBOARD_FAB2_LIB.BASEBOARD_FAB2(SCH_1):TP_CH_F_DIMM_F1_RFU_2
  J6L1   144  RFU<2>  SCONN288_H44441003_PIP  I111

TP_CH_G_DIMM0_RFU_0   @BASEBOARD_FAB2_LIB.BASEBOARD_FAB2(SCH_1):TP_CH_G_DIMM0_RFU_0
  J9T1   205  RFU<0>  SCONN288_H44441003_PIP  I13

TP_CH_G_DIMM0_RFU_1   @BASEBOARD_FAB2_LIB.BASEBOARD_FAB2(SCH_1):TP_CH_G_DIMM0_RFU_1
  J9T1   227  RFU<1>  SCONN288_H44441003_PIP  I13

TP_CH_G_DIMM0_RFU_2   @BASEBOARD_FAB2_LIB.BASEBOARD_FAB2(SCH_1):TP_CH_G_DIMM0_RFU_2
  J9T1   144  RFU<2>  SCONN288_H44441003_PIP  I13

TP_CH_G_DIMM_G0_RFU_0   @BASEBOARD_FAB2_LIB.BASEBOARD_FAB2(SCH_1):TP_CH_G_DIMM_G0_RFU_0
  J1G1   205  RFU<0>  SCONN288_H44441004_PIP  I111

TP_CH_G_DIMM_G0_RFU_1   @BASEBOARD_FAB2_LIB.BASEBOARD_FAB2(SCH_1):TP_CH_G_DIMM_G0_RFU_1
  J1G1   227  RFU<1>  SCONN288_H44441004_PIP  I111

TP_CH_G_DIMM_G0_RFU_2   @BASEBOARD_FAB2_LIB.BASEBOARD_FAB2(SCH_1):TP_CH_G_DIMM_G0_RFU_2
  J1G1   144  RFU<2>  SCONN288_H44441004_PIP  I111

TP_CH_H_DIMM0_RFU_0   @BASEBOARD_FAB2_LIB.BASEBOARD_FAB2(SCH_1):TP_CH_H_DIMM0_RFU_0
  J9U1   205  RFU<0>  SCONN288_H44441003_PIP  I24

TP_CH_H_DIMM0_RFU_1   @BASEBOARD_FAB2_LIB.BASEBOARD_FAB2(SCH_1):TP_CH_H_DIMM0_RFU_1
  J9U1   227  RFU<1>  SCONN288_H44441003_PIP  I24

TP_CH_H_DIMM0_RFU_2   @BASEBOARD_FAB2_LIB.BASEBOARD_FAB2(SCH_1):TP_CH_H_DIMM0_RFU_2
  J9U1   144  RFU<2>  SCONN288_H44441003_PIP  I24

TP_CH_H_DIMM_H0_RFU_0   @BASEBOARD_FAB2_LIB.BASEBOARD_FAB2(SCH_1):TP_CH_H_DIMM_H0_RFU_0
  J1G2   205  RFU<0>  SCONN288_H44441004_PIP  I111

TP_CH_H_DIMM_H0_RFU_1   @BASEBOARD_FAB2_LIB.BASEBOARD_FAB2(SCH_1):TP_CH_H_DIMM_H0_RFU_1
  J1G2   227  RFU<1>  SCONN288_H44441004_PIP  I111

TP_CH_H_DIMM_H0_RFU_2   @BASEBOARD_FAB2_LIB.BASEBOARD_FAB2(SCH_1):TP_CH_H_DIMM_H0_RFU_2
  J1G2   144  RFU<2>  SCONN288_H44441004_PIP  I111

TP_CH_J_DIMM_J0_RFU_0   @BASEBOARD_FAB2_LIB.BASEBOARD_FAB2(SCH_1):TP_CH_J_DIMM_J0_RFU_0
  J1G3   205  RFU<0>  SCONN288_H44441004_PIP  I186

TP_CH_J_DIMM_J0_RFU_1   @BASEBOARD_FAB2_LIB.BASEBOARD_FAB2(SCH_1):TP_CH_J_DIMM_J0_RFU_1
  J1G3   227  RFU<1>  SCONN288_H44441004_PIP  I186

TP_CH_J_DIMM_J0_RFU_2   @BASEBOARD_FAB2_LIB.BASEBOARD_FAB2(SCH_1):TP_CH_J_DIMM_J0_RFU_2
  J1G3   144  RFU<2>  SCONN288_H44441004_PIP  I186

TP_CH_J_DIMM_J1_RFU_0   @BASEBOARD_FAB2_LIB.BASEBOARD_FAB2(SCH_1):TP_CH_J_DIMM_J1_RFU_0
  J9U2   205  RFU<0>  SCONN288_H44441003_PIP  I187

TP_CH_J_DIMM_J1_RFU_1   @BASEBOARD_FAB2_LIB.BASEBOARD_FAB2(SCH_1):TP_CH_J_DIMM_J1_RFU_1
  J9U2   227  RFU<1>  SCONN288_H44441003_PIP  I187

TP_CH_J_DIMM_J1_RFU_2   @BASEBOARD_FAB2_LIB.BASEBOARD_FAB2(SCH_1):TP_CH_J_DIMM_J1_RFU_2
  J9U2   144  RFU<2>  SCONN288_H44441003_PIP  I187

TP_CH_K_DIMM0_RFU_0   @BASEBOARD_FAB2_LIB.BASEBOARD_FAB2(SCH_1):TP_CH_K_DIMM0_RFU_0
  J9M1   205  RFU<0>  SCONN288_H44441003_PIP  I14

TP_CH_K_DIMM0_RFU_1   @BASEBOARD_FAB2_LIB.BASEBOARD_FAB2(SCH_1):TP_CH_K_DIMM0_RFU_1
  J9M1   227  RFU<1>  SCONN288_H44441003_PIP  I14

TP_CH_K_DIMM0_RFU_2   @BASEBOARD_FAB2_LIB.BASEBOARD_FAB2(SCH_1):TP_CH_K_DIMM0_RFU_2
  J9M1   144  RFU<2>  SCONN288_H44441003_PIP  I14

TP_CH_K_DIMM_K0_RFU_0   @BASEBOARD_FAB2_LIB.BASEBOARD_FAB2(SCH_1):TP_CH_K_DIMM_K0_RFU_0
  J1B1   205  RFU<0>  SCONN288_H44441004_PIP  I111

TP_CH_K_DIMM_K0_RFU_1   @BASEBOARD_FAB2_LIB.BASEBOARD_FAB2(SCH_1):TP_CH_K_DIMM_K0_RFU_1
  J1B1   227  RFU<1>  SCONN288_H44441004_PIP  I111

TP_CH_K_DIMM_K0_RFU_2   @BASEBOARD_FAB2_LIB.BASEBOARD_FAB2(SCH_1):TP_CH_K_DIMM_K0_RFU_2
  J1B1   144  RFU<2>  SCONN288_H44441004_PIP  I111

TP_CH_L_DIMM0_RFU_0   @BASEBOARD_FAB2_LIB.BASEBOARD_FAB2(SCH_1):TP_CH_L_DIMM0_RFU_0
  J9L2   205  RFU<0>  SCONN288_H44441003_PIP  I12

TP_CH_L_DIMM0_RFU_1   @BASEBOARD_FAB2_LIB.BASEBOARD_FAB2(SCH_1):TP_CH_L_DIMM0_RFU_1
  J9L2   227  RFU<1>  SCONN288_H44441003_PIP  I12

TP_CH_L_DIMM0_RFU_2   @BASEBOARD_FAB2_LIB.BASEBOARD_FAB2(SCH_1):TP_CH_L_DIMM0_RFU_2
  J9L2   144  RFU<2>  SCONN288_H44441003_PIP  I12

TP_CH_L_DIMM_L0_RFU_0   @BASEBOARD_FAB2_LIB.BASEBOARD_FAB2(SCH_1):TP_CH_L_DIMM_L0_RFU_0
  J1A2   205  RFU<0>  SCONN288_H44441004_PIP  I111

TP_CH_L_DIMM_L0_RFU_1   @BASEBOARD_FAB2_LIB.BASEBOARD_FAB2(SCH_1):TP_CH_L_DIMM_L0_RFU_1
  J1A2   227  RFU<1>  SCONN288_H44441004_PIP  I111

TP_CH_L_DIMM_L0_RFU_2   @BASEBOARD_FAB2_LIB.BASEBOARD_FAB2(SCH_1):TP_CH_L_DIMM_L0_RFU_2
  J1A2   144  RFU<2>  SCONN288_H44441004_PIP  I111

TP_CH_M_DIMM_M0_RFU_0   @BASEBOARD_FAB2_LIB.BASEBOARD_FAB2(SCH_1):TP_CH_M_DIMM_M0_RFU_0
  J1A1   205  RFU<0>  SCONN288_H44441004_PIP  I186

TP_CH_M_DIMM_M0_RFU_1   @BASEBOARD_FAB2_LIB.BASEBOARD_FAB2(SCH_1):TP_CH_M_DIMM_M0_RFU_1
  J1A1   227  RFU<1>  SCONN288_H44441004_PIP  I186

TP_CH_M_DIMM_M0_RFU_2   @BASEBOARD_FAB2_LIB.BASEBOARD_FAB2(SCH_1):TP_CH_M_DIMM_M0_RFU_2
  J1A1   144  RFU<2>  SCONN288_H44441004_PIP  I186

TP_CH_M_DIMM_M1_RFU_0   @BASEBOARD_FAB2_LIB.BASEBOARD_FAB2(SCH_1):TP_CH_M_DIMM_M1_RFU_0
  J9L1   205  RFU<0>  SCONN288_H44441003_PIP  I111

TP_CH_M_DIMM_M1_RFU_1   @BASEBOARD_FAB2_LIB.BASEBOARD_FAB2(SCH_1):TP_CH_M_DIMM_M1_RFU_1
  J9L1   227  RFU<1>  SCONN288_H44441003_PIP  I111

TP_CH_M_DIMM_M1_RFU_2   @BASEBOARD_FAB2_LIB.BASEBOARD_FAB2(SCH_1):TP_CH_M_DIMM_M1_RFU_2
  J9L1   144  RFU<2>  SCONN288_H44441003_PIP  I111

TP_CLK5_50M_CKMNG   @BASEBOARD_FAB2_LIB.BASEBOARD_FAB2(SCH_1):TP_CLK5_50M_CKMNG
  EU8F2   24  RMII<5>  ICS9FGP204_MLFP  I34

TP_CLK_100M_NSSCC0_DN   @BASEBOARD_FAB2_LIB.BASEBOARD_FAB2(SCH_1):TP_CLK_100M_NSSCC0_DN
  U7C1   A32  CLKOUT_NSSCCAP0N  LBG_CORE_QAT_EXT_D  I40

TP_CLK_100M_NSSCC0_DP   @BASEBOARD_FAB2_LIB.BASEBOARD_FAB2(SCH_1):TP_CLK_100M_NSSCC0_DP
  U7C1   C32  CLKOUT_NSSCCAP0P  LBG_CORE_QAT_EXT_D  I40

TP_CLK_100M_NSSCC1_DN   @BASEBOARD_FAB2_LIB.BASEBOARD_FAB2(SCH_1):TP_CLK_100M_NSSCC1_DN
  U7C1   B38  CLKOUT_NSSCCAP1N  LBG_CORE_QAT_EXT_D  I40

TP_CLK_100M_NSSCC1_DP   @BASEBOARD_FAB2_LIB.BASEBOARD_FAB2(SCH_1):TP_CLK_100M_NSSCC1_DP
  U7C1   D38  CLKOUT_NSSCCAP1P  LBG_CORE_QAT_EXT_D  I40

TP_CLK_100M_PLAT1_DN   @BASEBOARD_FAB2_LIB.BASEBOARD_FAB2(SCH_1):TP_CLK_100M_PLAT1_DN
  U7C1   B40  CLKOUT_PLAT1N  LBG_CORE_QAT_EXT_D  I40

TP_CLK_100M_PLAT1_DP   @BASEBOARD_FAB2_LIB.BASEBOARD_FAB2(SCH_1):TP_CLK_100M_PLAT1_DP
  U7C1   D40  CLKOUT_PLAT1P  LBG_CORE_QAT_EXT_D  I40

TP_CLK_100M_R_DN   @BASEBOARD_FAB2_LIB.BASEBOARD_FAB2(SCH_1):TP_CLK_100M_R_DN
  EU8F2    8  CPUCLKC0  ICS9FGP204_MLFP  I34

TP_CLK_100M_R_DP   @BASEBOARD_FAB2_LIB.BASEBOARD_FAB2(SCH_1):TP_CLK_100M_R_DP
  EU8F2    7  CPUCLKT0  ICS9FGP204_MLFP  I34

TP_CLK_100M_SRC12_DN   @BASEBOARD_FAB2_LIB.BASEBOARD_FAB2(SCH_1):TP_CLK_100M_SRC12_DN
  U7C1   K24  CLKOUT_SRCN<12>  LBG_CORE_QAT_EXT_D  I40

TP_CLK_100M_SRC12_DP   @BASEBOARD_FAB2_LIB.BASEBOARD_FAB2(SCH_1):TP_CLK_100M_SRC12_DP
  U7C1   H24  CLKOUT_SRCP<12>  LBG_CORE_QAT_EXT_D  I40

TP_CLK_100M_SRC13_DN   @BASEBOARD_FAB2_LIB.BASEBOARD_FAB2(SCH_1):TP_CLK_100M_SRC13_DN
  U7C1   C24  CLKOUT_SRCN<13>  LBG_CORE_QAT_EXT_D  I40

TP_CLK_100M_SRC13_DP   @BASEBOARD_FAB2_LIB.BASEBOARD_FAB2(SCH_1):TP_CLK_100M_SRC13_DP
  U7C1   A24  CLKOUT_SRCP<13>  LBG_CORE_QAT_EXT_D  I40

TP_CLK_125M     @BASEBOARD_FAB2_LIB.BASEBOARD_FAB2(SCH_1):TP_CLK_125M
  EU8F2   36  RGMII<1>  ICS9FGP204_MLFP  I34

TP_CLK_125M_BMCA   @BASEBOARD_FAB2_LIB.BASEBOARD_FAB2(SCH_1):TP_CLK_125M_BMCA
  EU8F2   37  RGMII<0>  ICS9FGP204_MLFP  I34

TP_CLK_24M_PMSYNC2   @BASEBOARD_FAB2_LIB.BASEBOARD_FAB2(SCH_1):TP_CLK_24M_PMSYNC2
  U7C1   BV51  CLOCKSE_PMSYNCCLK2  LBG_CORE_QAT_EXT_D  I40

TP_CLK_96M_CKMNG_N   @BASEBOARD_FAB2_LIB.BASEBOARD_FAB2(SCH_1):TP_CLK_96M_CKMNG_N
  EU8F2    4  DOT96SSC  ICS9FGP204_MLFP  I34

TP_CLK_96M_CKMNG_P   @BASEBOARD_FAB2_LIB.BASEBOARD_FAB2(SCH_1):TP_CLK_96M_CKMNG_P
  EU8F2    3  DOT96SST  ICS9FGP204_MLFP  I34

TP_CPLD1_PB11B_PCLKC2_0   @BASEBOARD_FAB2_LIB.BASEBOARD_FAB2(SCH_1):TP_CPLD1_PB11B_PCLKC2_0
  U8D7    R8  PB11B_PCLKC2_0  LCMXO2_A_256BGA  I179

TP_CPLD1_PB16A_PCLKT2_1   @BASEBOARD_FAB2_LIB.BASEBOARD_FAB2(SCH_1):TP_CPLD1_PB16A_PCLKT2_1
  U8D7    T9  PB16A_PCLKT2_1  LCMXO2_A_256BGA  I179

TP_CPLD1_PB16B_PCLKC2_1   @BASEBOARD_FAB2_LIB.BASEBOARD_FAB2(SCH_1):TP_CPLD1_PB16B_PCLKC2_1
  U8D7    P9  PB16B_PCLKC2_1  LCMXO2_A_256BGA  I179

TP_CPLD1_PB25B_SI_SISPI   @BASEBOARD_FAB2_LIB.BASEBOARD_FAB2(SCH_1):TP_CPLD1_PB25B_SI_SISPI
  U8D7   P13  PB25B_SI_SISPI  LCMXO2_A_256BGA  I179

TP_CPLD1_PB5A_CSSPIN   @BASEBOARD_FAB2_LIB.BASEBOARD_FAB2(SCH_1):TP_CPLD1_PB5A_CSSPIN
  U8D7    R5  PB5A_CSSPIN  LCMXO2_A_256BGA  I179

TP_CPLD1_PB8A_MCLK_CCLK   @BASEBOARD_FAB2_LIB.BASEBOARD_FAB2(SCH_1):TP_CPLD1_PB8A_MCLK_CCLK
  U8D7    P6  PB8A_MCLK_CCLK  LCMXO2_A_256BGA  I179

TP_CPLD1_PB8B_SO_SPISO   @BASEBOARD_FAB2_LIB.BASEBOARD_FAB2(SCH_1):TP_CPLD1_PB8B_SO_SPISO
  U8D7    T6  PB8B_SO_SPISO  LCMXO2_A_256BGA  I179

TP_CPLD1_PB8D   @BASEBOARD_FAB2_LIB.BASEBOARD_FAB2(SCH_1):TP_CPLD1_PB8D
  U8D7    L7   PB8D  LCMXO2_A_256BGA  I179

TP_CPLD1_PL11A   @BASEBOARD_FAB2_LIB.BASEBOARD_FAB2(SCH_1):TP_CPLD1_PL11A
  U8D7    L3  PL11B  LCMXO2_A_256BGA  I179

TP_CPLD1_PL1A_L_GPLLT_FB   @BASEBOARD_FAB2_LIB.BASEBOARD_FAB2(SCH_1):TP_CPLD1_PL1A_L_GPLLT_FB
  U8D7    D3  PL1A_L_GPLLT_FB  LCMXO2_A_256BGA  I179

TP_CPLD1_PL1B_L_GPLLC_FB   @BASEBOARD_FAB2_LIB.BASEBOARD_FAB2(SCH_1):TP_CPLD1_PL1B_L_GPLLC_FB
  U8D7    D1  PL1B_L_GPLLC_FB  LCMXO2_A_256BGA  I179

TP_CPLD1_PL2B_L_GPLLC_IN   @BASEBOARD_FAB2_LIB.BASEBOARD_FAB2(SCH_1):TP_CPLD1_PL2B_L_GPLLC_IN
  U8D7    E3  PL2B_L_GPLLC_IN  LCMXO2_A_256BGA  I179

TP_CPLD1_PL7D_PCLKT4_0   @BASEBOARD_FAB2_LIB.BASEBOARD_FAB2(SCH_1):TP_CPLD1_PL7D_PCLKT4_0
  U8D7    J3  PL7D_PCLKC4_0  LCMXO2_A_256BGA  I179

TP_CPLD1_PR10C   @BASEBOARD_FAB2_LIB.BASEBOARD_FAB2(SCH_1):TP_CPLD1_PR10C
  U8D7   J11  PR10C  LCMXO2_A_256BGA  I59

TP_CPLD1_PR11B   @BASEBOARD_FAB2_LIB.BASEBOARD_FAB2(SCH_1):TP_CPLD1_PR11B
  U8D7   L14  PR11B  LCMXO2_A_256BGA  I59

TP_CPLD1_PR12D   @BASEBOARD_FAB2_LIB.BASEBOARD_FAB2(SCH_1):TP_CPLD1_PR12D
  U8D7   L13  PR12D  LCMXO2_A_256BGA  I59

TP_CPLD1_PR7A_PCLKT1_0   @BASEBOARD_FAB2_LIB.BASEBOARD_FAB2(SCH_1):TP_CPLD1_PR7A_PCLKT1_0
  U8D7   H14  PR7A_PCLKT1_0  LCMXO2_A_256BGA  I59

TP_CPLD1_PR7B_PCLKC1_0   @BASEBOARD_FAB2_LIB.BASEBOARD_FAB2(SCH_1):TP_CPLD1_PR7B_PCLKC1_0
  U8D7   H16  PR7B_PCLKC1_0  LCMXO2_A_256BGA  I59

TP_CPLD1_PR7C   @BASEBOARD_FAB2_LIB.BASEBOARD_FAB2(SCH_1):TP_CPLD1_PR7C
  U8D7   J16   PR7C  LCMXO2_A_256BGA  I59

TP_CPLD1_PR7D   @BASEBOARD_FAB2_LIB.BASEBOARD_FAB2(SCH_1):TP_CPLD1_PR7D
  U8D7   J14   PR7D  LCMXO2_A_256BGA  I59

TP_CPLD1_PR9A   @BASEBOARD_FAB2_LIB.BASEBOARD_FAB2(SCH_1):TP_CPLD1_PR9A
  U8D7   J15   PR9A  LCMXO2_A_256BGA  I59

TP_CPLD1_PR9C   @BASEBOARD_FAB2_LIB.BASEBOARD_FAB2(SCH_1):TP_CPLD1_PR9C
  U8D7   H11   PR9C  LCMXO2_A_256BGA  I59

TP_CPLD1_PR9D   @BASEBOARD_FAB2_LIB.BASEBOARD_FAB2(SCH_1):TP_CPLD1_PR9D
  U8D7   J13   PR9D  LCMXO2_A_256BGA  I59

TP_CPLD1_PT11A   @BASEBOARD_FAB2_LIB.BASEBOARD_FAB2(SCH_1):TP_CPLD1_PT11A
  U8D7    A5  PT11A  LCMXO2_A_256BGA  I59

TP_CPLD1_PT11B   @BASEBOARD_FAB2_LIB.BASEBOARD_FAB2(SCH_1):TP_CPLD1_PT11B
  U8D7    B6  PT11B  LCMXO2_A_256BGA  I59

TP_CPLD1_PT13A   @BASEBOARD_FAB2_LIB.BASEBOARD_FAB2(SCH_1):TP_CPLD1_PT13A
  U8D7    B7  PT13A  LCMXO2_A_256BGA  I59

TP_CPLD1_PT16B   @BASEBOARD_FAB2_LIB.BASEBOARD_FAB2(SCH_1):TP_CPLD1_PT16B
  U8D7    E8  PT16B  LCMXO2_A_256BGA  I59

TP_CPLD1_PT17B_PCLKC0_1   @BASEBOARD_FAB2_LIB.BASEBOARD_FAB2(SCH_1):TP_CPLD1_PT17B_PCLKC0_1
  U8D7    A8  PT17B_PCLKC0_1  LCMXO2_A_256BGA  I59

TP_CPLD1_PT17C   @BASEBOARD_FAB2_LIB.BASEBOARD_FAB2(SCH_1):TP_CPLD1_PT17C
  U8D7    D8  PT17C  LCMXO2_A_256BGA  I59

TP_CPLD1_PT19D   @BASEBOARD_FAB2_LIB.BASEBOARD_FAB2(SCH_1):TP_CPLD1_PT19D
  U8D7   E11  PT19D  LCMXO2_A_256BGA  I59

TP_CPLD1_PT20A   @BASEBOARD_FAB2_LIB.BASEBOARD_FAB2(SCH_1):TP_CPLD1_PT20A
  U8D7   D10  PT20A  LCMXO2_A_256BGA  I59

TP_CPLD1_PT20B   @BASEBOARD_FAB2_LIB.BASEBOARD_FAB2(SCH_1):TP_CPLD1_PT20B
  U8D7   E10  PT20B  LCMXO2_A_256BGA  I59

TP_CPLD1_PT20D_PROGRAMN   @BASEBOARD_FAB2_LIB.BASEBOARD_FAB2(SCH_1):TP_CPLD1_PT20D_PROGRAMN
  U8D7   B10  PT20D_PROGRAMN  LCMXO2_A_256BGA  I59

TP_CPLD1_PT22C   @BASEBOARD_FAB2_LIB.BASEBOARD_FAB2(SCH_1):TP_CPLD1_PT22C
  U8D7   B13  PT22C  LCMXO2_A_256BGA  I59

TP_CPLD1_PT22D   @BASEBOARD_FAB2_LIB.BASEBOARD_FAB2(SCH_1):TP_CPLD1_PT22D
  U8D7   A14  PT22D  LCMXO2_A_256BGA  I59

TP_CPLD1_PT24B   @BASEBOARD_FAB2_LIB.BASEBOARD_FAB2(SCH_1):TP_CPLD1_PT24B
  U8D7   A15  PT24B  LCMXO2_A_256BGA  I59

TP_CPLD1_PT24C_INITN   @BASEBOARD_FAB2_LIB.BASEBOARD_FAB2(SCH_1):TP_CPLD1_PT24C_INITN
  U8D7   A13  PT24C_INITN  LCMXO2_A_256BGA  I59

TP_CPLD1_PT24D_DONE   @BASEBOARD_FAB2_LIB.BASEBOARD_FAB2(SCH_1):TP_CPLD1_PT24D_DONE
  U8D7   C13  PT24D_DONE  LCMXO2_A_256BGA  I59

TP_CPU0_KTI2_AMONV   @BASEBOARD_FAB2_LIB.BASEBOARD_FAB2(SCH_1):TP_CPU0_KTI2_AMONV
  U5D1   CN22  RSVD<77>  SKX_EXT_B_BGA1  I127

TP_CPU0_KTI2_DFX_DN   @BASEBOARD_FAB2_LIB.BASEBOARD_FAB2(SCH_1):TP_CPU0_KTI2_DFX_DN
  U5D1   CW22  RSVD<63>  SKX_EXT_B_BGA1  I127

TP_CPU0_PE_HP_SCL   @BASEBOARD_FAB2_LIB.BASEBOARD_FAB2(SCH_1):TP_CPU0_PE_HP_SCL
  U5D1   AM19  PE_HP_SCL  SKX_EXT_B_BGA1  I259

TP_CPU0_PE_HP_SDA   @BASEBOARD_FAB2_LIB.BASEBOARD_FAB2(SCH_1):TP_CPU0_PE_HP_SDA
  U5D1   AL18  PE_HP_SDA  SKX_EXT_B_BGA1  I259

TP_CPU0_PROCDIS_G_N   @BASEBOARD_FAB2_LIB.BASEBOARD_FAB2(SCH_1):TP_CPU0_PROCDIS_G_N
  U5D1   AB17  PROCDIS_N  SKX_EXT_B_BGA1  I259

TP_CPU0_RSVD_0   @BASEBOARD_FAB2_LIB.BASEBOARD_FAB2(SCH_1):TP_CPU0_RSVD_0
  U5D1   EF83  RSVD<0>  SKX_EXT_B_BGA1  I127

TP_CPU0_RSVD_1   @BASEBOARD_FAB2_LIB.BASEBOARD_FAB2(SCH_1):TP_CPU0_RSVD_1
  U5D1   EF81  RSVD<1>  SKX_EXT_B_BGA1  I127

TP_CPU0_RSVD_2   @BASEBOARD_FAB2_LIB.BASEBOARD_FAB2(SCH_1):TP_CPU0_RSVD_2
  U5D1   EF77  RSVD<2>  SKX_EXT_B_BGA1  I127

TP_CPU0_RSVD_3   @BASEBOARD_FAB2_LIB.BASEBOARD_FAB2(SCH_1):TP_CPU0_RSVD_3
  U5D1   EF47  RSVD<3>  SKX_EXT_B_BGA1  I127

TP_CPU0_RSVD_4   @BASEBOARD_FAB2_LIB.BASEBOARD_FAB2(SCH_1):TP_CPU0_RSVD_4
  U5D1   EE84  RSVD<4>  SKX_EXT_B_BGA1  I127

TP_CPU0_RSVD_5   @BASEBOARD_FAB2_LIB.BASEBOARD_FAB2(SCH_1):TP_CPU0_RSVD_5
  U5D1   EE82  RSVD<5>  SKX_EXT_B_BGA1  I127

TP_CPU0_RSVD_6   @BASEBOARD_FAB2_LIB.BASEBOARD_FAB2(SCH_1):TP_CPU0_RSVD_6
  U5D1   EE6  RSVD<6>  SKX_EXT_B_BGA1  I127

TP_CPU0_RSVD_7   @BASEBOARD_FAB2_LIB.BASEBOARD_FAB2(SCH_1):TP_CPU0_RSVD_7
  U5D1   EE46  RSVD<7>  SKX_EXT_B_BGA1  I127

TP_CPU0_RSVD_8   @BASEBOARD_FAB2_LIB.BASEBOARD_FAB2(SCH_1):TP_CPU0_RSVD_8
  U5D1   EE16  RSVD<8>  SKX_EXT_B_BGA1  I127

TP_CPU0_RSVD_9   @BASEBOARD_FAB2_LIB.BASEBOARD_FAB2(SCH_1):TP_CPU0_RSVD_9
  U5D1   ED83  RSVD<9>  SKX_EXT_B_BGA1  I127

TP_CPU0_RSVD_10   @BASEBOARD_FAB2_LIB.BASEBOARD_FAB2(SCH_1):TP_CPU0_RSVD_10
  U5D1   ED5  RSVD<10>  SKX_EXT_B_BGA1  I127

TP_CPU0_RSVD_11   @BASEBOARD_FAB2_LIB.BASEBOARD_FAB2(SCH_1):TP_CPU0_RSVD_11
  U5D1   ED45  RSVD<11>  SKX_EXT_B_BGA1  I127

TP_CPU0_RSVD_12   @BASEBOARD_FAB2_LIB.BASEBOARD_FAB2(SCH_1):TP_CPU0_RSVD_12
  U5D1   EC84  RSVD<12>  SKX_EXT_B_BGA1  I127

TP_CPU0_RSVD_13   @BASEBOARD_FAB2_LIB.BASEBOARD_FAB2(SCH_1):TP_CPU0_RSVD_13
  U5D1   EC44  RSVD<13>  SKX_EXT_B_BGA1  I127

TP_CPU0_RSVD_14   @BASEBOARD_FAB2_LIB.BASEBOARD_FAB2(SCH_1):TP_CPU0_RSVD_14
  U5D1   EC4  RSVD<14>  SKX_EXT_B_BGA1  I127

TP_CPU0_RSVD_15   @BASEBOARD_FAB2_LIB.BASEBOARD_FAB2(SCH_1):TP_CPU0_RSVD_15
  U5D1   EC16  RSVD<15>  SKX_EXT_B_BGA1  I127

TP_CPU0_RSVD_16   @BASEBOARD_FAB2_LIB.BASEBOARD_FAB2(SCH_1):TP_CPU0_RSVD_16
  U5D1   EB85  RSVD<16>  SKX_EXT_B_BGA1  I127

TP_CPU0_RSVD_17   @BASEBOARD_FAB2_LIB.BASEBOARD_FAB2(SCH_1):TP_CPU0_RSVD_17
  U5D1   EB5  RSVD<17>  SKX_EXT_B_BGA1  I127

TP_CPU0_RSVD_18   @BASEBOARD_FAB2_LIB.BASEBOARD_FAB2(SCH_1):TP_CPU0_RSVD_18
  U5D1   EB3  RSVD<18>  SKX_EXT_B_BGA1  I127

TP_CPU0_RSVD_19   @BASEBOARD_FAB2_LIB.BASEBOARD_FAB2(SCH_1):TP_CPU0_RSVD_19
  U5D1   EA44  RSVD<19>  SKX_EXT_B_BGA1  I127

TP_CPU0_RSVD_20   @BASEBOARD_FAB2_LIB.BASEBOARD_FAB2(SCH_1):TP_CPU0_RSVD_20
  U5D1   EA4  RSVD<20>  SKX_EXT_B_BGA1  I127

TP_CPU0_RSVD_21   @BASEBOARD_FAB2_LIB.BASEBOARD_FAB2(SCH_1):TP_CPU0_RSVD_21
  U5D1   DY3  RSVD<21>  SKX_EXT_B_BGA1  I127

TP_CPU0_RSVD_22   @BASEBOARD_FAB2_LIB.BASEBOARD_FAB2(SCH_1):TP_CPU0_RSVD_22
  U5D1   DW46  RSVD<22>  SKX_EXT_B_BGA1  I127

TP_CPU0_RSVD_23   @BASEBOARD_FAB2_LIB.BASEBOARD_FAB2(SCH_1):TP_CPU0_RSVD_23
  U5D1   DW44  RSVD<23>  SKX_EXT_B_BGA1  I127

TP_CPU0_RSVD_24   @BASEBOARD_FAB2_LIB.BASEBOARD_FAB2(SCH_1):TP_CPU0_RSVD_24
  U5D1   DV71  RSVD<24>  SKX_EXT_B_BGA1  I127

TP_CPU0_RSVD_25   @BASEBOARD_FAB2_LIB.BASEBOARD_FAB2(SCH_1):TP_CPU0_RSVD_25
  U5D1   DV61  RSVD<25>  SKX_EXT_B_BGA1  I127

TP_CPU0_RSVD_26   @BASEBOARD_FAB2_LIB.BASEBOARD_FAB2(SCH_1):TP_CPU0_RSVD_26
  U5D1   DU44  RSVD<26>  SKX_EXT_B_BGA1  I127

TP_CPU0_RSVD_27   @BASEBOARD_FAB2_LIB.BASEBOARD_FAB2(SCH_1):TP_CPU0_RSVD_27
  U5D1   DT71  RSVD<27>  SKX_EXT_B_BGA1  I127

TP_CPU0_RSVD_28   @BASEBOARD_FAB2_LIB.BASEBOARD_FAB2(SCH_1):TP_CPU0_RSVD_28
  U5D1   DR44  RSVD<28>  SKX_EXT_B_BGA1  I127

TP_CPU0_RSVD_29   @BASEBOARD_FAB2_LIB.BASEBOARD_FAB2(SCH_1):TP_CPU0_RSVD_29
  U5D1   DP65  RSVD<29>  SKX_EXT_B_BGA1  I127

TP_CPU0_RSVD_30   @BASEBOARD_FAB2_LIB.BASEBOARD_FAB2(SCH_1):TP_CPU0_RSVD_30
  U5D1   DP17  RSVD<30>  SKX_EXT_B_BGA1  I127

TP_CPU0_RSVD_31   @BASEBOARD_FAB2_LIB.BASEBOARD_FAB2(SCH_1):TP_CPU0_RSVD_31
  U5D1   DN66  RSVD<31>  SKX_EXT_B_BGA1  I127

TP_CPU0_RSVD_32   @BASEBOARD_FAB2_LIB.BASEBOARD_FAB2(SCH_1):TP_CPU0_RSVD_32
  U5D1   DN62  RSVD<32>  SKX_EXT_B_BGA1  I127

TP_CPU0_RSVD_33   @BASEBOARD_FAB2_LIB.BASEBOARD_FAB2(SCH_1):TP_CPU0_RSVD_33
  U5D1   DM67  RSVD<33>  SKX_EXT_B_BGA1  I127

TP_CPU0_RSVD_34   @BASEBOARD_FAB2_LIB.BASEBOARD_FAB2(SCH_1):TP_CPU0_RSVD_34
  U5D1   DL66  RSVD<34>  SKX_EXT_B_BGA1  I127

TP_CPU0_RSVD_35   @BASEBOARD_FAB2_LIB.BASEBOARD_FAB2(SCH_1):TP_CPU0_RSVD_35
  U5D1   DL38  RSVD<35>  SKX_EXT_B_BGA1  I127

TP_CPU0_RSVD_36   @BASEBOARD_FAB2_LIB.BASEBOARD_FAB2(SCH_1):TP_CPU0_RSVD_36
  U5D1   DK67  RSVD<36>  SKX_EXT_B_BGA1  I127

TP_CPU0_RSVD_37   @BASEBOARD_FAB2_LIB.BASEBOARD_FAB2(SCH_1):TP_CPU0_RSVD_37
  U5D1   DK65  RSVD<37>  SKX_EXT_B_BGA1  I127

TP_CPU0_RSVD_38   @BASEBOARD_FAB2_LIB.BASEBOARD_FAB2(SCH_1):TP_CPU0_RSVD_38
  U5D1   DK37  RSVD<38>  SKX_EXT_B_BGA1  I127

TP_CPU0_RSVD_39   @BASEBOARD_FAB2_LIB.BASEBOARD_FAB2(SCH_1):TP_CPU0_RSVD_39
  U5D1   DK15  RSVD<39>  SKX_EXT_B_BGA1  I127

TP_CPU0_RSVD_40   @BASEBOARD_FAB2_LIB.BASEBOARD_FAB2(SCH_1):TP_CPU0_RSVD_40
  U5D1   DJ66  RSVD<40>  SKX_EXT_B_BGA1  I127

TP_CPU0_RSVD_41   @BASEBOARD_FAB2_LIB.BASEBOARD_FAB2(SCH_1):TP_CPU0_RSVD_41
  U5D1   DJ36  RSVD<41>  SKX_EXT_B_BGA1  I127

TP_CPU0_RSVD_42   @BASEBOARD_FAB2_LIB.BASEBOARD_FAB2(SCH_1):TP_CPU0_RSVD_42
  U5D1   DH65  RSVD<42>  SKX_EXT_B_BGA1  I127

TP_CPU0_RSVD_43   @BASEBOARD_FAB2_LIB.BASEBOARD_FAB2(SCH_1):TP_CPU0_RSVD_43
  U5D1   DG64  RSVD<43>  SKX_EXT_B_BGA1  I127

TP_CPU0_RSVD_44   @BASEBOARD_FAB2_LIB.BASEBOARD_FAB2(SCH_1):TP_CPU0_RSVD_44
  U5D1   DG36  RSVD<44>  SKX_EXT_B_BGA1  I127

TP_CPU0_RSVD_45   @BASEBOARD_FAB2_LIB.BASEBOARD_FAB2(SCH_1):TP_CPU0_RSVD_45
  U5D1   DD51  RSVD<45>  SKX_EXT_B_BGA1  I127

TP_CPU0_RSVD_46   @BASEBOARD_FAB2_LIB.BASEBOARD_FAB2(SCH_1):TP_CPU0_RSVD_46
  U5D1   DC52  RSVD<46>  SKX_EXT_B_BGA1  I127

TP_CPU0_RSVD_47   @BASEBOARD_FAB2_LIB.BASEBOARD_FAB2(SCH_1):TP_CPU0_RSVD_47
  U5D1   DC46  RSVD<47>  SKX_EXT_B_BGA1  I127

TP_CPU0_RSVD_48   @BASEBOARD_FAB2_LIB.BASEBOARD_FAB2(SCH_1):TP_CPU0_RSVD_48
  U5D1   DA56  RSVD<48>  SKX_EXT_B_BGA1  I127

TP_CPU0_RSVD_49   @BASEBOARD_FAB2_LIB.BASEBOARD_FAB2(SCH_1):TP_CPU0_RSVD_49
  U5D1   DA54  RSVD<49>  SKX_EXT_B_BGA1  I127

TP_CPU0_RSVD_50   @BASEBOARD_FAB2_LIB.BASEBOARD_FAB2(SCH_1):TP_CPU0_RSVD_50
  U5D1   DA52  RSVD<50>  SKX_EXT_B_BGA1  I127

TP_CPU0_RSVD_51   @BASEBOARD_FAB2_LIB.BASEBOARD_FAB2(SCH_1):TP_CPU0_RSVD_51
  U5D1   DA40  RSVD<51>  SKX_EXT_B_BGA1  I127

TP_CPU0_RSVD_53   @BASEBOARD_FAB2_LIB.BASEBOARD_FAB2(SCH_1):TP_CPU0_RSVD_53
  U5D1   CY73  RSVD<53>  SKX_EXT_B_BGA1  I127

TP_CPU0_RSVD_54   @BASEBOARD_FAB2_LIB.BASEBOARD_FAB2(SCH_1):TP_CPU0_RSVD_54
  U5D1   CY63  RSVD<54>  SKX_EXT_B_BGA1  I127

TP_CPU0_RSVD_55   @BASEBOARD_FAB2_LIB.BASEBOARD_FAB2(SCH_1):TP_CPU0_RSVD_55
  U5D1   CY57  RSVD<55>  SKX_EXT_B_BGA1  I127

TP_CPU0_RSVD_56   @BASEBOARD_FAB2_LIB.BASEBOARD_FAB2(SCH_1):TP_CPU0_RSVD_56
  U5D1   CY53  RSVD<56>  SKX_EXT_B_BGA1  I127

TP_CPU0_RSVD_57   @BASEBOARD_FAB2_LIB.BASEBOARD_FAB2(SCH_1):TP_CPU0_RSVD_57
  U5D1   CY39  RSVD<57>  SKX_EXT_B_BGA1  I127

TP_CPU0_RSVD_59   @BASEBOARD_FAB2_LIB.BASEBOARD_FAB2(SCH_1):TP_CPU0_RSVD_59
  U5D1   CY23  RSVD<59>  SKX_EXT_B_BGA1  I127

TP_CPU0_RSVD_60   @BASEBOARD_FAB2_LIB.BASEBOARD_FAB2(SCH_1):TP_CPU0_RSVD_60
  U5D1   CW62  RSVD<60>  SKX_EXT_B_BGA1  I127

TP_CPU0_RSVD_61   @BASEBOARD_FAB2_LIB.BASEBOARD_FAB2(SCH_1):TP_CPU0_RSVD_61
  U5D1   CW60  RSVD<61>  SKX_EXT_B_BGA1  I127

TP_CPU0_RSVD_64   @BASEBOARD_FAB2_LIB.BASEBOARD_FAB2(SCH_1):TP_CPU0_RSVD_64
  U5D1   CV69  RSVD<64>  SKX_EXT_B_BGA1  I127

TP_CPU0_RSVD_66   @BASEBOARD_FAB2_LIB.BASEBOARD_FAB2(SCH_1):TP_CPU0_RSVD_66
  U5D1   CU60  RSVD<66>  SKX_EXT_B_BGA1  I127

TP_CPU0_RSVD_67   @BASEBOARD_FAB2_LIB.BASEBOARD_FAB2(SCH_1):TP_CPU0_RSVD_67
  U5D1   CU6  RSVD<67>  SKX_EXT_B_BGA1  I127

TP_CPU0_RSVD_69   @BASEBOARD_FAB2_LIB.BASEBOARD_FAB2(SCH_1):TP_CPU0_RSVD_69
  U5D1   CT69  RSVD<69>  SKX_EXT_B_BGA1  I127

TP_CPU0_RSVD_70   @BASEBOARD_FAB2_LIB.BASEBOARD_FAB2(SCH_1):TP_CPU0_RSVD_70
  U5D1   CT5  RSVD<70>  SKX_EXT_B_BGA1  I127

TP_CPU0_RSVD_72   @BASEBOARD_FAB2_LIB.BASEBOARD_FAB2(SCH_1):TP_CPU0_RSVD_72
  U5D1   CR60  RSVD<72>  SKX_EXT_B_BGA1  I127

TP_CPU0_RSVD_73   @BASEBOARD_FAB2_LIB.BASEBOARD_FAB2(SCH_1):TP_CPU0_RSVD_73
  U5D1   CP31  RSVD<73>  SKX_EXT_B_BGA1  I127

TP_CPU0_RSVD_82   @BASEBOARD_FAB2_LIB.BASEBOARD_FAB2(SCH_1):TP_CPU0_RSVD_82
  U5D1   CK77  RSVD<82>  SKX_EXT_B_BGA1  I16

TP_CPU0_RSVD_85   @BASEBOARD_FAB2_LIB.BASEBOARD_FAB2(SCH_1):TP_CPU0_RSVD_85
  U5D1   CK19  RSVD<85>  SKX_EXT_B_BGA1  I16

TP_CPU0_RSVD_90   @BASEBOARD_FAB2_LIB.BASEBOARD_FAB2(SCH_1):TP_CPU0_RSVD_90
  U5D1   CH77  RSVD<90>  SKX_EXT_B_BGA1  I16

TP_CPU0_RSVD_91   @BASEBOARD_FAB2_LIB.BASEBOARD_FAB2(SCH_1):TP_CPU0_RSVD_91
  U5D1   CH25  RSVD<91>  SKX_EXT_B_BGA1  I16

TP_CPU0_RSVD_94   @BASEBOARD_FAB2_LIB.BASEBOARD_FAB2(SCH_1):TP_CPU0_RSVD_94
  U5D1   CG82  RSVD<94>  SKX_EXT_B_BGA1  I15

TP_CPU0_RSVD_95   @BASEBOARD_FAB2_LIB.BASEBOARD_FAB2(SCH_1):TP_CPU0_RSVD_95
  U5D1   CG78  RSVD<95>  SKX_EXT_B_BGA1  I15

TP_CPU0_RSVD_97   @BASEBOARD_FAB2_LIB.BASEBOARD_FAB2(SCH_1):TP_CPU0_RSVD_97
  U5D1   CG24  RSVD<97>  SKX_EXT_B_BGA1  I15

TP_CPU0_RSVD_99   @BASEBOARD_FAB2_LIB.BASEBOARD_FAB2(SCH_1):TP_CPU0_RSVD_99
  U5D1   CG10  RSVD<99>  SKX_EXT_B_BGA1  I15

TP_CPU0_RSVD_100   @BASEBOARD_FAB2_LIB.BASEBOARD_FAB2(SCH_1):TP_CPU0_RSVD_100
  U5D1   CF81  RSVD<100>  SKX_EXT_B_BGA1  I15

TP_CPU0_RSVD_101   @BASEBOARD_FAB2_LIB.BASEBOARD_FAB2(SCH_1):TP_CPU0_RSVD_101
  U5D1   CF79  RSVD<101>  SKX_EXT_B_BGA1  I15

TP_CPU0_RSVD_105   @BASEBOARD_FAB2_LIB.BASEBOARD_FAB2(SCH_1):TP_CPU0_RSVD_105
  U5D1   CE80  RSVD<105>  SKX_EXT_B_BGA1  I15

TP_CPU0_RSVD_106   @BASEBOARD_FAB2_LIB.BASEBOARD_FAB2(SCH_1):TP_CPU0_RSVD_106
  U5D1   CE78  RSVD<106>  SKX_EXT_B_BGA1  I15

TP_CPU0_RSVD_108   @BASEBOARD_FAB2_LIB.BASEBOARD_FAB2(SCH_1):TP_CPU0_RSVD_108
  U5D1   CD25  RSVD<108>  SKX_EXT_B_BGA1  I15

TP_CPU0_RSVD_111   @BASEBOARD_FAB2_LIB.BASEBOARD_FAB2(SCH_1):TP_CPU0_RSVD_111
  U5D1   CC6  RSVD<111>  SKX_EXT_B_BGA1  I15

TP_CPU0_RSVD_113   @BASEBOARD_FAB2_LIB.BASEBOARD_FAB2(SCH_1):TP_CPU0_RSVD_113
  U5D1   CB5  RSVD<113>  SKX_EXT_B_BGA1  I15

TP_CPU0_RSVD_114   @BASEBOARD_FAB2_LIB.BASEBOARD_FAB2(SCH_1):TP_CPU0_RSVD_114
  U5D1   CB25  RSVD<114>  SKX_EXT_B_BGA1  I15

TP_CPU0_RSVD_117   @BASEBOARD_FAB2_LIB.BASEBOARD_FAB2(SCH_1):TP_CPU0_RSVD_117
  U5D1   CA24  RSVD<117>  SKX_EXT_B_BGA1  I15

TP_CPU0_RSVD_119   @BASEBOARD_FAB2_LIB.BASEBOARD_FAB2(SCH_1):TP_CPU0_RSVD_119
  U5D1   BY25  RSVD<119>  SKX_EXT_B_BGA1  I15

TP_CPU0_RSVD_121   @BASEBOARD_FAB2_LIB.BASEBOARD_FAB2(SCH_1):TP_CPU0_RSVD_121
  U5D1   BW22  RSVD<121>  SKX_EXT_B_BGA1  I15

TP_CPU0_RSVD_123   @BASEBOARD_FAB2_LIB.BASEBOARD_FAB2(SCH_1):TP_CPU0_RSVD_123
  U5D1   BW10  RSVD<123>  SKX_EXT_B_BGA1  I15

TP_CPU0_RSVD_124   @BASEBOARD_FAB2_LIB.BASEBOARD_FAB2(SCH_1):TP_CPU0_RSVD_124
  U5D1   BV23  RSVD<124>  SKX_EXT_B_BGA1  I15

TP_CPU0_RSVD_144   @BASEBOARD_FAB2_LIB.BASEBOARD_FAB2(SCH_1):TP_CPU0_RSVD_144
  U5D1   BG20  RSVD<144>  SKX_EXT_B_BGA1  I15

TP_CPU0_RSVD_145   @BASEBOARD_FAB2_LIB.BASEBOARD_FAB2(SCH_1):TP_CPU0_RSVD_145
  U5D1   BG18  RSVD<145>  SKX_EXT_B_BGA1  I15

TP_CPU0_RSVD_146   @BASEBOARD_FAB2_LIB.BASEBOARD_FAB2(SCH_1):TP_CPU0_RSVD_146
  U5D1   BF21  RSVD<146>  SKX_EXT_B_BGA1  I15

TP_CPU0_RSVD_147   @BASEBOARD_FAB2_LIB.BASEBOARD_FAB2(SCH_1):TP_CPU0_RSVD_147
  U5D1   BE22  RSVD<147>  SKX_EXT_B_BGA1  I15

TP_CPU0_RSVD_148   @BASEBOARD_FAB2_LIB.BASEBOARD_FAB2(SCH_1):TP_CPU0_RSVD_148
  U5D1   BE20  RSVD<148>  SKX_EXT_B_BGA1  I15

TP_CPU0_RSVD_149   @BASEBOARD_FAB2_LIB.BASEBOARD_FAB2(SCH_1):TP_CPU0_RSVD_149
  U5D1   BE18  RSVD<149>  SKX_EXT_B_BGA1  I15

TP_CPU0_RSVD_150   @BASEBOARD_FAB2_LIB.BASEBOARD_FAB2(SCH_1):TP_CPU0_RSVD_150
  U5D1   BD69  RSVD<150>  SKX_EXT_B_BGA1  I15

TP_CPU0_RSVD_151   @BASEBOARD_FAB2_LIB.BASEBOARD_FAB2(SCH_1):TP_CPU0_RSVD_151
  U5D1   BD67  RSVD<151>  SKX_EXT_B_BGA1  I15

TP_CPU0_RSVD_152   @BASEBOARD_FAB2_LIB.BASEBOARD_FAB2(SCH_1):TP_CPU0_RSVD_152
  U5D1   BD65  RSVD<152>  SKX_EXT_B_BGA1  I15

TP_CPU0_RSVD_154   @BASEBOARD_FAB2_LIB.BASEBOARD_FAB2(SCH_1):TP_CPU0_RSVD_154
  U5D1   BD19  RSVD<154>  SKX_EXT_B_BGA1  I15

TP_CPU0_RSVD_155   @BASEBOARD_FAB2_LIB.BASEBOARD_FAB2(SCH_1):TP_CPU0_RSVD_155
  U5D1   BD17  RSVD<155>  SKX_EXT_B_BGA1  I15

TP_CPU0_RSVD_156   @BASEBOARD_FAB2_LIB.BASEBOARD_FAB2(SCH_1):TP_CPU0_RSVD_156
  U5D1   BC68  RSVD<156>  SKX_EXT_B_BGA1  I15

TP_CPU0_RSVD_157   @BASEBOARD_FAB2_LIB.BASEBOARD_FAB2(SCH_1):TP_CPU0_RSVD_157
  U5D1   BC66  RSVD<157>  SKX_EXT_B_BGA1  I15

TP_CPU0_RSVD_158   @BASEBOARD_FAB2_LIB.BASEBOARD_FAB2(SCH_1):TP_CPU0_RSVD_158
  U5D1   BC64  RSVD<158>  SKX_EXT_B_BGA1  I15

TP_CPU0_RSVD_159   @BASEBOARD_FAB2_LIB.BASEBOARD_FAB2(SCH_1):TP_CPU0_RSVD_159
  U5D1   BC22  RSVD<159>  SKX_EXT_B_BGA1  I15

TP_CPU0_RSVD_160   @BASEBOARD_FAB2_LIB.BASEBOARD_FAB2(SCH_1):TP_CPU0_RSVD_160
  U5D1   BC20  RSVD<160>  SKX_EXT_B_BGA1  I15

TP_CPU0_RSVD_161   @BASEBOARD_FAB2_LIB.BASEBOARD_FAB2(SCH_1):TP_CPU0_RSVD_161
  U5D1   BC18  RSVD<161>  SKX_EXT_B_BGA1  I15

TP_CPU0_RSVD_162   @BASEBOARD_FAB2_LIB.BASEBOARD_FAB2(SCH_1):TP_CPU0_RSVD_162
  U5D1   BC14  RSVD<162>  SKX_EXT_B_BGA1  I15

TP_CPU0_RSVD_163   @BASEBOARD_FAB2_LIB.BASEBOARD_FAB2(SCH_1):TP_CPU0_RSVD_163
  U5D1   BB67  RSVD<163>  SKX_EXT_B_BGA1  I15

TP_CPU0_RSVD_164   @BASEBOARD_FAB2_LIB.BASEBOARD_FAB2(SCH_1):TP_CPU0_RSVD_164
  U5D1   BB65  RSVD<164>  SKX_EXT_B_BGA1  I15

TP_CPU0_RSVD_166   @BASEBOARD_FAB2_LIB.BASEBOARD_FAB2(SCH_1):TP_CPU0_RSVD_166
  U5D1   BB21  RSVD<166>  SKX_EXT_B_BGA1  I15

TP_CPU0_RSVD_167   @BASEBOARD_FAB2_LIB.BASEBOARD_FAB2(SCH_1):TP_CPU0_RSVD_167
  U5D1   BB17  RSVD<167>  SKX_EXT_B_BGA1  I15

TP_CPU0_RSVD_168   @BASEBOARD_FAB2_LIB.BASEBOARD_FAB2(SCH_1):TP_CPU0_RSVD_168
  U5D1   BB15  RSVD<168>  SKX_EXT_B_BGA1  I15

TP_CPU0_RSVD_169   @BASEBOARD_FAB2_LIB.BASEBOARD_FAB2(SCH_1):TP_CPU0_RSVD_169
  U5D1   BB13  RSVD<169>  SKX_EXT_B_BGA1  I15

TP_CPU0_RSVD_170   @BASEBOARD_FAB2_LIB.BASEBOARD_FAB2(SCH_1):TP_CPU0_RSVD_170
  U5D1   BA82  RSVD<170>  SKX_EXT_B_BGA1  I15

TP_CPU0_RSVD_171   @BASEBOARD_FAB2_LIB.BASEBOARD_FAB2(SCH_1):TP_CPU0_RSVD_171
  U5D1   BA78  RSVD<171>  SKX_EXT_B_BGA1  I15

TP_CPU0_RSVD_172   @BASEBOARD_FAB2_LIB.BASEBOARD_FAB2(SCH_1):TP_CPU0_RSVD_172
  U5D1   BA76  RSVD<172>  SKX_EXT_B_BGA1  I61

TP_CPU0_RSVD_173   @BASEBOARD_FAB2_LIB.BASEBOARD_FAB2(SCH_1):TP_CPU0_RSVD_173
  U5D1   BA66  RSVD<173>  SKX_EXT_B_BGA1  I61

TP_CPU0_RSVD_174   @BASEBOARD_FAB2_LIB.BASEBOARD_FAB2(SCH_1):TP_CPU0_RSVD_174
  U5D1   BA64  RSVD<174>  SKX_EXT_B_BGA1  I61

TP_CPU0_RSVD_175   @BASEBOARD_FAB2_LIB.BASEBOARD_FAB2(SCH_1):TP_CPU0_RSVD_175
  U5D1   BA22  RSVD<175>  SKX_EXT_B_BGA1  I61

TP_CPU0_RSVD_176   @BASEBOARD_FAB2_LIB.BASEBOARD_FAB2(SCH_1):TP_CPU0_RSVD_176
  U5D1   BA18  RSVD<176>  SKX_EXT_B_BGA1  I61

TP_CPU0_RSVD_177   @BASEBOARD_FAB2_LIB.BASEBOARD_FAB2(SCH_1):TP_CPU0_RSVD_177
  U5D1   BA16  RSVD<177>  SKX_EXT_B_BGA1  I61

TP_CPU0_RSVD_178   @BASEBOARD_FAB2_LIB.BASEBOARD_FAB2(SCH_1):TP_CPU0_RSVD_178
  U5D1   BA14  RSVD<178>  SKX_EXT_B_BGA1  I61

TP_CPU0_RSVD_179   @BASEBOARD_FAB2_LIB.BASEBOARD_FAB2(SCH_1):TP_CPU0_RSVD_179
  U5D1   AY77  RSVD<179>  SKX_EXT_B_BGA1  I61

TP_CPU0_RSVD_180   @BASEBOARD_FAB2_LIB.BASEBOARD_FAB2(SCH_1):TP_CPU0_RSVD_180
  U5D1   AY75  RSVD<180>  SKX_EXT_B_BGA1  I61

TP_CPU0_RSVD_181   @BASEBOARD_FAB2_LIB.BASEBOARD_FAB2(SCH_1):TP_CPU0_RSVD_181
  U5D1   AY67  RSVD<181>  SKX_EXT_B_BGA1  I61

TP_CPU0_RSVD_182   @BASEBOARD_FAB2_LIB.BASEBOARD_FAB2(SCH_1):TP_CPU0_RSVD_182
  U5D1   AY65  RSVD<182>  SKX_EXT_B_BGA1  I61

TP_CPU0_RSVD_183   @BASEBOARD_FAB2_LIB.BASEBOARD_FAB2(SCH_1):TP_CPU0_RSVD_183
  U5D1   AW76  RSVD<183>  SKX_EXT_B_BGA1  I61

TP_CPU0_RSVD_184   @BASEBOARD_FAB2_LIB.BASEBOARD_FAB2(SCH_1):TP_CPU0_RSVD_184
  U5D1   AW64  RSVD<184>  SKX_EXT_B_BGA1  I61

TP_CPU0_RSVD_186   @BASEBOARD_FAB2_LIB.BASEBOARD_FAB2(SCH_1):TP_CPU0_RSVD_186
  U5D1   AV77  RSVD<186>  SKX_EXT_B_BGA1  I61

TP_CPU0_RSVD_189   @BASEBOARD_FAB2_LIB.BASEBOARD_FAB2(SCH_1):TP_CPU0_RSVD_189
  U5D1   AT13  RSVD<189>  SKX_EXT_B_BGA1  I61

TP_CPU0_RSVD_190   @BASEBOARD_FAB2_LIB.BASEBOARD_FAB2(SCH_1):TP_CPU0_RSVD_190
  U5D1   AR62  RSVD<190>  SKX_EXT_B_BGA1  I61

TP_CPU0_RSVD_194   @BASEBOARD_FAB2_LIB.BASEBOARD_FAB2(SCH_1):TP_CPU0_RSVD_194
  U5D1   AP61  RSVD<194>  SKX_EXT_B_BGA1  I204

TP_CPU0_RSVD_198   @BASEBOARD_FAB2_LIB.BASEBOARD_FAB2(SCH_1):TP_CPU0_RSVD_198
  U5D1   AN62  RSVD<198>  SKX_EXT_B_BGA1  I204

TP_CPU0_RSVD_199   @BASEBOARD_FAB2_LIB.BASEBOARD_FAB2(SCH_1):TP_CPU0_RSVD_199
  U5D1   AN60  RSVD<199>  SKX_EXT_B_BGA1  I204

TP_CPU0_RSVD_204   @BASEBOARD_FAB2_LIB.BASEBOARD_FAB2(SCH_1):TP_CPU0_RSVD_204
  U5D1   AM61  RSVD<204>  SKX_EXT_B_BGA1  I204

TP_CPU0_RSVD_205   @BASEBOARD_FAB2_LIB.BASEBOARD_FAB2(SCH_1):TP_CPU0_RSVD_205
  U5D1   AM59  RSVD<205>  SKX_EXT_B_BGA1  I204

TP_CPU0_RSVD_208   @BASEBOARD_FAB2_LIB.BASEBOARD_FAB2(SCH_1):TP_CPU0_RSVD_208
  U5D1   AM23  RSVD<208>  SKX_EXT_B_BGA1  I204

TP_CPU0_RSVD_210   @BASEBOARD_FAB2_LIB.BASEBOARD_FAB2(SCH_1):TP_CPU0_RSVD_210
  U5D1   AL62  RSVD<210>  SKX_EXT_B_BGA1  I204

TP_CPU0_RSVD_211   @BASEBOARD_FAB2_LIB.BASEBOARD_FAB2(SCH_1):TP_CPU0_RSVD_211
  U5D1   AL60  RSVD<211>  SKX_EXT_B_BGA1  I204

TP_CPU0_RSVD_212   @BASEBOARD_FAB2_LIB.BASEBOARD_FAB2(SCH_1):TP_CPU0_RSVD_212
  U5D1   AL58  RSVD<212>  SKX_EXT_B_BGA1  I204

TP_CPU0_RSVD_214   @BASEBOARD_FAB2_LIB.BASEBOARD_FAB2(SCH_1):TP_CPU0_RSVD_214
  U5D1   AL22  RSVD<214>  SKX_EXT_B_BGA1  I204

TP_CPU0_RSVD_216   @BASEBOARD_FAB2_LIB.BASEBOARD_FAB2(SCH_1):TP_CPU0_RSVD_216
  U5D1   AK69  RSVD<216>  SKX_EXT_B_BGA1  I204

TP_CPU0_RSVD_217   @BASEBOARD_FAB2_LIB.BASEBOARD_FAB2(SCH_1):TP_CPU0_RSVD_217
  U5D1   AK61  RSVD<217>  SKX_EXT_B_BGA1  I204

TP_CPU0_RSVD_218   @BASEBOARD_FAB2_LIB.BASEBOARD_FAB2(SCH_1):TP_CPU0_RSVD_218
  U5D1   AK59  RSVD<218>  SKX_EXT_B_BGA1  I204

TP_CPU0_RSVD_219   @BASEBOARD_FAB2_LIB.BASEBOARD_FAB2(SCH_1):TP_CPU0_RSVD_219
  U5D1   AK57  RSVD<219>  SKX_EXT_B_BGA1  I204

TP_CPU0_RSVD_222   @BASEBOARD_FAB2_LIB.BASEBOARD_FAB2(SCH_1):TP_CPU0_RSVD_222
  U5D1   AJ70  RSVD<222>  SKX_EXT_B_BGA1  I204

TP_CPU0_RSVD_223   @BASEBOARD_FAB2_LIB.BASEBOARD_FAB2(SCH_1):TP_CPU0_RSVD_223
  U5D1   AJ62  RSVD<223>  SKX_EXT_B_BGA1  I204

TP_CPU0_RSVD_224   @BASEBOARD_FAB2_LIB.BASEBOARD_FAB2(SCH_1):TP_CPU0_RSVD_224
  U5D1   AJ60  RSVD<224>  SKX_EXT_B_BGA1  I204

TP_CPU0_RSVD_225   @BASEBOARD_FAB2_LIB.BASEBOARD_FAB2(SCH_1):TP_CPU0_RSVD_225
  U5D1   AJ58  RSVD<225>  SKX_EXT_B_BGA1  I204

TP_CPU0_RSVD_226   @BASEBOARD_FAB2_LIB.BASEBOARD_FAB2(SCH_1):TP_CPU0_RSVD_226
  U5D1   AJ56  RSVD<226>  SKX_EXT_B_BGA1  I204

TP_CPU0_RSVD_227   @BASEBOARD_FAB2_LIB.BASEBOARD_FAB2(SCH_1):TP_CPU0_RSVD_227
  U5D1   AJ20  RSVD<227>  SKX_EXT_B_BGA1  I204

TP_CPU0_RSVD_228   @BASEBOARD_FAB2_LIB.BASEBOARD_FAB2(SCH_1):TP_CPU0_RSVD_228
  U5D1   AH73  RSVD<228>  SKX_EXT_B_BGA1  I204

TP_CPU0_RSVD_229   @BASEBOARD_FAB2_LIB.BASEBOARD_FAB2(SCH_1):TP_CPU0_RSVD_229
  U5D1   AH71  RSVD<229>  SKX_EXT_B_BGA1  I204

TP_CPU0_RSVD_230   @BASEBOARD_FAB2_LIB.BASEBOARD_FAB2(SCH_1):TP_CPU0_RSVD_230
  U5D1   AH57  RSVD<230>  SKX_EXT_B_BGA1  I204

TP_CPU0_RSVD_231   @BASEBOARD_FAB2_LIB.BASEBOARD_FAB2(SCH_1):TP_CPU0_RSVD_231
  U5D1   AH55  RSVD<231>  SKX_EXT_B_BGA1  I204

TP_CPU0_RSVD_232   @BASEBOARD_FAB2_LIB.BASEBOARD_FAB2(SCH_1):TP_CPU0_RSVD_232
  U5D1   AH19  RSVD<232>  SKX_EXT_B_BGA1  I204

TP_CPU0_RSVD_233   @BASEBOARD_FAB2_LIB.BASEBOARD_FAB2(SCH_1):TP_CPU0_RSVD_233
  U5D1   AH15  RSVD<233>  SKX_EXT_B_BGA1  I204

TP_CPU0_RSVD_234   @BASEBOARD_FAB2_LIB.BASEBOARD_FAB2(SCH_1):TP_CPU0_RSVD_234
  U5D1   AG72  RSVD<234>  SKX_EXT_B_BGA1  I204

TP_CPU0_RSVD_235   @BASEBOARD_FAB2_LIB.BASEBOARD_FAB2(SCH_1):TP_CPU0_RSVD_235
  U5D1   AG56  RSVD<235>  SKX_EXT_B_BGA1  I204

TP_CPU0_RSVD_236   @BASEBOARD_FAB2_LIB.BASEBOARD_FAB2(SCH_1):TP_CPU0_RSVD_236
  U5D1   AG54  RSVD<236>  SKX_EXT_B_BGA1  I204

TP_CPU0_RSVD_237   @BASEBOARD_FAB2_LIB.BASEBOARD_FAB2(SCH_1):TP_CPU0_RSVD_237
  U5D1   AG52  RSVD<237>  SKX_EXT_B_BGA1  I204

TP_CPU0_RSVD_238   @BASEBOARD_FAB2_LIB.BASEBOARD_FAB2(SCH_1):TP_CPU0_RSVD_238
  U5D1   AG50  RSVD<238>  SKX_EXT_B_BGA1  I204

TP_CPU0_RSVD_239   @BASEBOARD_FAB2_LIB.BASEBOARD_FAB2(SCH_1):TP_CPU0_RSVD_239
  U5D1   AG48  RSVD<239>  SKX_EXT_B_BGA1  I204

TP_CPU0_RSVD_240   @BASEBOARD_FAB2_LIB.BASEBOARD_FAB2(SCH_1):TP_CPU0_RSVD_240
  U5D1   AG20  RSVD<240>  SKX_EXT_B_BGA1  I204

TP_CPU0_RSVD_241   @BASEBOARD_FAB2_LIB.BASEBOARD_FAB2(SCH_1):TP_CPU0_RSVD_241
  U5D1   AF71  RSVD<241>  SKX_EXT_B_BGA1  I204

TP_CPU0_RSVD_242   @BASEBOARD_FAB2_LIB.BASEBOARD_FAB2(SCH_1):TP_CPU0_RSVD_242
  U5D1   AF53  RSVD<242>  SKX_EXT_B_BGA1  I204

TP_CPU0_RSVD_243   @BASEBOARD_FAB2_LIB.BASEBOARD_FAB2(SCH_1):TP_CPU0_RSVD_243
  U5D1   AF51  RSVD<243>  SKX_EXT_B_BGA1  I204

TP_CPU0_RSVD_244   @BASEBOARD_FAB2_LIB.BASEBOARD_FAB2(SCH_1):TP_CPU0_RSVD_244
  U5D1   AF49  RSVD<244>  SKX_EXT_B_BGA1  I204

TP_CPU0_RSVD_245   @BASEBOARD_FAB2_LIB.BASEBOARD_FAB2(SCH_1):TP_CPU0_RSVD_245
  U5D1   AF47  RSVD<245>  SKX_EXT_B_BGA1  I204

TP_CPU0_RSVD_246   @BASEBOARD_FAB2_LIB.BASEBOARD_FAB2(SCH_1):TP_CPU0_RSVD_246
  U5D1   AF19  RSVD<246>  SKX_EXT_B_BGA1  I204

TP_CPU0_RSVD_247   @BASEBOARD_FAB2_LIB.BASEBOARD_FAB2(SCH_1):TP_CPU0_RSVD_247
  U5D1   AE72  RSVD<247>  SKX_EXT_B_BGA1  I204

TP_CPU0_RSVD_248   @BASEBOARD_FAB2_LIB.BASEBOARD_FAB2(SCH_1):TP_CPU0_RSVD_248
  U5D1   AE52  RSVD<248>  SKX_EXT_B_BGA1  I204

TP_CPU0_RSVD_249   @BASEBOARD_FAB2_LIB.BASEBOARD_FAB2(SCH_1):TP_CPU0_RSVD_249
  U5D1   AE50  RSVD<249>  SKX_EXT_B_BGA1  I204

TP_CPU0_RSVD_250   @BASEBOARD_FAB2_LIB.BASEBOARD_FAB2(SCH_1):TP_CPU0_RSVD_250
  U5D1   AE48  RSVD<250>  SKX_EXT_B_BGA1  I204

TP_CPU0_RSVD_251   @BASEBOARD_FAB2_LIB.BASEBOARD_FAB2(SCH_1):TP_CPU0_RSVD_251
  U5D1   AE46  RSVD<251>  SKX_EXT_B_BGA1  I204

TP_CPU0_RSVD_252   @BASEBOARD_FAB2_LIB.BASEBOARD_FAB2(SCH_1):TP_CPU0_RSVD_252
  U5D1   AD51  RSVD<252>  SKX_EXT_B_BGA1  I204

TP_CPU0_RSVD_253   @BASEBOARD_FAB2_LIB.BASEBOARD_FAB2(SCH_1):TP_CPU0_RSVD_253
  U5D1   AD49  RSVD<253>  SKX_EXT_B_BGA1  I204

TP_CPU0_RSVD_254   @BASEBOARD_FAB2_LIB.BASEBOARD_FAB2(SCH_1):TP_CPU0_RSVD_254
  U5D1   AD47  RSVD<254>  SKX_EXT_B_BGA1  I204

TP_CPU0_RSVD_255   @BASEBOARD_FAB2_LIB.BASEBOARD_FAB2(SCH_1):TP_CPU0_RSVD_255
  U5D1   AY83  RSVD<255>  SKX_EXT_B_BGA1  I15

TP_CPU0_RSVD_256   @BASEBOARD_FAB2_LIB.BASEBOARD_FAB2(SCH_1):TP_CPU0_RSVD_256
  U5D1   Y65  RSVD<256>  SKX_EXT_B_BGA1  I204

TP_CPU0_RSVD_258   @BASEBOARD_FAB2_LIB.BASEBOARD_FAB2(SCH_1):TP_CPU0_RSVD_258
  U5D1   W66  RSVD<258>  SKX_EXT_B_BGA1  I204

TP_CPU0_RSVD_259   @BASEBOARD_FAB2_LIB.BASEBOARD_FAB2(SCH_1):TP_CPU0_RSVD_259
  U5D1   V67  RSVD<259>  SKX_EXT_B_BGA1  I204

TP_CPU0_RSVD_260   @BASEBOARD_FAB2_LIB.BASEBOARD_FAB2(SCH_1):TP_CPU0_RSVD_260
  U5D1   V65  RSVD<260>  SKX_EXT_B_BGA1  I204

TP_CPU0_RSVD_261   @BASEBOARD_FAB2_LIB.BASEBOARD_FAB2(SCH_1):TP_CPU0_RSVD_261
  U5D1   U66  RSVD<261>  SKX_EXT_B_BGA1  I204

TP_CPU0_RSVD_262   @BASEBOARD_FAB2_LIB.BASEBOARD_FAB2(SCH_1):TP_CPU0_RSVD_262
  U5D1   T67  RSVD<262>  SKX_EXT_B_BGA1  I204

TP_CPU0_RSVD_263   @BASEBOARD_FAB2_LIB.BASEBOARD_FAB2(SCH_1):TP_CPU0_RSVD_263
  U5D1   R66  RSVD<263>  SKX_EXT_B_BGA1  I204

TP_CPU0_RSVD_264   @BASEBOARD_FAB2_LIB.BASEBOARD_FAB2(SCH_1):TP_CPU0_RSVD_264
  U5D1   R62  RSVD<264>  SKX_EXT_B_BGA1  I204

TP_CPU0_RSVD_265   @BASEBOARD_FAB2_LIB.BASEBOARD_FAB2(SCH_1):TP_CPU0_RSVD_265
  U5D1   P65  RSVD<265>  SKX_EXT_B_BGA1  I204

TP_CPU0_RSVD_266   @BASEBOARD_FAB2_LIB.BASEBOARD_FAB2(SCH_1):TP_CPU0_RSVD_266
  U5D1   M63  RSVD<266>  SKX_EXT_B_BGA1  I204

TP_CPU0_RSVD_267   @BASEBOARD_FAB2_LIB.BASEBOARD_FAB2(SCH_1):TP_CPU0_RSVD_267
  U5D1   K61  RSVD<267>  SKX_EXT_B_BGA1  I204

TP_CPU0_RSVD_268   @BASEBOARD_FAB2_LIB.BASEBOARD_FAB2(SCH_1):TP_CPU0_RSVD_268
  U5D1   J62  RSVD<268>  SKX_EXT_B_BGA1  I204

TP_CPU0_RSVD_269   @BASEBOARD_FAB2_LIB.BASEBOARD_FAB2(SCH_1):TP_CPU0_RSVD_269
  U5D1   J46  RSVD<269>  SKX_EXT_B_BGA1  I204

TP_CPU0_RSVD_270   @BASEBOARD_FAB2_LIB.BASEBOARD_FAB2(SCH_1):TP_CPU0_RSVD_270
  U5D1   H85  RSVD<270>  SKX_EXT_B_BGA1  I204

TP_CPU0_RSVD_271   @BASEBOARD_FAB2_LIB.BASEBOARD_FAB2(SCH_1):TP_CPU0_RSVD_271
  U5D1   H83  RSVD<271>  SKX_EXT_B_BGA1  I204

TP_CPU0_RSVD_272   @BASEBOARD_FAB2_LIB.BASEBOARD_FAB2(SCH_1):TP_CPU0_RSVD_272
  U5D1    H1  RSVD<272>  SKX_EXT_B_BGA1  I204

TP_CPU0_RSVD_273   @BASEBOARD_FAB2_LIB.BASEBOARD_FAB2(SCH_1):TP_CPU0_RSVD_273
  U5D1   G84  RSVD<273>  SKX_EXT_B_BGA1  I204

TP_CPU0_RSVD_274   @BASEBOARD_FAB2_LIB.BASEBOARD_FAB2(SCH_1):TP_CPU0_RSVD_274
  U5D1   G64  RSVD<274>  SKX_EXT_B_BGA1  I204

TP_CPU0_RSVD_275   @BASEBOARD_FAB2_LIB.BASEBOARD_FAB2(SCH_1):TP_CPU0_RSVD_275
  U5D1    G2  RSVD<275>  SKX_EXT_B_BGA1  I204

TP_CPU0_RSVD_276   @BASEBOARD_FAB2_LIB.BASEBOARD_FAB2(SCH_1):TP_CPU0_RSVD_276
  U5D1   F83  RSVD<276>  SKX_EXT_B_BGA1  I204

TP_CPU0_RSVD_277   @BASEBOARD_FAB2_LIB.BASEBOARD_FAB2(SCH_1):TP_CPU0_RSVD_277
  U5D1   F65  RSVD<277>  SKX_EXT_B_BGA1  I204

TP_CPU0_RSVD_278   @BASEBOARD_FAB2_LIB.BASEBOARD_FAB2(SCH_1):TP_CPU0_RSVD_278
  U5D1   F23  RSVD<278>  SKX_EXT_B_BGA1  I204

TP_CPU0_RSVD_279   @BASEBOARD_FAB2_LIB.BASEBOARD_FAB2(SCH_1):TP_CPU0_RSVD_279
  U5D1    F3  RSVD<279>  SKX_EXT_B_BGA1  I204

TP_CPU0_RSVD_280   @BASEBOARD_FAB2_LIB.BASEBOARD_FAB2(SCH_1):TP_CPU0_RSVD_280
  U5D1   E84  RSVD<280>  SKX_EXT_B_BGA1  I204

TP_CPU0_RSVD_281   @BASEBOARD_FAB2_LIB.BASEBOARD_FAB2(SCH_1):TP_CPU0_RSVD_281
  U5D1   E24  RSVD<281>  SKX_EXT_B_BGA1  I204

TP_CPU0_RSVD_282   @BASEBOARD_FAB2_LIB.BASEBOARD_FAB2(SCH_1):TP_CPU0_RSVD_282
  U5D1    E4  RSVD<282>  SKX_EXT_B_BGA1  I204

TP_CPU0_RSVD_283   @BASEBOARD_FAB2_LIB.BASEBOARD_FAB2(SCH_1):TP_CPU0_RSVD_283
  U5D1    E2  RSVD<283>  SKX_EXT_B_BGA1  I204

TP_CPU0_RSVD_284   @BASEBOARD_FAB2_LIB.BASEBOARD_FAB2(SCH_1):TP_CPU0_RSVD_284
  U5D1   D83  RSVD<284>  SKX_EXT_B_BGA1  I204

TP_CPU0_RSVD_285   @BASEBOARD_FAB2_LIB.BASEBOARD_FAB2(SCH_1):TP_CPU0_RSVD_285
  U5D1   D65  RSVD<285>  SKX_EXT_B_BGA1  I204

TP_CPU0_RSVD_286   @BASEBOARD_FAB2_LIB.BASEBOARD_FAB2(SCH_1):TP_CPU0_RSVD_286
  U5D1   D17  RSVD<286>  SKX_EXT_B_BGA1  I204

TP_CPU0_RSVD_287   @BASEBOARD_FAB2_LIB.BASEBOARD_FAB2(SCH_1):TP_CPU0_RSVD_287
  U5D1    D5  RSVD<287>  SKX_EXT_B_BGA1  I204

TP_CPU0_RSVD_288   @BASEBOARD_FAB2_LIB.BASEBOARD_FAB2(SCH_1):TP_CPU0_RSVD_288
  U5D1   C82  RSVD<288>  SKX_EXT_B_BGA1  I204

TP_CPU0_RSVD_289   @BASEBOARD_FAB2_LIB.BASEBOARD_FAB2(SCH_1):TP_CPU0_RSVD_289
  U5D1   C24  RSVD<289>  SKX_EXT_B_BGA1  I204

TP_CPU0_RSVD_290   @BASEBOARD_FAB2_LIB.BASEBOARD_FAB2(SCH_1):TP_CPU0_RSVD_290
  U5D1   C18  RSVD<290>  SKX_EXT_B_BGA1  I204

TP_CPU0_RSVD_291   @BASEBOARD_FAB2_LIB.BASEBOARD_FAB2(SCH_1):TP_CPU0_RSVD_291
  U5D1    C6  RSVD<291>  SKX_EXT_B_BGA1  I204

TP_CPU0_RSVD_292   @BASEBOARD_FAB2_LIB.BASEBOARD_FAB2(SCH_1):TP_CPU0_RSVD_292
  U5D1   B81  RSVD<292>  SKX_EXT_B_BGA1  I204

TP_CPU0_RSVD_293   @BASEBOARD_FAB2_LIB.BASEBOARD_FAB2(SCH_1):TP_CPU0_RSVD_293
  U5D1   B77  RSVD<293>  SKX_EXT_B_BGA1  I204

TP_CPU0_RSVD_298   @BASEBOARD_FAB2_LIB.BASEBOARD_FAB2(SCH_1):TP_CPU0_RSVD_298
  U5D1    B7  RSVD<298>  SKX_EXT_B_BGA1  I204

TP_CPU0_RSVD_299   @BASEBOARD_FAB2_LIB.BASEBOARD_FAB2(SCH_1):TP_CPU0_RSVD_299
  U5D1    B3  RSVD<299>  SKX_EXT_B_BGA1  I204

TP_CPU0_RSVD_300   @BASEBOARD_FAB2_LIB.BASEBOARD_FAB2(SCH_1):TP_CPU0_RSVD_300
  U5D1   A24  RSVD<300>  SKX_EXT_B_BGA1  I204

TP_CPU0_RSVD_303   @BASEBOARD_FAB2_LIB.BASEBOARD_FAB2(SCH_1):TP_CPU0_RSVD_303
  U5D1    A6  RSVD<303>  SKX_EXT_B_BGA1  I204

TP_CPU0_RSVD_304   @BASEBOARD_FAB2_LIB.BASEBOARD_FAB2(SCH_1):TP_CPU0_RSVD_304
  U5D1    A4  RSVD<304>  SKX_EXT_B_BGA1  I204

TP_CPU0_RSVD_TEST_3   @BASEBOARD_FAB2_LIB.BASEBOARD_FAB2(SCH_1):TP_CPU0_RSVD_TEST_3
  U5D1   AM13  TEST_3  SKX_EXT_B_BGA1  I204

TP_CPU0_RSVD_TEST_4   @BASEBOARD_FAB2_LIB.BASEBOARD_FAB2(SCH_1):TP_CPU0_RSVD_TEST_4
  U5D1   AN12  TEST_4  SKX_EXT_B_BGA1  I204

TP_CPU0_RSVD_TEST_5   @BASEBOARD_FAB2_LIB.BASEBOARD_FAB2(SCH_1):TP_CPU0_RSVD_TEST_5
  U5D1   AN14  TEST_5  SKX_EXT_B_BGA1  I204

TP_CPU0_RSVD_TEST_11   @BASEBOARD_FAB2_LIB.BASEBOARD_FAB2(SCH_1):TP_CPU0_RSVD_TEST_11
  U5D1   AY13  TEST_11  SKX_EXT_B_BGA1  I204

TP_CPU0_SOCKET_ID_2   @BASEBOARD_FAB2_LIB.BASEBOARD_FAB2(SCH_1):TP_CPU0_SOCKET_ID_2
  U5D1   AU20  SOCKET_ID<2>  SKX_EXT_B_BGA1  I259

TP_CPU0_TEST_6   @BASEBOARD_FAB2_LIB.BASEBOARD_FAB2(SCH_1):TP_CPU0_TEST_6
  U5D1   AR16  TEST_6  SKX_EXT_B_BGA1  I16

TP_CPU0_TEST_7   @BASEBOARD_FAB2_LIB.BASEBOARD_FAB2(SCH_1):TP_CPU0_TEST_7
  U5D1   AU18  TEST_7  SKX_EXT_B_BGA1  I16

TP_CPU0_TEST_8   @BASEBOARD_FAB2_LIB.BASEBOARD_FAB2(SCH_1):TP_CPU0_TEST_8
  U5D1   AW16  TEST_8  SKX_EXT_B_BGA1  I16

TP_CPU0_TEST_9   @BASEBOARD_FAB2_LIB.BASEBOARD_FAB2(SCH_1):TP_CPU0_TEST_9
  U5D1   AW20  TEST_9  SKX_EXT_B_BGA1  I16

TP_CPU0_TEST_10   @BASEBOARD_FAB2_LIB.BASEBOARD_FAB2(SCH_1):TP_CPU0_TEST_10
  U5D1   AW22  TEST_10  SKX_EXT_B_BGA1  I16

TP_CPU0_UPI2_RSVD_CA12   @BASEBOARD_FAB2_LIB.BASEBOARD_FAB2(SCH_1):TP_CPU0_UPI2_RSVD_CA12
  U5D1   DP21  UPI2_TX_DP<0>  SKX_EXT_B_BGA1   I3

TP_CPU0_UPI2_RSVD_CB11   @BASEBOARD_FAB2_LIB.BASEBOARD_FAB2(SCH_1):TP_CPU0_UPI2_RSVD_CB11
  U5D1   DN20  UPI2_TX_DP<1>  SKX_EXT_B_BGA1   I3

TP_CPU0_UPI2_RSVD_CC10   @BASEBOARD_FAB2_LIB.BASEBOARD_FAB2(SCH_1):TP_CPU0_UPI2_RSVD_CC10
  U5D1   DM21  UPI2_TX_DN<1>  SKX_EXT_B_BGA1   I3

TP_CPU0_UPI2_RSVD_CC12   @BASEBOARD_FAB2_LIB.BASEBOARD_FAB2(SCH_1):TP_CPU0_UPI2_RSVD_CC12
  U5D1   DT21  UPI2_TX_DN<0>  SKX_EXT_B_BGA1   I3

TP_CPU0_UPI2_RSVD_CD11   @BASEBOARD_FAB2_LIB.BASEBOARD_FAB2(SCH_1):TP_CPU0_UPI2_RSVD_CD11
  U5D1   DK19  UPI2_TX_DP<2>  SKX_EXT_B_BGA1   I3

TP_CPU0_UPI2_RSVD_CE12   @BASEBOARD_FAB2_LIB.BASEBOARD_FAB2(SCH_1):TP_CPU0_UPI2_RSVD_CE12
  U5D1   DL20  UPI2_TX_DN<2>  SKX_EXT_B_BGA1   I3

TP_CPU0_UPI2_RSVD_CF11   @BASEBOARD_FAB2_LIB.BASEBOARD_FAB2(SCH_1):TP_CPU0_UPI2_RSVD_CF11
  U5D1   DJ20  UPI2_TX_DP<3>  SKX_EXT_B_BGA1   I3

TP_CPU0_UPI2_RSVD_CF13   @BASEBOARD_FAB2_LIB.BASEBOARD_FAB2(SCH_1):TP_CPU0_UPI2_RSVD_CF13
  U5D1   DH19  UPI2_TX_DN<4>  SKX_EXT_B_BGA1   I3

TP_CPU0_UPI2_RSVD_CG12   @BASEBOARD_FAB2_LIB.BASEBOARD_FAB2(SCH_1):TP_CPU0_UPI2_RSVD_CG12
  U5D1   DJ18  UPI2_TX_DP<4>  SKX_EXT_B_BGA1   I3

TP_CPU0_UPI2_RSVD_CH11   @BASEBOARD_FAB2_LIB.BASEBOARD_FAB2(SCH_1):TP_CPU0_UPI2_RSVD_CH11
  U5D1   DG20  UPI2_TX_DN<3>  SKX_EXT_B_BGA1   I3

TP_CPU0_UPI2_RSVD_CH13   @BASEBOARD_FAB2_LIB.BASEBOARD_FAB2(SCH_1):TP_CPU0_UPI2_RSVD_CH13
  U5D1   DH17  UPI2_TX_DP<5>  SKX_EXT_B_BGA1   I3

TP_CPU0_UPI2_RSVD_CJ14   @BASEBOARD_FAB2_LIB.BASEBOARD_FAB2(SCH_1):TP_CPU0_UPI2_RSVD_CJ14
  U5D1   DK17  UPI2_TX_DN<5>  SKX_EXT_B_BGA1   I3

TP_CPU0_UPI2_RSVD_CK13   @BASEBOARD_FAB2_LIB.BASEBOARD_FAB2(SCH_1):TP_CPU0_UPI2_RSVD_CK13
  U5D1   DF17  UPI2_TX_DP<6>  SKX_EXT_B_BGA1   I3

TP_CPU0_UPI2_RSVD_CM13   @BASEBOARD_FAB2_LIB.BASEBOARD_FAB2(SCH_1):TP_CPU0_UPI2_RSVD_CM13
  U5D1   DG18  UPI2_TX_DN<6>  SKX_EXT_B_BGA1   I3

TP_CPU0_UPI2_RSVD_CR14   @BASEBOARD_FAB2_LIB.BASEBOARD_FAB2(SCH_1):TP_CPU0_UPI2_RSVD_CR14
  U5D1   DE16  UPI2_TX_DP<7>  SKX_EXT_B_BGA1   I3

TP_CPU0_UPI2_RSVD_CU14   @BASEBOARD_FAB2_LIB.BASEBOARD_FAB2(SCH_1):TP_CPU0_UPI2_RSVD_CU14
  U5D1   DD17  UPI2_TX_DN<7>  SKX_EXT_B_BGA1   I3

TP_CPU0_UPI2_RSVD_CV13   @BASEBOARD_FAB2_LIB.BASEBOARD_FAB2(SCH_1):TP_CPU0_UPI2_RSVD_CV13
  U5D1   DD15  UPI2_TX_DP<8>  SKX_EXT_B_BGA1   I3

TP_CPU0_UPI2_RSVD_CW14   @BASEBOARD_FAB2_LIB.BASEBOARD_FAB2(SCH_1):TP_CPU0_UPI2_RSVD_CW14
  U5D1   DF15  UPI2_TX_DN<8>  SKX_EXT_B_BGA1   I3

TP_CPU0_UPI2_RSVD_CW16   @BASEBOARD_FAB2_LIB.BASEBOARD_FAB2(SCH_1):TP_CPU0_UPI2_RSVD_CW16
  U5D1   DB15  UPI2_TX_DP<9>  SKX_EXT_B_BGA1   I3

TP_CPU0_UPI2_RSVD_DA16   @BASEBOARD_FAB2_LIB.BASEBOARD_FAB2(SCH_1):TP_CPU0_UPI2_RSVD_DA16
  U5D1   DC16  UPI2_TX_DN<9>  SKX_EXT_B_BGA1   I3

TP_CPU0_UPI2_RSVD_DB15   @BASEBOARD_FAB2_LIB.BASEBOARD_FAB2(SCH_1):TP_CPU0_UPI2_RSVD_DB15
  U5D1   CW16  UPI2_TX_DP<10>  SKX_EXT_B_BGA1   I3

TP_CPU0_UPI2_RSVD_DC16   @BASEBOARD_FAB2_LIB.BASEBOARD_FAB2(SCH_1):TP_CPU0_UPI2_RSVD_DC16
  U5D1   DA16  UPI2_TX_DN<10>  SKX_EXT_B_BGA1   I3

TP_CPU0_UPI2_RSVD_DD15   @BASEBOARD_FAB2_LIB.BASEBOARD_FAB2(SCH_1):TP_CPU0_UPI2_RSVD_DD15
  U5D1   CV13  UPI2_TX_DP<11>  SKX_EXT_B_BGA1   I3

TP_CPU0_UPI2_RSVD_DD17   @BASEBOARD_FAB2_LIB.BASEBOARD_FAB2(SCH_1):TP_CPU0_UPI2_RSVD_DD17
  U5D1   CU14  UPI2_TX_DN<12>  SKX_EXT_B_BGA1   I3

TP_CPU0_UPI2_RSVD_DE16   @BASEBOARD_FAB2_LIB.BASEBOARD_FAB2(SCH_1):TP_CPU0_UPI2_RSVD_DE16
  U5D1   CR14  UPI2_TX_DP<12>  SKX_EXT_B_BGA1   I3

TP_CPU0_UPI2_RSVD_DF15   @BASEBOARD_FAB2_LIB.BASEBOARD_FAB2(SCH_1):TP_CPU0_UPI2_RSVD_DF15
  U5D1   CW14  UPI2_TX_DN<11>  SKX_EXT_B_BGA1   I3

TP_CPU0_UPI2_RSVD_DF17   @BASEBOARD_FAB2_LIB.BASEBOARD_FAB2(SCH_1):TP_CPU0_UPI2_RSVD_DF17
  U5D1   CK13  UPI2_TX_DP<13>  SKX_EXT_B_BGA1   I3

TP_CPU0_UPI2_RSVD_DG18   @BASEBOARD_FAB2_LIB.BASEBOARD_FAB2(SCH_1):TP_CPU0_UPI2_RSVD_DG18
  U5D1   CM13  UPI2_TX_DN<13>  SKX_EXT_B_BGA1   I3

TP_CPU0_UPI2_RSVD_DG20   @BASEBOARD_FAB2_LIB.BASEBOARD_FAB2(SCH_1):TP_CPU0_UPI2_RSVD_DG20
  U5D1   CH11  UPI2_TX_DN<16>  SKX_EXT_B_BGA1   I3

TP_CPU0_UPI2_RSVD_DH17   @BASEBOARD_FAB2_LIB.BASEBOARD_FAB2(SCH_1):TP_CPU0_UPI2_RSVD_DH17
  U5D1   CH13  UPI2_TX_DP<14>  SKX_EXT_B_BGA1   I3

TP_CPU0_UPI2_RSVD_DH19   @BASEBOARD_FAB2_LIB.BASEBOARD_FAB2(SCH_1):TP_CPU0_UPI2_RSVD_DH19
  U5D1   CF13  UPI2_TX_DN<15>  SKX_EXT_B_BGA1   I3

TP_CPU0_UPI2_RSVD_DJ18   @BASEBOARD_FAB2_LIB.BASEBOARD_FAB2(SCH_1):TP_CPU0_UPI2_RSVD_DJ18
  U5D1   CG12  UPI2_TX_DP<15>  SKX_EXT_B_BGA1   I3

TP_CPU0_UPI2_RSVD_DJ20   @BASEBOARD_FAB2_LIB.BASEBOARD_FAB2(SCH_1):TP_CPU0_UPI2_RSVD_DJ20
  U5D1   CF11  UPI2_TX_DP<16>  SKX_EXT_B_BGA1   I3

TP_CPU0_UPI2_RSVD_DK17   @BASEBOARD_FAB2_LIB.BASEBOARD_FAB2(SCH_1):TP_CPU0_UPI2_RSVD_DK17
  U5D1   CJ14  UPI2_TX_DN<14>  SKX_EXT_B_BGA1   I3

TP_CPU0_UPI2_RSVD_DK19   @BASEBOARD_FAB2_LIB.BASEBOARD_FAB2(SCH_1):TP_CPU0_UPI2_RSVD_DK19
  U5D1   CD11  UPI2_TX_DP<17>  SKX_EXT_B_BGA1   I3

TP_CPU0_UPI2_RSVD_DL20   @BASEBOARD_FAB2_LIB.BASEBOARD_FAB2(SCH_1):TP_CPU0_UPI2_RSVD_DL20
  U5D1   CE12  UPI2_TX_DN<17>  SKX_EXT_B_BGA1   I3

TP_CPU0_UPI2_RSVD_DM21   @BASEBOARD_FAB2_LIB.BASEBOARD_FAB2(SCH_1):TP_CPU0_UPI2_RSVD_DM21
  U5D1   CC10  UPI2_TX_DN<18>  SKX_EXT_B_BGA1   I3

TP_CPU0_UPI2_RSVD_DN20   @BASEBOARD_FAB2_LIB.BASEBOARD_FAB2(SCH_1):TP_CPU0_UPI2_RSVD_DN20
  U5D1   CB11  UPI2_TX_DP<18>  SKX_EXT_B_BGA1   I3

TP_CPU0_UPI2_RSVD_DP21   @BASEBOARD_FAB2_LIB.BASEBOARD_FAB2(SCH_1):TP_CPU0_UPI2_RSVD_DP21
  U5D1   CA12  UPI2_TX_DP<19>  SKX_EXT_B_BGA1   I3

TP_CPU0_UPI2_RSVD_DT21   @BASEBOARD_FAB2_LIB.BASEBOARD_FAB2(SCH_1):TP_CPU0_UPI2_RSVD_DT21
  U5D1   CC12  UPI2_TX_DN<19>  SKX_EXT_B_BGA1   I3

TP_CPU1_DMI_RX_DN0   @BASEBOARD_FAB2_LIB.BASEBOARD_FAB2(SCH_1):TP_CPU1_DMI_RX_DN0
  U2D1   CK9  DMI_RX_DN<0>  SKX_EXT_B_BGA1  I23

TP_CPU1_DMI_RX_DN1   @BASEBOARD_FAB2_LIB.BASEBOARD_FAB2(SCH_1):TP_CPU1_DMI_RX_DN1
  U2D1   CM11  DMI_RX_DN<1>  SKX_EXT_B_BGA1  I23

TP_CPU1_DMI_RX_DN2   @BASEBOARD_FAB2_LIB.BASEBOARD_FAB2(SCH_1):TP_CPU1_DMI_RX_DN2
  U2D1   CR12  DMI_RX_DN<2>  SKX_EXT_B_BGA1  I23

TP_CPU1_DMI_RX_DN3   @BASEBOARD_FAB2_LIB.BASEBOARD_FAB2(SCH_1):TP_CPU1_DMI_RX_DN3
  U2D1   CT11  DMI_RX_DN<3>  SKX_EXT_B_BGA1  I23

TP_CPU1_DMI_RX_DP0   @BASEBOARD_FAB2_LIB.BASEBOARD_FAB2(SCH_1):TP_CPU1_DMI_RX_DP0
  U2D1   CL10  DMI_RX_DP<0>  SKX_EXT_B_BGA1  I23

TP_CPU1_DMI_RX_DP1   @BASEBOARD_FAB2_LIB.BASEBOARD_FAB2(SCH_1):TP_CPU1_DMI_RX_DP1
  U2D1   CN10  DMI_RX_DP<1>  SKX_EXT_B_BGA1  I23

TP_CPU1_DMI_RX_DP2   @BASEBOARD_FAB2_LIB.BASEBOARD_FAB2(SCH_1):TP_CPU1_DMI_RX_DP2
  U2D1   CP11  DMI_RX_DP<2>  SKX_EXT_B_BGA1  I23

TP_CPU1_DMI_RX_DP3   @BASEBOARD_FAB2_LIB.BASEBOARD_FAB2(SCH_1):TP_CPU1_DMI_RX_DP3
  U2D1   CV11  DMI_RX_DP<3>  SKX_EXT_B_BGA1  I23

TP_CPU1_DMI_TX_DN0   @BASEBOARD_FAB2_LIB.BASEBOARD_FAB2(SCH_1):TP_CPU1_DMI_TX_DN0
  U2D1   CG4  DMI_TX_DN<0>  SKX_EXT_B_BGA1  I23

TP_CPU1_DMI_TX_DN1   @BASEBOARD_FAB2_LIB.BASEBOARD_FAB2(SCH_1):TP_CPU1_DMI_TX_DN1
  U2D1   CJ4  DMI_TX_DN<1>  SKX_EXT_B_BGA1  I23

TP_CPU1_DMI_TX_DN2   @BASEBOARD_FAB2_LIB.BASEBOARD_FAB2(SCH_1):TP_CPU1_DMI_TX_DN2
  U2D1   CN4  DMI_TX_DN<2>  SKX_EXT_B_BGA1  I23

TP_CPU1_DMI_TX_DN3   @BASEBOARD_FAB2_LIB.BASEBOARD_FAB2(SCH_1):TP_CPU1_DMI_TX_DN3
  U2D1   CP5  DMI_TX_DN<3>  SKX_EXT_B_BGA1  I23

TP_CPU1_DMI_TX_DP0   @BASEBOARD_FAB2_LIB.BASEBOARD_FAB2(SCH_1):TP_CPU1_DMI_TX_DP0
  U2D1   CH5  DMI_TX_DP<0>  SKX_EXT_B_BGA1  I23

TP_CPU1_DMI_TX_DP1   @BASEBOARD_FAB2_LIB.BASEBOARD_FAB2(SCH_1):TP_CPU1_DMI_TX_DP1
  U2D1   CL4  DMI_TX_DP<1>  SKX_EXT_B_BGA1  I23

TP_CPU1_DMI_TX_DP2   @BASEBOARD_FAB2_LIB.BASEBOARD_FAB2(SCH_1):TP_CPU1_DMI_TX_DP2
  U2D1   CM3  DMI_TX_DP<2>  SKX_EXT_B_BGA1  I23

TP_CPU1_DMI_TX_DP3   @BASEBOARD_FAB2_LIB.BASEBOARD_FAB2(SCH_1):TP_CPU1_DMI_TX_DP3
  U2D1   CR4  DMI_TX_DP<3>  SKX_EXT_B_BGA1  I23

TP_CPU1_KTI2_AMONV   @BASEBOARD_FAB2_LIB.BASEBOARD_FAB2(SCH_1):TP_CPU1_KTI2_AMONV
  U2D1   CN22  RSVD<77>  SKX_EXT_B_BGA1  I107

TP_CPU1_KTI2_DFX_DN   @BASEBOARD_FAB2_LIB.BASEBOARD_FAB2(SCH_1):TP_CPU1_KTI2_DFX_DN
  U2D1   CW22  RSVD<63>  SKX_EXT_B_BGA1  I107

TP_CPU1_NMI     @BASEBOARD_FAB2_LIB.BASEBOARD_FAB2(SCH_1):TP_CPU1_NMI
  U2D1   AP11    NMI  SKX_EXT_B_BGA1  I172

TP_CPU1_PROC_DIS_G_N   @BASEBOARD_FAB2_LIB.BASEBOARD_FAB2(SCH_1):TP_CPU1_PROC_DIS_G_N
  U2D1   AB17  PROCDIS_N  SKX_EXT_B_BGA1  I172

TP_CPU1_RSVD_0   @BASEBOARD_FAB2_LIB.BASEBOARD_FAB2(SCH_1):TP_CPU1_RSVD_0
  U2D1   EF83  RSVD<0>  SKX_EXT_B_BGA1  I107

TP_CPU1_RSVD_1   @BASEBOARD_FAB2_LIB.BASEBOARD_FAB2(SCH_1):TP_CPU1_RSVD_1
  U2D1   EF81  RSVD<1>  SKX_EXT_B_BGA1  I107

TP_CPU1_RSVD_2   @BASEBOARD_FAB2_LIB.BASEBOARD_FAB2(SCH_1):TP_CPU1_RSVD_2
  U2D1   EF77  RSVD<2>  SKX_EXT_B_BGA1  I107

TP_CPU1_RSVD_3   @BASEBOARD_FAB2_LIB.BASEBOARD_FAB2(SCH_1):TP_CPU1_RSVD_3
  U2D1   EF47  RSVD<3>  SKX_EXT_B_BGA1  I107

TP_CPU1_RSVD_4   @BASEBOARD_FAB2_LIB.BASEBOARD_FAB2(SCH_1):TP_CPU1_RSVD_4
  U2D1   EE84  RSVD<4>  SKX_EXT_B_BGA1  I107

TP_CPU1_RSVD_5   @BASEBOARD_FAB2_LIB.BASEBOARD_FAB2(SCH_1):TP_CPU1_RSVD_5
  U2D1   EE82  RSVD<5>  SKX_EXT_B_BGA1  I107

TP_CPU1_RSVD_6   @BASEBOARD_FAB2_LIB.BASEBOARD_FAB2(SCH_1):TP_CPU1_RSVD_6
  U2D1   EE6  RSVD<6>  SKX_EXT_B_BGA1  I107

TP_CPU1_RSVD_7   @BASEBOARD_FAB2_LIB.BASEBOARD_FAB2(SCH_1):TP_CPU1_RSVD_7
  U2D1   EE46  RSVD<7>  SKX_EXT_B_BGA1  I107

TP_CPU1_RSVD_8   @BASEBOARD_FAB2_LIB.BASEBOARD_FAB2(SCH_1):TP_CPU1_RSVD_8
  U2D1   EE16  RSVD<8>  SKX_EXT_B_BGA1  I107

TP_CPU1_RSVD_9   @BASEBOARD_FAB2_LIB.BASEBOARD_FAB2(SCH_1):TP_CPU1_RSVD_9
  U2D1   ED83  RSVD<9>  SKX_EXT_B_BGA1  I107

TP_CPU1_RSVD_10   @BASEBOARD_FAB2_LIB.BASEBOARD_FAB2(SCH_1):TP_CPU1_RSVD_10
  U2D1   ED5  RSVD<10>  SKX_EXT_B_BGA1  I107

TP_CPU1_RSVD_11   @BASEBOARD_FAB2_LIB.BASEBOARD_FAB2(SCH_1):TP_CPU1_RSVD_11
  U2D1   ED45  RSVD<11>  SKX_EXT_B_BGA1  I107

TP_CPU1_RSVD_12   @BASEBOARD_FAB2_LIB.BASEBOARD_FAB2(SCH_1):TP_CPU1_RSVD_12
  U2D1   EC84  RSVD<12>  SKX_EXT_B_BGA1  I107

TP_CPU1_RSVD_13   @BASEBOARD_FAB2_LIB.BASEBOARD_FAB2(SCH_1):TP_CPU1_RSVD_13
  U2D1   EC44  RSVD<13>  SKX_EXT_B_BGA1  I107

TP_CPU1_RSVD_14   @BASEBOARD_FAB2_LIB.BASEBOARD_FAB2(SCH_1):TP_CPU1_RSVD_14
  U2D1   EC4  RSVD<14>  SKX_EXT_B_BGA1  I107

TP_CPU1_RSVD_15   @BASEBOARD_FAB2_LIB.BASEBOARD_FAB2(SCH_1):TP_CPU1_RSVD_15
  U2D1   EC16  RSVD<15>  SKX_EXT_B_BGA1  I107

TP_CPU1_RSVD_16   @BASEBOARD_FAB2_LIB.BASEBOARD_FAB2(SCH_1):TP_CPU1_RSVD_16
  U2D1   EB85  RSVD<16>  SKX_EXT_B_BGA1  I107

TP_CPU1_RSVD_17   @BASEBOARD_FAB2_LIB.BASEBOARD_FAB2(SCH_1):TP_CPU1_RSVD_17
  U2D1   EB5  RSVD<17>  SKX_EXT_B_BGA1  I107

TP_CPU1_RSVD_18   @BASEBOARD_FAB2_LIB.BASEBOARD_FAB2(SCH_1):TP_CPU1_RSVD_18
  U2D1   EB3  RSVD<18>  SKX_EXT_B_BGA1  I107

TP_CPU1_RSVD_19   @BASEBOARD_FAB2_LIB.BASEBOARD_FAB2(SCH_1):TP_CPU1_RSVD_19
  U2D1   EA44  RSVD<19>  SKX_EXT_B_BGA1  I107

TP_CPU1_RSVD_20   @BASEBOARD_FAB2_LIB.BASEBOARD_FAB2(SCH_1):TP_CPU1_RSVD_20
  U2D1   EA4  RSVD<20>  SKX_EXT_B_BGA1  I107

TP_CPU1_RSVD_21   @BASEBOARD_FAB2_LIB.BASEBOARD_FAB2(SCH_1):TP_CPU1_RSVD_21
  U2D1   DY3  RSVD<21>  SKX_EXT_B_BGA1  I107

TP_CPU1_RSVD_22   @BASEBOARD_FAB2_LIB.BASEBOARD_FAB2(SCH_1):TP_CPU1_RSVD_22
  U2D1   DW46  RSVD<22>  SKX_EXT_B_BGA1  I107

TP_CPU1_RSVD_23   @BASEBOARD_FAB2_LIB.BASEBOARD_FAB2(SCH_1):TP_CPU1_RSVD_23
  U2D1   DW44  RSVD<23>  SKX_EXT_B_BGA1  I107

TP_CPU1_RSVD_24   @BASEBOARD_FAB2_LIB.BASEBOARD_FAB2(SCH_1):TP_CPU1_RSVD_24
  U2D1   DV71  RSVD<24>  SKX_EXT_B_BGA1  I107

TP_CPU1_RSVD_25   @BASEBOARD_FAB2_LIB.BASEBOARD_FAB2(SCH_1):TP_CPU1_RSVD_25
  U2D1   DV61  RSVD<25>  SKX_EXT_B_BGA1  I107

TP_CPU1_RSVD_26   @BASEBOARD_FAB2_LIB.BASEBOARD_FAB2(SCH_1):TP_CPU1_RSVD_26
  U2D1   DU44  RSVD<26>  SKX_EXT_B_BGA1  I107

TP_CPU1_RSVD_27   @BASEBOARD_FAB2_LIB.BASEBOARD_FAB2(SCH_1):TP_CPU1_RSVD_27
  U2D1   DT71  RSVD<27>  SKX_EXT_B_BGA1  I107

TP_CPU1_RSVD_28   @BASEBOARD_FAB2_LIB.BASEBOARD_FAB2(SCH_1):TP_CPU1_RSVD_28
  U2D1   DR44  RSVD<28>  SKX_EXT_B_BGA1  I107

TP_CPU1_RSVD_29   @BASEBOARD_FAB2_LIB.BASEBOARD_FAB2(SCH_1):TP_CPU1_RSVD_29
  U2D1   DP65  RSVD<29>  SKX_EXT_B_BGA1  I107

TP_CPU1_RSVD_30   @BASEBOARD_FAB2_LIB.BASEBOARD_FAB2(SCH_1):TP_CPU1_RSVD_30
  U2D1   DP17  RSVD<30>  SKX_EXT_B_BGA1  I107

TP_CPU1_RSVD_31   @BASEBOARD_FAB2_LIB.BASEBOARD_FAB2(SCH_1):TP_CPU1_RSVD_31
  U2D1   DN66  RSVD<31>  SKX_EXT_B_BGA1  I107

TP_CPU1_RSVD_32   @BASEBOARD_FAB2_LIB.BASEBOARD_FAB2(SCH_1):TP_CPU1_RSVD_32
  U2D1   DN62  RSVD<32>  SKX_EXT_B_BGA1  I107

TP_CPU1_RSVD_33   @BASEBOARD_FAB2_LIB.BASEBOARD_FAB2(SCH_1):TP_CPU1_RSVD_33
  U2D1   DM67  RSVD<33>  SKX_EXT_B_BGA1  I107

TP_CPU1_RSVD_34   @BASEBOARD_FAB2_LIB.BASEBOARD_FAB2(SCH_1):TP_CPU1_RSVD_34
  U2D1   DL66  RSVD<34>  SKX_EXT_B_BGA1  I107

TP_CPU1_RSVD_35   @BASEBOARD_FAB2_LIB.BASEBOARD_FAB2(SCH_1):TP_CPU1_RSVD_35
  U2D1   DL38  RSVD<35>  SKX_EXT_B_BGA1  I107

TP_CPU1_RSVD_36   @BASEBOARD_FAB2_LIB.BASEBOARD_FAB2(SCH_1):TP_CPU1_RSVD_36
  U2D1   DK67  RSVD<36>  SKX_EXT_B_BGA1  I107

TP_CPU1_RSVD_37   @BASEBOARD_FAB2_LIB.BASEBOARD_FAB2(SCH_1):TP_CPU1_RSVD_37
  U2D1   DK65  RSVD<37>  SKX_EXT_B_BGA1  I107

TP_CPU1_RSVD_38   @BASEBOARD_FAB2_LIB.BASEBOARD_FAB2(SCH_1):TP_CPU1_RSVD_38
  U2D1   DK37  RSVD<38>  SKX_EXT_B_BGA1  I107

TP_CPU1_RSVD_39   @BASEBOARD_FAB2_LIB.BASEBOARD_FAB2(SCH_1):TP_CPU1_RSVD_39
  U2D1   DK15  RSVD<39>  SKX_EXT_B_BGA1  I107

TP_CPU1_RSVD_40   @BASEBOARD_FAB2_LIB.BASEBOARD_FAB2(SCH_1):TP_CPU1_RSVD_40
  U2D1   DJ66  RSVD<40>  SKX_EXT_B_BGA1  I107

TP_CPU1_RSVD_41   @BASEBOARD_FAB2_LIB.BASEBOARD_FAB2(SCH_1):TP_CPU1_RSVD_41
  U2D1   DJ36  RSVD<41>  SKX_EXT_B_BGA1  I107

TP_CPU1_RSVD_42   @BASEBOARD_FAB2_LIB.BASEBOARD_FAB2(SCH_1):TP_CPU1_RSVD_42
  U2D1   DH65  RSVD<42>  SKX_EXT_B_BGA1  I107

TP_CPU1_RSVD_43   @BASEBOARD_FAB2_LIB.BASEBOARD_FAB2(SCH_1):TP_CPU1_RSVD_43
  U2D1   DG64  RSVD<43>  SKX_EXT_B_BGA1  I107

TP_CPU1_RSVD_44   @BASEBOARD_FAB2_LIB.BASEBOARD_FAB2(SCH_1):TP_CPU1_RSVD_44
  U2D1   DG36  RSVD<44>  SKX_EXT_B_BGA1  I107

TP_CPU1_RSVD_45   @BASEBOARD_FAB2_LIB.BASEBOARD_FAB2(SCH_1):TP_CPU1_RSVD_45
  U2D1   DD51  RSVD<45>  SKX_EXT_B_BGA1  I107

TP_CPU1_RSVD_46   @BASEBOARD_FAB2_LIB.BASEBOARD_FAB2(SCH_1):TP_CPU1_RSVD_46
  U2D1   DC52  RSVD<46>  SKX_EXT_B_BGA1  I107

TP_CPU1_RSVD_47   @BASEBOARD_FAB2_LIB.BASEBOARD_FAB2(SCH_1):TP_CPU1_RSVD_47
  U2D1   DC46  RSVD<47>  SKX_EXT_B_BGA1  I107

TP_CPU1_RSVD_48   @BASEBOARD_FAB2_LIB.BASEBOARD_FAB2(SCH_1):TP_CPU1_RSVD_48
  U2D1   DA56  RSVD<48>  SKX_EXT_B_BGA1  I107

TP_CPU1_RSVD_49   @BASEBOARD_FAB2_LIB.BASEBOARD_FAB2(SCH_1):TP_CPU1_RSVD_49
  U2D1   DA54  RSVD<49>  SKX_EXT_B_BGA1  I107

TP_CPU1_RSVD_50   @BASEBOARD_FAB2_LIB.BASEBOARD_FAB2(SCH_1):TP_CPU1_RSVD_50
  U2D1   DA52  RSVD<50>  SKX_EXT_B_BGA1  I107

TP_CPU1_RSVD_51   @BASEBOARD_FAB2_LIB.BASEBOARD_FAB2(SCH_1):TP_CPU1_RSVD_51
  U2D1   DA40  RSVD<51>  SKX_EXT_B_BGA1  I107

TP_CPU1_RSVD_53   @BASEBOARD_FAB2_LIB.BASEBOARD_FAB2(SCH_1):TP_CPU1_RSVD_53
  U2D1   CY73  RSVD<53>  SKX_EXT_B_BGA1  I107

TP_CPU1_RSVD_54   @BASEBOARD_FAB2_LIB.BASEBOARD_FAB2(SCH_1):TP_CPU1_RSVD_54
  U2D1   CY63  RSVD<54>  SKX_EXT_B_BGA1  I107

TP_CPU1_RSVD_55   @BASEBOARD_FAB2_LIB.BASEBOARD_FAB2(SCH_1):TP_CPU1_RSVD_55
  U2D1   CY57  RSVD<55>  SKX_EXT_B_BGA1  I107

TP_CPU1_RSVD_56   @BASEBOARD_FAB2_LIB.BASEBOARD_FAB2(SCH_1):TP_CPU1_RSVD_56
  U2D1   CY53  RSVD<56>  SKX_EXT_B_BGA1  I107

TP_CPU1_RSVD_57   @BASEBOARD_FAB2_LIB.BASEBOARD_FAB2(SCH_1):TP_CPU1_RSVD_57
  U2D1   CY39  RSVD<57>  SKX_EXT_B_BGA1  I107

TP_CPU1_RSVD_59   @BASEBOARD_FAB2_LIB.BASEBOARD_FAB2(SCH_1):TP_CPU1_RSVD_59
  U2D1   CY23  RSVD<59>  SKX_EXT_B_BGA1  I107

TP_CPU1_RSVD_60   @BASEBOARD_FAB2_LIB.BASEBOARD_FAB2(SCH_1):TP_CPU1_RSVD_60
  U2D1   CW62  RSVD<60>  SKX_EXT_B_BGA1  I107

TP_CPU1_RSVD_61   @BASEBOARD_FAB2_LIB.BASEBOARD_FAB2(SCH_1):TP_CPU1_RSVD_61
  U2D1   CW60  RSVD<61>  SKX_EXT_B_BGA1  I107

TP_CPU1_RSVD_64   @BASEBOARD_FAB2_LIB.BASEBOARD_FAB2(SCH_1):TP_CPU1_RSVD_64
  U2D1   CV69  RSVD<64>  SKX_EXT_B_BGA1  I107

TP_CPU1_RSVD_66   @BASEBOARD_FAB2_LIB.BASEBOARD_FAB2(SCH_1):TP_CPU1_RSVD_66
  U2D1   CU60  RSVD<66>  SKX_EXT_B_BGA1  I107

TP_CPU1_RSVD_67   @BASEBOARD_FAB2_LIB.BASEBOARD_FAB2(SCH_1):TP_CPU1_RSVD_67
  U2D1   CU6  RSVD<67>  SKX_EXT_B_BGA1  I107

TP_CPU1_RSVD_69   @BASEBOARD_FAB2_LIB.BASEBOARD_FAB2(SCH_1):TP_CPU1_RSVD_69
  U2D1   CT69  RSVD<69>  SKX_EXT_B_BGA1  I107

TP_CPU1_RSVD_70   @BASEBOARD_FAB2_LIB.BASEBOARD_FAB2(SCH_1):TP_CPU1_RSVD_70
  U2D1   CT5  RSVD<70>  SKX_EXT_B_BGA1  I107

TP_CPU1_RSVD_72   @BASEBOARD_FAB2_LIB.BASEBOARD_FAB2(SCH_1):TP_CPU1_RSVD_72
  U2D1   CR60  RSVD<72>  SKX_EXT_B_BGA1  I107

TP_CPU1_RSVD_73   @BASEBOARD_FAB2_LIB.BASEBOARD_FAB2(SCH_1):TP_CPU1_RSVD_73
  U2D1   CP31  RSVD<73>  SKX_EXT_B_BGA1  I107

TP_CPU1_RSVD_82   @BASEBOARD_FAB2_LIB.BASEBOARD_FAB2(SCH_1):TP_CPU1_RSVD_82
  U2D1   CK77  RSVD<82>  SKX_EXT_B_BGA1  I10

TP_CPU1_RSVD_85   @BASEBOARD_FAB2_LIB.BASEBOARD_FAB2(SCH_1):TP_CPU1_RSVD_85
  U2D1   CK19  RSVD<85>  SKX_EXT_B_BGA1  I10

TP_CPU1_RSVD_90   @BASEBOARD_FAB2_LIB.BASEBOARD_FAB2(SCH_1):TP_CPU1_RSVD_90
  U2D1   CH77  RSVD<90>  SKX_EXT_B_BGA1  I10

TP_CPU1_RSVD_91   @BASEBOARD_FAB2_LIB.BASEBOARD_FAB2(SCH_1):TP_CPU1_RSVD_91
  U2D1   CH25  RSVD<91>  SKX_EXT_B_BGA1  I10

TP_CPU1_RSVD_94   @BASEBOARD_FAB2_LIB.BASEBOARD_FAB2(SCH_1):TP_CPU1_RSVD_94
  U2D1   CG82  RSVD<94>  SKX_EXT_B_BGA1   I9

TP_CPU1_RSVD_95   @BASEBOARD_FAB2_LIB.BASEBOARD_FAB2(SCH_1):TP_CPU1_RSVD_95
  U2D1   CG78  RSVD<95>  SKX_EXT_B_BGA1   I9

TP_CPU1_RSVD_97   @BASEBOARD_FAB2_LIB.BASEBOARD_FAB2(SCH_1):TP_CPU1_RSVD_97
  U2D1   CG24  RSVD<97>  SKX_EXT_B_BGA1   I9

TP_CPU1_RSVD_99   @BASEBOARD_FAB2_LIB.BASEBOARD_FAB2(SCH_1):TP_CPU1_RSVD_99
  U2D1   CG10  RSVD<99>  SKX_EXT_B_BGA1   I9

TP_CPU1_RSVD_100   @BASEBOARD_FAB2_LIB.BASEBOARD_FAB2(SCH_1):TP_CPU1_RSVD_100
  U2D1   CF81  RSVD<100>  SKX_EXT_B_BGA1   I9

TP_CPU1_RSVD_101   @BASEBOARD_FAB2_LIB.BASEBOARD_FAB2(SCH_1):TP_CPU1_RSVD_101
  U2D1   CF79  RSVD<101>  SKX_EXT_B_BGA1   I9

TP_CPU1_RSVD_105   @BASEBOARD_FAB2_LIB.BASEBOARD_FAB2(SCH_1):TP_CPU1_RSVD_105
  U2D1   CE80  RSVD<105>  SKX_EXT_B_BGA1   I9

TP_CPU1_RSVD_106   @BASEBOARD_FAB2_LIB.BASEBOARD_FAB2(SCH_1):TP_CPU1_RSVD_106
  U2D1   CE78  RSVD<106>  SKX_EXT_B_BGA1   I9

TP_CPU1_RSVD_108   @BASEBOARD_FAB2_LIB.BASEBOARD_FAB2(SCH_1):TP_CPU1_RSVD_108
  U2D1   CD25  RSVD<108>  SKX_EXT_B_BGA1   I9

TP_CPU1_RSVD_111   @BASEBOARD_FAB2_LIB.BASEBOARD_FAB2(SCH_1):TP_CPU1_RSVD_111
  U2D1   CC6  RSVD<111>  SKX_EXT_B_BGA1   I9

TP_CPU1_RSVD_113   @BASEBOARD_FAB2_LIB.BASEBOARD_FAB2(SCH_1):TP_CPU1_RSVD_113
  U2D1   CB5  RSVD<113>  SKX_EXT_B_BGA1   I9

TP_CPU1_RSVD_114   @BASEBOARD_FAB2_LIB.BASEBOARD_FAB2(SCH_1):TP_CPU1_RSVD_114
  U2D1   CB25  RSVD<114>  SKX_EXT_B_BGA1   I9

TP_CPU1_RSVD_117   @BASEBOARD_FAB2_LIB.BASEBOARD_FAB2(SCH_1):TP_CPU1_RSVD_117
  U2D1   CA24  RSVD<117>  SKX_EXT_B_BGA1   I9

TP_CPU1_RSVD_119   @BASEBOARD_FAB2_LIB.BASEBOARD_FAB2(SCH_1):TP_CPU1_RSVD_119
  U2D1   BY25  RSVD<119>  SKX_EXT_B_BGA1   I9

TP_CPU1_RSVD_121   @BASEBOARD_FAB2_LIB.BASEBOARD_FAB2(SCH_1):TP_CPU1_RSVD_121
  U2D1   BW22  RSVD<121>  SKX_EXT_B_BGA1   I9

TP_CPU1_RSVD_123   @BASEBOARD_FAB2_LIB.BASEBOARD_FAB2(SCH_1):TP_CPU1_RSVD_123
  U2D1   BW10  RSVD<123>  SKX_EXT_B_BGA1   I9

TP_CPU1_RSVD_124   @BASEBOARD_FAB2_LIB.BASEBOARD_FAB2(SCH_1):TP_CPU1_RSVD_124
  U2D1   BV23  RSVD<124>  SKX_EXT_B_BGA1   I9

TP_CPU1_RSVD_144   @BASEBOARD_FAB2_LIB.BASEBOARD_FAB2(SCH_1):TP_CPU1_RSVD_144
  U2D1   BG20  RSVD<144>  SKX_EXT_B_BGA1   I9

TP_CPU1_RSVD_145   @BASEBOARD_FAB2_LIB.BASEBOARD_FAB2(SCH_1):TP_CPU1_RSVD_145
  U2D1   BG18  RSVD<145>  SKX_EXT_B_BGA1   I9

TP_CPU1_RSVD_146   @BASEBOARD_FAB2_LIB.BASEBOARD_FAB2(SCH_1):TP_CPU1_RSVD_146
  U2D1   BF21  RSVD<146>  SKX_EXT_B_BGA1   I9

TP_CPU1_RSVD_147   @BASEBOARD_FAB2_LIB.BASEBOARD_FAB2(SCH_1):TP_CPU1_RSVD_147
  U2D1   BE22  RSVD<147>  SKX_EXT_B_BGA1   I9

TP_CPU1_RSVD_148   @BASEBOARD_FAB2_LIB.BASEBOARD_FAB2(SCH_1):TP_CPU1_RSVD_148
  U2D1   BE20  RSVD<148>  SKX_EXT_B_BGA1   I9

TP_CPU1_RSVD_149   @BASEBOARD_FAB2_LIB.BASEBOARD_FAB2(SCH_1):TP_CPU1_RSVD_149
  U2D1   BE18  RSVD<149>  SKX_EXT_B_BGA1   I9

TP_CPU1_RSVD_150   @BASEBOARD_FAB2_LIB.BASEBOARD_FAB2(SCH_1):TP_CPU1_RSVD_150
  U2D1   BD69  RSVD<150>  SKX_EXT_B_BGA1   I9

TP_CPU1_RSVD_151   @BASEBOARD_FAB2_LIB.BASEBOARD_FAB2(SCH_1):TP_CPU1_RSVD_151
  U2D1   BD67  RSVD<151>  SKX_EXT_B_BGA1   I9

TP_CPU1_RSVD_152   @BASEBOARD_FAB2_LIB.BASEBOARD_FAB2(SCH_1):TP_CPU1_RSVD_152
  U2D1   BD65  RSVD<152>  SKX_EXT_B_BGA1   I9

TP_CPU1_RSVD_154   @BASEBOARD_FAB2_LIB.BASEBOARD_FAB2(SCH_1):TP_CPU1_RSVD_154
  U2D1   BD19  RSVD<154>  SKX_EXT_B_BGA1   I9

TP_CPU1_RSVD_155   @BASEBOARD_FAB2_LIB.BASEBOARD_FAB2(SCH_1):TP_CPU1_RSVD_155
  U2D1   BD17  RSVD<155>  SKX_EXT_B_BGA1   I9

TP_CPU1_RSVD_156   @BASEBOARD_FAB2_LIB.BASEBOARD_FAB2(SCH_1):TP_CPU1_RSVD_156
  U2D1   BC68  RSVD<156>  SKX_EXT_B_BGA1   I9

TP_CPU1_RSVD_157   @BASEBOARD_FAB2_LIB.BASEBOARD_FAB2(SCH_1):TP_CPU1_RSVD_157
  U2D1   BC66  RSVD<157>  SKX_EXT_B_BGA1   I9

TP_CPU1_RSVD_158   @BASEBOARD_FAB2_LIB.BASEBOARD_FAB2(SCH_1):TP_CPU1_RSVD_158
  U2D1   BC64  RSVD<158>  SKX_EXT_B_BGA1   I9

TP_CPU1_RSVD_159   @BASEBOARD_FAB2_LIB.BASEBOARD_FAB2(SCH_1):TP_CPU1_RSVD_159
  U2D1   BC22  RSVD<159>  SKX_EXT_B_BGA1   I9

TP_CPU1_RSVD_160   @BASEBOARD_FAB2_LIB.BASEBOARD_FAB2(SCH_1):TP_CPU1_RSVD_160
  U2D1   BC20  RSVD<160>  SKX_EXT_B_BGA1   I9

TP_CPU1_RSVD_161   @BASEBOARD_FAB2_LIB.BASEBOARD_FAB2(SCH_1):TP_CPU1_RSVD_161
  U2D1   BC18  RSVD<161>  SKX_EXT_B_BGA1   I9

TP_CPU1_RSVD_162   @BASEBOARD_FAB2_LIB.BASEBOARD_FAB2(SCH_1):TP_CPU1_RSVD_162
  U2D1   BC14  RSVD<162>  SKX_EXT_B_BGA1   I9

TP_CPU1_RSVD_163   @BASEBOARD_FAB2_LIB.BASEBOARD_FAB2(SCH_1):TP_CPU1_RSVD_163
  U2D1   BB67  RSVD<163>  SKX_EXT_B_BGA1   I9

TP_CPU1_RSVD_164   @BASEBOARD_FAB2_LIB.BASEBOARD_FAB2(SCH_1):TP_CPU1_RSVD_164
  U2D1   BB65  RSVD<164>  SKX_EXT_B_BGA1   I9

TP_CPU1_RSVD_166   @BASEBOARD_FAB2_LIB.BASEBOARD_FAB2(SCH_1):TP_CPU1_RSVD_166
  U2D1   BB21  RSVD<166>  SKX_EXT_B_BGA1   I9

TP_CPU1_RSVD_167   @BASEBOARD_FAB2_LIB.BASEBOARD_FAB2(SCH_1):TP_CPU1_RSVD_167
  U2D1   BB17  RSVD<167>  SKX_EXT_B_BGA1   I9

TP_CPU1_RSVD_168   @BASEBOARD_FAB2_LIB.BASEBOARD_FAB2(SCH_1):TP_CPU1_RSVD_168
  U2D1   BB15  RSVD<168>  SKX_EXT_B_BGA1   I9

TP_CPU1_RSVD_169   @BASEBOARD_FAB2_LIB.BASEBOARD_FAB2(SCH_1):TP_CPU1_RSVD_169
  U2D1   BB13  RSVD<169>  SKX_EXT_B_BGA1   I9

TP_CPU1_RSVD_170   @BASEBOARD_FAB2_LIB.BASEBOARD_FAB2(SCH_1):TP_CPU1_RSVD_170
  U2D1   BA82  RSVD<170>  SKX_EXT_B_BGA1   I9

TP_CPU1_RSVD_171   @BASEBOARD_FAB2_LIB.BASEBOARD_FAB2(SCH_1):TP_CPU1_RSVD_171
  U2D1   BA78  RSVD<171>  SKX_EXT_B_BGA1   I9

TP_CPU1_RSVD_172   @BASEBOARD_FAB2_LIB.BASEBOARD_FAB2(SCH_1):TP_CPU1_RSVD_172
  U2D1   BA76  RSVD<172>  SKX_EXT_B_BGA1  I23

TP_CPU1_RSVD_173   @BASEBOARD_FAB2_LIB.BASEBOARD_FAB2(SCH_1):TP_CPU1_RSVD_173
  U2D1   BA66  RSVD<173>  SKX_EXT_B_BGA1  I23

TP_CPU1_RSVD_174   @BASEBOARD_FAB2_LIB.BASEBOARD_FAB2(SCH_1):TP_CPU1_RSVD_174
  U2D1   BA64  RSVD<174>  SKX_EXT_B_BGA1  I23

TP_CPU1_RSVD_175   @BASEBOARD_FAB2_LIB.BASEBOARD_FAB2(SCH_1):TP_CPU1_RSVD_175
  U2D1   BA22  RSVD<175>  SKX_EXT_B_BGA1  I23

TP_CPU1_RSVD_176   @BASEBOARD_FAB2_LIB.BASEBOARD_FAB2(SCH_1):TP_CPU1_RSVD_176
  U2D1   BA18  RSVD<176>  SKX_EXT_B_BGA1  I23

TP_CPU1_RSVD_177   @BASEBOARD_FAB2_LIB.BASEBOARD_FAB2(SCH_1):TP_CPU1_RSVD_177
  U2D1   BA16  RSVD<177>  SKX_EXT_B_BGA1  I23

TP_CPU1_RSVD_178   @BASEBOARD_FAB2_LIB.BASEBOARD_FAB2(SCH_1):TP_CPU1_RSVD_178
  U2D1   BA14  RSVD<178>  SKX_EXT_B_BGA1  I23

TP_CPU1_RSVD_179   @BASEBOARD_FAB2_LIB.BASEBOARD_FAB2(SCH_1):TP_CPU1_RSVD_179
  U2D1   AY77  RSVD<179>  SKX_EXT_B_BGA1  I23

TP_CPU1_RSVD_180   @BASEBOARD_FAB2_LIB.BASEBOARD_FAB2(SCH_1):TP_CPU1_RSVD_180
  U2D1   AY75  RSVD<180>  SKX_EXT_B_BGA1  I23

TP_CPU1_RSVD_181   @BASEBOARD_FAB2_LIB.BASEBOARD_FAB2(SCH_1):TP_CPU1_RSVD_181
  U2D1   AY67  RSVD<181>  SKX_EXT_B_BGA1  I23

TP_CPU1_RSVD_182   @BASEBOARD_FAB2_LIB.BASEBOARD_FAB2(SCH_1):TP_CPU1_RSVD_182
  U2D1   AY65  RSVD<182>  SKX_EXT_B_BGA1  I23

TP_CPU1_RSVD_183   @BASEBOARD_FAB2_LIB.BASEBOARD_FAB2(SCH_1):TP_CPU1_RSVD_183
  U2D1   AW76  RSVD<183>  SKX_EXT_B_BGA1  I23

TP_CPU1_RSVD_184   @BASEBOARD_FAB2_LIB.BASEBOARD_FAB2(SCH_1):TP_CPU1_RSVD_184
  U2D1   AW64  RSVD<184>  SKX_EXT_B_BGA1  I23

TP_CPU1_RSVD_186   @BASEBOARD_FAB2_LIB.BASEBOARD_FAB2(SCH_1):TP_CPU1_RSVD_186
  U2D1   AV77  RSVD<186>  SKX_EXT_B_BGA1  I23

TP_CPU1_RSVD_189   @BASEBOARD_FAB2_LIB.BASEBOARD_FAB2(SCH_1):TP_CPU1_RSVD_189
  U2D1   AT13  RSVD<189>  SKX_EXT_B_BGA1  I23

TP_CPU1_RSVD_190   @BASEBOARD_FAB2_LIB.BASEBOARD_FAB2(SCH_1):TP_CPU1_RSVD_190
  U2D1   AR62  RSVD<190>  SKX_EXT_B_BGA1  I23

TP_CPU1_RSVD_194   @BASEBOARD_FAB2_LIB.BASEBOARD_FAB2(SCH_1):TP_CPU1_RSVD_194
  U2D1   AP61  RSVD<194>  SKX_EXT_B_BGA1  I169

TP_CPU1_RSVD_198   @BASEBOARD_FAB2_LIB.BASEBOARD_FAB2(SCH_1):TP_CPU1_RSVD_198
  U2D1   AN62  RSVD<198>  SKX_EXT_B_BGA1  I169

TP_CPU1_RSVD_199   @BASEBOARD_FAB2_LIB.BASEBOARD_FAB2(SCH_1):TP_CPU1_RSVD_199
  U2D1   AN60  RSVD<199>  SKX_EXT_B_BGA1  I169

TP_CPU1_RSVD_204   @BASEBOARD_FAB2_LIB.BASEBOARD_FAB2(SCH_1):TP_CPU1_RSVD_204
  U2D1   AM61  RSVD<204>  SKX_EXT_B_BGA1  I169

TP_CPU1_RSVD_205   @BASEBOARD_FAB2_LIB.BASEBOARD_FAB2(SCH_1):TP_CPU1_RSVD_205
  U2D1   AM59  RSVD<205>  SKX_EXT_B_BGA1  I169

TP_CPU1_RSVD_208   @BASEBOARD_FAB2_LIB.BASEBOARD_FAB2(SCH_1):TP_CPU1_RSVD_208
  U2D1   AM23  RSVD<208>  SKX_EXT_B_BGA1  I169

TP_CPU1_RSVD_210   @BASEBOARD_FAB2_LIB.BASEBOARD_FAB2(SCH_1):TP_CPU1_RSVD_210
  U2D1   AL62  RSVD<210>  SKX_EXT_B_BGA1  I169

TP_CPU1_RSVD_211   @BASEBOARD_FAB2_LIB.BASEBOARD_FAB2(SCH_1):TP_CPU1_RSVD_211
  U2D1   AL60  RSVD<211>  SKX_EXT_B_BGA1  I169

TP_CPU1_RSVD_212   @BASEBOARD_FAB2_LIB.BASEBOARD_FAB2(SCH_1):TP_CPU1_RSVD_212
  U2D1   AL58  RSVD<212>  SKX_EXT_B_BGA1  I169

TP_CPU1_RSVD_214   @BASEBOARD_FAB2_LIB.BASEBOARD_FAB2(SCH_1):TP_CPU1_RSVD_214
  U2D1   AL22  RSVD<214>  SKX_EXT_B_BGA1  I169

TP_CPU1_RSVD_216   @BASEBOARD_FAB2_LIB.BASEBOARD_FAB2(SCH_1):TP_CPU1_RSVD_216
  U2D1   AK69  RSVD<216>  SKX_EXT_B_BGA1  I169

TP_CPU1_RSVD_217   @BASEBOARD_FAB2_LIB.BASEBOARD_FAB2(SCH_1):TP_CPU1_RSVD_217
  U2D1   AK61  RSVD<217>  SKX_EXT_B_BGA1  I169

TP_CPU1_RSVD_218   @BASEBOARD_FAB2_LIB.BASEBOARD_FAB2(SCH_1):TP_CPU1_RSVD_218
  U2D1   AK59  RSVD<218>  SKX_EXT_B_BGA1  I169

TP_CPU1_RSVD_219   @BASEBOARD_FAB2_LIB.BASEBOARD_FAB2(SCH_1):TP_CPU1_RSVD_219
  U2D1   AK57  RSVD<219>  SKX_EXT_B_BGA1  I169

TP_CPU1_RSVD_222   @BASEBOARD_FAB2_LIB.BASEBOARD_FAB2(SCH_1):TP_CPU1_RSVD_222
  U2D1   AJ70  RSVD<222>  SKX_EXT_B_BGA1  I169

TP_CPU1_RSVD_223   @BASEBOARD_FAB2_LIB.BASEBOARD_FAB2(SCH_1):TP_CPU1_RSVD_223
  U2D1   AJ62  RSVD<223>  SKX_EXT_B_BGA1  I169

TP_CPU1_RSVD_224   @BASEBOARD_FAB2_LIB.BASEBOARD_FAB2(SCH_1):TP_CPU1_RSVD_224
  U2D1   AJ60  RSVD<224>  SKX_EXT_B_BGA1  I169

TP_CPU1_RSVD_225   @BASEBOARD_FAB2_LIB.BASEBOARD_FAB2(SCH_1):TP_CPU1_RSVD_225
  U2D1   AJ58  RSVD<225>  SKX_EXT_B_BGA1  I169

TP_CPU1_RSVD_226   @BASEBOARD_FAB2_LIB.BASEBOARD_FAB2(SCH_1):TP_CPU1_RSVD_226
  U2D1   AJ56  RSVD<226>  SKX_EXT_B_BGA1  I169

TP_CPU1_RSVD_227   @BASEBOARD_FAB2_LIB.BASEBOARD_FAB2(SCH_1):TP_CPU1_RSVD_227
  U2D1   AJ20  RSVD<227>  SKX_EXT_B_BGA1  I169

TP_CPU1_RSVD_228   @BASEBOARD_FAB2_LIB.BASEBOARD_FAB2(SCH_1):TP_CPU1_RSVD_228
  U2D1   AH73  RSVD<228>  SKX_EXT_B_BGA1  I169

TP_CPU1_RSVD_229   @BASEBOARD_FAB2_LIB.BASEBOARD_FAB2(SCH_1):TP_CPU1_RSVD_229
  U2D1   AH71  RSVD<229>  SKX_EXT_B_BGA1  I169

TP_CPU1_RSVD_230   @BASEBOARD_FAB2_LIB.BASEBOARD_FAB2(SCH_1):TP_CPU1_RSVD_230
  U2D1   AH57  RSVD<230>  SKX_EXT_B_BGA1  I169

TP_CPU1_RSVD_231   @BASEBOARD_FAB2_LIB.BASEBOARD_FAB2(SCH_1):TP_CPU1_RSVD_231
  U2D1   AH55  RSVD<231>  SKX_EXT_B_BGA1  I169

TP_CPU1_RSVD_232   @BASEBOARD_FAB2_LIB.BASEBOARD_FAB2(SCH_1):TP_CPU1_RSVD_232
  U2D1   AH19  RSVD<232>  SKX_EXT_B_BGA1  I169

TP_CPU1_RSVD_233   @BASEBOARD_FAB2_LIB.BASEBOARD_FAB2(SCH_1):TP_CPU1_RSVD_233
  U2D1   AH15  RSVD<233>  SKX_EXT_B_BGA1  I169

TP_CPU1_RSVD_234   @BASEBOARD_FAB2_LIB.BASEBOARD_FAB2(SCH_1):TP_CPU1_RSVD_234
  U2D1   AG72  RSVD<234>  SKX_EXT_B_BGA1  I169

TP_CPU1_RSVD_235   @BASEBOARD_FAB2_LIB.BASEBOARD_FAB2(SCH_1):TP_CPU1_RSVD_235
  U2D1   AG56  RSVD<235>  SKX_EXT_B_BGA1  I169

TP_CPU1_RSVD_236   @BASEBOARD_FAB2_LIB.BASEBOARD_FAB2(SCH_1):TP_CPU1_RSVD_236
  U2D1   AG54  RSVD<236>  SKX_EXT_B_BGA1  I169

TP_CPU1_RSVD_237   @BASEBOARD_FAB2_LIB.BASEBOARD_FAB2(SCH_1):TP_CPU1_RSVD_237
  U2D1   AG52  RSVD<237>  SKX_EXT_B_BGA1  I169

TP_CPU1_RSVD_238   @BASEBOARD_FAB2_LIB.BASEBOARD_FAB2(SCH_1):TP_CPU1_RSVD_238
  U2D1   AG50  RSVD<238>  SKX_EXT_B_BGA1  I169

TP_CPU1_RSVD_239   @BASEBOARD_FAB2_LIB.BASEBOARD_FAB2(SCH_1):TP_CPU1_RSVD_239
  U2D1   AG48  RSVD<239>  SKX_EXT_B_BGA1  I169

TP_CPU1_RSVD_240   @BASEBOARD_FAB2_LIB.BASEBOARD_FAB2(SCH_1):TP_CPU1_RSVD_240
  U2D1   AG20  RSVD<240>  SKX_EXT_B_BGA1  I169

TP_CPU1_RSVD_241   @BASEBOARD_FAB2_LIB.BASEBOARD_FAB2(SCH_1):TP_CPU1_RSVD_241
  U2D1   AF71  RSVD<241>  SKX_EXT_B_BGA1  I169

TP_CPU1_RSVD_242   @BASEBOARD_FAB2_LIB.BASEBOARD_FAB2(SCH_1):TP_CPU1_RSVD_242
  U2D1   AF53  RSVD<242>  SKX_EXT_B_BGA1  I169

TP_CPU1_RSVD_243   @BASEBOARD_FAB2_LIB.BASEBOARD_FAB2(SCH_1):TP_CPU1_RSVD_243
  U2D1   AF51  RSVD<243>  SKX_EXT_B_BGA1  I169

TP_CPU1_RSVD_244   @BASEBOARD_FAB2_LIB.BASEBOARD_FAB2(SCH_1):TP_CPU1_RSVD_244
  U2D1   AF49  RSVD<244>  SKX_EXT_B_BGA1  I169

TP_CPU1_RSVD_245   @BASEBOARD_FAB2_LIB.BASEBOARD_FAB2(SCH_1):TP_CPU1_RSVD_245
  U2D1   AF47  RSVD<245>  SKX_EXT_B_BGA1  I169

TP_CPU1_RSVD_246   @BASEBOARD_FAB2_LIB.BASEBOARD_FAB2(SCH_1):TP_CPU1_RSVD_246
  U2D1   AF19  RSVD<246>  SKX_EXT_B_BGA1  I169

TP_CPU1_RSVD_247   @BASEBOARD_FAB2_LIB.BASEBOARD_FAB2(SCH_1):TP_CPU1_RSVD_247
  U2D1   AE72  RSVD<247>  SKX_EXT_B_BGA1  I169

TP_CPU1_RSVD_248   @BASEBOARD_FAB2_LIB.BASEBOARD_FAB2(SCH_1):TP_CPU1_RSVD_248
  U2D1   AE52  RSVD<248>  SKX_EXT_B_BGA1  I169

TP_CPU1_RSVD_249   @BASEBOARD_FAB2_LIB.BASEBOARD_FAB2(SCH_1):TP_CPU1_RSVD_249
  U2D1   AE50  RSVD<249>  SKX_EXT_B_BGA1  I169

TP_CPU1_RSVD_250   @BASEBOARD_FAB2_LIB.BASEBOARD_FAB2(SCH_1):TP_CPU1_RSVD_250
  U2D1   AE48  RSVD<250>  SKX_EXT_B_BGA1  I169

TP_CPU1_RSVD_251   @BASEBOARD_FAB2_LIB.BASEBOARD_FAB2(SCH_1):TP_CPU1_RSVD_251
  U2D1   AE46  RSVD<251>  SKX_EXT_B_BGA1  I169

TP_CPU1_RSVD_252   @BASEBOARD_FAB2_LIB.BASEBOARD_FAB2(SCH_1):TP_CPU1_RSVD_252
  U2D1   AD51  RSVD<252>  SKX_EXT_B_BGA1  I169

TP_CPU1_RSVD_253   @BASEBOARD_FAB2_LIB.BASEBOARD_FAB2(SCH_1):TP_CPU1_RSVD_253
  U2D1   AD49  RSVD<253>  SKX_EXT_B_BGA1  I169

TP_CPU1_RSVD_254   @BASEBOARD_FAB2_LIB.BASEBOARD_FAB2(SCH_1):TP_CPU1_RSVD_254
  U2D1   AD47  RSVD<254>  SKX_EXT_B_BGA1  I169

TP_CPU1_RSVD_255   @BASEBOARD_FAB2_LIB.BASEBOARD_FAB2(SCH_1):TP_CPU1_RSVD_255
  U2D1   AY83  RSVD<255>  SKX_EXT_B_BGA1   I9

TP_CPU1_RSVD_256   @BASEBOARD_FAB2_LIB.BASEBOARD_FAB2(SCH_1):TP_CPU1_RSVD_256
  U2D1   Y65  RSVD<256>  SKX_EXT_B_BGA1  I169

TP_CPU1_RSVD_258   @BASEBOARD_FAB2_LIB.BASEBOARD_FAB2(SCH_1):TP_CPU1_RSVD_258
  U2D1   W66  RSVD<258>  SKX_EXT_B_BGA1  I169

TP_CPU1_RSVD_259   @BASEBOARD_FAB2_LIB.BASEBOARD_FAB2(SCH_1):TP_CPU1_RSVD_259
  U2D1   V67  RSVD<259>  SKX_EXT_B_BGA1  I169

TP_CPU1_RSVD_260   @BASEBOARD_FAB2_LIB.BASEBOARD_FAB2(SCH_1):TP_CPU1_RSVD_260
  U2D1   V65  RSVD<260>  SKX_EXT_B_BGA1  I169

TP_CPU1_RSVD_261   @BASEBOARD_FAB2_LIB.BASEBOARD_FAB2(SCH_1):TP_CPU1_RSVD_261
  U2D1   U66  RSVD<261>  SKX_EXT_B_BGA1  I169

TP_CPU1_RSVD_262   @BASEBOARD_FAB2_LIB.BASEBOARD_FAB2(SCH_1):TP_CPU1_RSVD_262
  U2D1   T67  RSVD<262>  SKX_EXT_B_BGA1  I169

TP_CPU1_RSVD_263   @BASEBOARD_FAB2_LIB.BASEBOARD_FAB2(SCH_1):TP_CPU1_RSVD_263
  U2D1   R66  RSVD<263>  SKX_EXT_B_BGA1  I169

TP_CPU1_RSVD_264   @BASEBOARD_FAB2_LIB.BASEBOARD_FAB2(SCH_1):TP_CPU1_RSVD_264
  U2D1   R62  RSVD<264>  SKX_EXT_B_BGA1  I169

TP_CPU1_RSVD_265   @BASEBOARD_FAB2_LIB.BASEBOARD_FAB2(SCH_1):TP_CPU1_RSVD_265
  U2D1   P65  RSVD<265>  SKX_EXT_B_BGA1  I169

TP_CPU1_RSVD_266   @BASEBOARD_FAB2_LIB.BASEBOARD_FAB2(SCH_1):TP_CPU1_RSVD_266
  U2D1   M63  RSVD<266>  SKX_EXT_B_BGA1  I169

TP_CPU1_RSVD_267   @BASEBOARD_FAB2_LIB.BASEBOARD_FAB2(SCH_1):TP_CPU1_RSVD_267
  U2D1   K61  RSVD<267>  SKX_EXT_B_BGA1  I169

TP_CPU1_RSVD_268   @BASEBOARD_FAB2_LIB.BASEBOARD_FAB2(SCH_1):TP_CPU1_RSVD_268
  U2D1   J62  RSVD<268>  SKX_EXT_B_BGA1  I169

TP_CPU1_RSVD_269   @BASEBOARD_FAB2_LIB.BASEBOARD_FAB2(SCH_1):TP_CPU1_RSVD_269
  U2D1   J46  RSVD<269>  SKX_EXT_B_BGA1  I169

TP_CPU1_RSVD_270   @BASEBOARD_FAB2_LIB.BASEBOARD_FAB2(SCH_1):TP_CPU1_RSVD_270
  U2D1   H85  RSVD<270>  SKX_EXT_B_BGA1  I169

TP_CPU1_RSVD_271   @BASEBOARD_FAB2_LIB.BASEBOARD_FAB2(SCH_1):TP_CPU1_RSVD_271
  U2D1   H83  RSVD<271>  SKX_EXT_B_BGA1  I169

TP_CPU1_RSVD_272   @BASEBOARD_FAB2_LIB.BASEBOARD_FAB2(SCH_1):TP_CPU1_RSVD_272
  U2D1    H1  RSVD<272>  SKX_EXT_B_BGA1  I169

TP_CPU1_RSVD_273   @BASEBOARD_FAB2_LIB.BASEBOARD_FAB2(SCH_1):TP_CPU1_RSVD_273
  U2D1   G84  RSVD<273>  SKX_EXT_B_BGA1  I169

TP_CPU1_RSVD_274   @BASEBOARD_FAB2_LIB.BASEBOARD_FAB2(SCH_1):TP_CPU1_RSVD_274
  U2D1   G64  RSVD<274>  SKX_EXT_B_BGA1  I169

TP_CPU1_RSVD_275   @BASEBOARD_FAB2_LIB.BASEBOARD_FAB2(SCH_1):TP_CPU1_RSVD_275
  U2D1    G2  RSVD<275>  SKX_EXT_B_BGA1  I169

TP_CPU1_RSVD_276   @BASEBOARD_FAB2_LIB.BASEBOARD_FAB2(SCH_1):TP_CPU1_RSVD_276
  U2D1   F83  RSVD<276>  SKX_EXT_B_BGA1  I169

TP_CPU1_RSVD_277   @BASEBOARD_FAB2_LIB.BASEBOARD_FAB2(SCH_1):TP_CPU1_RSVD_277
  U2D1   F65  RSVD<277>  SKX_EXT_B_BGA1  I169

TP_CPU1_RSVD_278   @BASEBOARD_FAB2_LIB.BASEBOARD_FAB2(SCH_1):TP_CPU1_RSVD_278
  U2D1   F23  RSVD<278>  SKX_EXT_B_BGA1  I169

TP_CPU1_RSVD_279   @BASEBOARD_FAB2_LIB.BASEBOARD_FAB2(SCH_1):TP_CPU1_RSVD_279
  U2D1    F3  RSVD<279>  SKX_EXT_B_BGA1  I169

TP_CPU1_RSVD_280   @BASEBOARD_FAB2_LIB.BASEBOARD_FAB2(SCH_1):TP_CPU1_RSVD_280
  U2D1   E84  RSVD<280>  SKX_EXT_B_BGA1  I169

TP_CPU1_RSVD_281   @BASEBOARD_FAB2_LIB.BASEBOARD_FAB2(SCH_1):TP_CPU1_RSVD_281
  U2D1   E24  RSVD<281>  SKX_EXT_B_BGA1  I169

TP_CPU1_RSVD_282   @BASEBOARD_FAB2_LIB.BASEBOARD_FAB2(SCH_1):TP_CPU1_RSVD_282
  U2D1    E4  RSVD<282>  SKX_EXT_B_BGA1  I169

TP_CPU1_RSVD_283   @BASEBOARD_FAB2_LIB.BASEBOARD_FAB2(SCH_1):TP_CPU1_RSVD_283
  U2D1    E2  RSVD<283>  SKX_EXT_B_BGA1  I169

TP_CPU1_RSVD_284   @BASEBOARD_FAB2_LIB.BASEBOARD_FAB2(SCH_1):TP_CPU1_RSVD_284
  U2D1   D83  RSVD<284>  SKX_EXT_B_BGA1  I169

TP_CPU1_RSVD_285   @BASEBOARD_FAB2_LIB.BASEBOARD_FAB2(SCH_1):TP_CPU1_RSVD_285
  U2D1   D65  RSVD<285>  SKX_EXT_B_BGA1  I169

TP_CPU1_RSVD_286   @BASEBOARD_FAB2_LIB.BASEBOARD_FAB2(SCH_1):TP_CPU1_RSVD_286
  U2D1   D17  RSVD<286>  SKX_EXT_B_BGA1  I169

TP_CPU1_RSVD_287   @BASEBOARD_FAB2_LIB.BASEBOARD_FAB2(SCH_1):TP_CPU1_RSVD_287
  U2D1    D5  RSVD<287>  SKX_EXT_B_BGA1  I169

TP_CPU1_RSVD_288   @BASEBOARD_FAB2_LIB.BASEBOARD_FAB2(SCH_1):TP_CPU1_RSVD_288
  U2D1   C82  RSVD<288>  SKX_EXT_B_BGA1  I169

TP_CPU1_RSVD_289   @BASEBOARD_FAB2_LIB.BASEBOARD_FAB2(SCH_1):TP_CPU1_RSVD_289
  U2D1   C24  RSVD<289>  SKX_EXT_B_BGA1  I169

TP_CPU1_RSVD_290   @BASEBOARD_FAB2_LIB.BASEBOARD_FAB2(SCH_1):TP_CPU1_RSVD_290
  U2D1   C18  RSVD<290>  SKX_EXT_B_BGA1  I169

TP_CPU1_RSVD_291   @BASEBOARD_FAB2_LIB.BASEBOARD_FAB2(SCH_1):TP_CPU1_RSVD_291
  U2D1    C6  RSVD<291>  SKX_EXT_B_BGA1  I169

TP_CPU1_RSVD_292   @BASEBOARD_FAB2_LIB.BASEBOARD_FAB2(SCH_1):TP_CPU1_RSVD_292
  U2D1   B81  RSVD<292>  SKX_EXT_B_BGA1  I169

TP_CPU1_RSVD_293   @BASEBOARD_FAB2_LIB.BASEBOARD_FAB2(SCH_1):TP_CPU1_RSVD_293
  U2D1   B77  RSVD<293>  SKX_EXT_B_BGA1  I169

TP_CPU1_RSVD_298   @BASEBOARD_FAB2_LIB.BASEBOARD_FAB2(SCH_1):TP_CPU1_RSVD_298
  U2D1    B7  RSVD<298>  SKX_EXT_B_BGA1  I169

TP_CPU1_RSVD_299   @BASEBOARD_FAB2_LIB.BASEBOARD_FAB2(SCH_1):TP_CPU1_RSVD_299
  U2D1    B3  RSVD<299>  SKX_EXT_B_BGA1  I169

TP_CPU1_RSVD_300   @BASEBOARD_FAB2_LIB.BASEBOARD_FAB2(SCH_1):TP_CPU1_RSVD_300
  U2D1   A24  RSVD<300>  SKX_EXT_B_BGA1  I169

TP_CPU1_RSVD_303   @BASEBOARD_FAB2_LIB.BASEBOARD_FAB2(SCH_1):TP_CPU1_RSVD_303
  U2D1    A6  RSVD<303>  SKX_EXT_B_BGA1  I169

TP_CPU1_RSVD_304   @BASEBOARD_FAB2_LIB.BASEBOARD_FAB2(SCH_1):TP_CPU1_RSVD_304
  U2D1    A4  RSVD<304>  SKX_EXT_B_BGA1  I169

TP_CPU1_RSVD_TEST_3   @BASEBOARD_FAB2_LIB.BASEBOARD_FAB2(SCH_1):TP_CPU1_RSVD_TEST_3
  U2D1   AM13  TEST_3  SKX_EXT_B_BGA1  I169

TP_CPU1_RSVD_TEST_4   @BASEBOARD_FAB2_LIB.BASEBOARD_FAB2(SCH_1):TP_CPU1_RSVD_TEST_4
  U2D1   AN12  TEST_4  SKX_EXT_B_BGA1  I169

TP_CPU1_RSVD_TEST_5   @BASEBOARD_FAB2_LIB.BASEBOARD_FAB2(SCH_1):TP_CPU1_RSVD_TEST_5
  U2D1   AN14  TEST_5  SKX_EXT_B_BGA1  I169

TP_CPU1_RSVD_TEST_11   @BASEBOARD_FAB2_LIB.BASEBOARD_FAB2(SCH_1):TP_CPU1_RSVD_TEST_11
  U2D1   AY13  TEST_11  SKX_EXT_B_BGA1  I169

TP_CPU1_SOCKET_ID_2   @BASEBOARD_FAB2_LIB.BASEBOARD_FAB2(SCH_1):TP_CPU1_SOCKET_ID_2
  U2D1   AU20  SOCKET_ID<2>  SKX_EXT_B_BGA1  I172

TP_CPU1_TEST_6   @BASEBOARD_FAB2_LIB.BASEBOARD_FAB2(SCH_1):TP_CPU1_TEST_6
  U2D1   AR16  TEST_6  SKX_EXT_B_BGA1  I10

TP_CPU1_TEST_7   @BASEBOARD_FAB2_LIB.BASEBOARD_FAB2(SCH_1):TP_CPU1_TEST_7
  U2D1   AU18  TEST_7  SKX_EXT_B_BGA1  I10

TP_CPU1_TEST_8   @BASEBOARD_FAB2_LIB.BASEBOARD_FAB2(SCH_1):TP_CPU1_TEST_8
  U2D1   AW16  TEST_8  SKX_EXT_B_BGA1  I10

TP_CPU1_TEST_9   @BASEBOARD_FAB2_LIB.BASEBOARD_FAB2(SCH_1):TP_CPU1_TEST_9
  U2D1   AW20  TEST_9  SKX_EXT_B_BGA1  I10

TP_CPU1_TEST_10   @BASEBOARD_FAB2_LIB.BASEBOARD_FAB2(SCH_1):TP_CPU1_TEST_10
  U2D1   AW22  TEST_10  SKX_EXT_B_BGA1  I10

TP_CPU1_UPI2_RSVD_CA12   @BASEBOARD_FAB2_LIB.BASEBOARD_FAB2(SCH_1):TP_CPU1_UPI2_RSVD_CA12
  U2D1   DP21  UPI2_TX_DP<0>  SKX_EXT_B_BGA1   I1

TP_CPU1_UPI2_RSVD_CB11   @BASEBOARD_FAB2_LIB.BASEBOARD_FAB2(SCH_1):TP_CPU1_UPI2_RSVD_CB11
  U2D1   DN20  UPI2_TX_DP<1>  SKX_EXT_B_BGA1   I1

TP_CPU1_UPI2_RSVD_CC10   @BASEBOARD_FAB2_LIB.BASEBOARD_FAB2(SCH_1):TP_CPU1_UPI2_RSVD_CC10
  U2D1   DM21  UPI2_TX_DN<1>  SKX_EXT_B_BGA1   I1

TP_CPU1_UPI2_RSVD_CC12   @BASEBOARD_FAB2_LIB.BASEBOARD_FAB2(SCH_1):TP_CPU1_UPI2_RSVD_CC12
  U2D1   DT21  UPI2_TX_DN<0>  SKX_EXT_B_BGA1   I1

TP_CPU1_UPI2_RSVD_CD11   @BASEBOARD_FAB2_LIB.BASEBOARD_FAB2(SCH_1):TP_CPU1_UPI2_RSVD_CD11
  U2D1   DK19  UPI2_TX_DP<2>  SKX_EXT_B_BGA1   I1

TP_CPU1_UPI2_RSVD_CE12   @BASEBOARD_FAB2_LIB.BASEBOARD_FAB2(SCH_1):TP_CPU1_UPI2_RSVD_CE12
  U2D1   DL20  UPI2_TX_DN<2>  SKX_EXT_B_BGA1   I1

TP_CPU1_UPI2_RSVD_CF11   @BASEBOARD_FAB2_LIB.BASEBOARD_FAB2(SCH_1):TP_CPU1_UPI2_RSVD_CF11
  U2D1   DJ20  UPI2_TX_DP<3>  SKX_EXT_B_BGA1   I1

TP_CPU1_UPI2_RSVD_CF13   @BASEBOARD_FAB2_LIB.BASEBOARD_FAB2(SCH_1):TP_CPU1_UPI2_RSVD_CF13
  U2D1   DH19  UPI2_TX_DN<4>  SKX_EXT_B_BGA1   I1

TP_CPU1_UPI2_RSVD_CG12   @BASEBOARD_FAB2_LIB.BASEBOARD_FAB2(SCH_1):TP_CPU1_UPI2_RSVD_CG12
  U2D1   DJ18  UPI2_TX_DP<4>  SKX_EXT_B_BGA1   I1

TP_CPU1_UPI2_RSVD_CH11   @BASEBOARD_FAB2_LIB.BASEBOARD_FAB2(SCH_1):TP_CPU1_UPI2_RSVD_CH11
  U2D1   DG20  UPI2_TX_DN<3>  SKX_EXT_B_BGA1   I1

TP_CPU1_UPI2_RSVD_CH13   @BASEBOARD_FAB2_LIB.BASEBOARD_FAB2(SCH_1):TP_CPU1_UPI2_RSVD_CH13
  U2D1   DH17  UPI2_TX_DP<5>  SKX_EXT_B_BGA1   I1

TP_CPU1_UPI2_RSVD_CJ14   @BASEBOARD_FAB2_LIB.BASEBOARD_FAB2(SCH_1):TP_CPU1_UPI2_RSVD_CJ14
  U2D1   DK17  UPI2_TX_DN<5>  SKX_EXT_B_BGA1   I1

TP_CPU1_UPI2_RSVD_CK13   @BASEBOARD_FAB2_LIB.BASEBOARD_FAB2(SCH_1):TP_CPU1_UPI2_RSVD_CK13
  U2D1   DF17  UPI2_TX_DP<6>  SKX_EXT_B_BGA1   I1

TP_CPU1_UPI2_RSVD_CM13   @BASEBOARD_FAB2_LIB.BASEBOARD_FAB2(SCH_1):TP_CPU1_UPI2_RSVD_CM13
  U2D1   DG18  UPI2_TX_DN<6>  SKX_EXT_B_BGA1   I1

TP_CPU1_UPI2_RSVD_CR14   @BASEBOARD_FAB2_LIB.BASEBOARD_FAB2(SCH_1):TP_CPU1_UPI2_RSVD_CR14
  U2D1   DE16  UPI2_TX_DP<7>  SKX_EXT_B_BGA1   I1

TP_CPU1_UPI2_RSVD_CU14   @BASEBOARD_FAB2_LIB.BASEBOARD_FAB2(SCH_1):TP_CPU1_UPI2_RSVD_CU14
  U2D1   DD17  UPI2_TX_DN<7>  SKX_EXT_B_BGA1   I1

TP_CPU1_UPI2_RSVD_CV13   @BASEBOARD_FAB2_LIB.BASEBOARD_FAB2(SCH_1):TP_CPU1_UPI2_RSVD_CV13
  U2D1   DD15  UPI2_TX_DP<8>  SKX_EXT_B_BGA1   I1

TP_CPU1_UPI2_RSVD_CW14   @BASEBOARD_FAB2_LIB.BASEBOARD_FAB2(SCH_1):TP_CPU1_UPI2_RSVD_CW14
  U2D1   DF15  UPI2_TX_DN<8>  SKX_EXT_B_BGA1   I1

TP_CPU1_UPI2_RSVD_CW16   @BASEBOARD_FAB2_LIB.BASEBOARD_FAB2(SCH_1):TP_CPU1_UPI2_RSVD_CW16
  U2D1   DB15  UPI2_TX_DP<9>  SKX_EXT_B_BGA1   I1

TP_CPU1_UPI2_RSVD_DA16   @BASEBOARD_FAB2_LIB.BASEBOARD_FAB2(SCH_1):TP_CPU1_UPI2_RSVD_DA16
  U2D1   DC16  UPI2_TX_DN<9>  SKX_EXT_B_BGA1   I1

TP_CPU1_UPI2_RSVD_DB15   @BASEBOARD_FAB2_LIB.BASEBOARD_FAB2(SCH_1):TP_CPU1_UPI2_RSVD_DB15
  U2D1   CW16  UPI2_TX_DP<10>  SKX_EXT_B_BGA1   I1

TP_CPU1_UPI2_RSVD_DC16   @BASEBOARD_FAB2_LIB.BASEBOARD_FAB2(SCH_1):TP_CPU1_UPI2_RSVD_DC16
  U2D1   DA16  UPI2_TX_DN<10>  SKX_EXT_B_BGA1   I1

TP_CPU1_UPI2_RSVD_DD15   @BASEBOARD_FAB2_LIB.BASEBOARD_FAB2(SCH_1):TP_CPU1_UPI2_RSVD_DD15
  U2D1   CV13  UPI2_TX_DP<11>  SKX_EXT_B_BGA1   I1

TP_CPU1_UPI2_RSVD_DD17   @BASEBOARD_FAB2_LIB.BASEBOARD_FAB2(SCH_1):TP_CPU1_UPI2_RSVD_DD17
  U2D1   CU14  UPI2_TX_DN<12>  SKX_EXT_B_BGA1   I1

TP_CPU1_UPI2_RSVD_DE16   @BASEBOARD_FAB2_LIB.BASEBOARD_FAB2(SCH_1):TP_CPU1_UPI2_RSVD_DE16
  U2D1   CR14  UPI2_TX_DP<12>  SKX_EXT_B_BGA1   I1

TP_CPU1_UPI2_RSVD_DF15   @BASEBOARD_FAB2_LIB.BASEBOARD_FAB2(SCH_1):TP_CPU1_UPI2_RSVD_DF15
  U2D1   CW14  UPI2_TX_DN<11>  SKX_EXT_B_BGA1   I1

TP_CPU1_UPI2_RSVD_DF17   @BASEBOARD_FAB2_LIB.BASEBOARD_FAB2(SCH_1):TP_CPU1_UPI2_RSVD_DF17
  U2D1   CK13  UPI2_TX_DP<13>  SKX_EXT_B_BGA1   I1

TP_CPU1_UPI2_RSVD_DG18   @BASEBOARD_FAB2_LIB.BASEBOARD_FAB2(SCH_1):TP_CPU1_UPI2_RSVD_DG18
  U2D1   CM13  UPI2_TX_DN<13>  SKX_EXT_B_BGA1   I1

TP_CPU1_UPI2_RSVD_DG20   @BASEBOARD_FAB2_LIB.BASEBOARD_FAB2(SCH_1):TP_CPU1_UPI2_RSVD_DG20
  U2D1   CH11  UPI2_TX_DN<16>  SKX_EXT_B_BGA1   I1

TP_CPU1_UPI2_RSVD_DH17   @BASEBOARD_FAB2_LIB.BASEBOARD_FAB2(SCH_1):TP_CPU1_UPI2_RSVD_DH17
  U2D1   CH13  UPI2_TX_DP<14>  SKX_EXT_B_BGA1   I1

TP_CPU1_UPI2_RSVD_DH19   @BASEBOARD_FAB2_LIB.BASEBOARD_FAB2(SCH_1):TP_CPU1_UPI2_RSVD_DH19
  U2D1   CF13  UPI2_TX_DN<15>  SKX_EXT_B_BGA1   I1

TP_CPU1_UPI2_RSVD_DJ18   @BASEBOARD_FAB2_LIB.BASEBOARD_FAB2(SCH_1):TP_CPU1_UPI2_RSVD_DJ18
  U2D1   CG12  UPI2_TX_DP<15>  SKX_EXT_B_BGA1   I1

TP_CPU1_UPI2_RSVD_DJ20   @BASEBOARD_FAB2_LIB.BASEBOARD_FAB2(SCH_1):TP_CPU1_UPI2_RSVD_DJ20
  U2D1   CF11  UPI2_TX_DP<16>  SKX_EXT_B_BGA1   I1

TP_CPU1_UPI2_RSVD_DK17   @BASEBOARD_FAB2_LIB.BASEBOARD_FAB2(SCH_1):TP_CPU1_UPI2_RSVD_DK17
  U2D1   CJ14  UPI2_TX_DN<14>  SKX_EXT_B_BGA1   I1

TP_CPU1_UPI2_RSVD_DK19   @BASEBOARD_FAB2_LIB.BASEBOARD_FAB2(SCH_1):TP_CPU1_UPI2_RSVD_DK19
  U2D1   CD11  UPI2_TX_DP<17>  SKX_EXT_B_BGA1   I1

TP_CPU1_UPI2_RSVD_DL20   @BASEBOARD_FAB2_LIB.BASEBOARD_FAB2(SCH_1):TP_CPU1_UPI2_RSVD_DL20
  U2D1   CE12  UPI2_TX_DN<17>  SKX_EXT_B_BGA1   I1

TP_CPU1_UPI2_RSVD_DM21   @BASEBOARD_FAB2_LIB.BASEBOARD_FAB2(SCH_1):TP_CPU1_UPI2_RSVD_DM21
  U2D1   CC10  UPI2_TX_DN<18>  SKX_EXT_B_BGA1   I1

TP_CPU1_UPI2_RSVD_DN20   @BASEBOARD_FAB2_LIB.BASEBOARD_FAB2(SCH_1):TP_CPU1_UPI2_RSVD_DN20
  U2D1   CB11  UPI2_TX_DP<18>  SKX_EXT_B_BGA1   I1

TP_CPU1_UPI2_RSVD_DP21   @BASEBOARD_FAB2_LIB.BASEBOARD_FAB2(SCH_1):TP_CPU1_UPI2_RSVD_DP21
  U2D1   CA12  UPI2_TX_DP<19>  SKX_EXT_B_BGA1   I1

TP_CPU1_UPI2_RSVD_DT21   @BASEBOARD_FAB2_LIB.BASEBOARD_FAB2(SCH_1):TP_CPU1_UPI2_RSVD_DT21
  U2D1   CC12  UPI2_TX_DN<19>  SKX_EXT_B_BGA1   I1

TP_CPU_PCH_TRIGGER_IN   @BASEBOARD_FAB2_LIB.BASEBOARD_FAB2(SCH_1):TP_CPU_PCH_TRIGGER_IN
  U7C1    M7  TRIGGER_IN  LBG_CORE_QAT_EXT_D  I73

TP_CPU_PCH_TRIGGER_OUT   @BASEBOARD_FAB2_LIB.BASEBOARD_FAB2(SCH_1):TP_CPU_PCH_TRIGGER_OUT
  U7C1   R13  TRIGGER_OUT  LBG_CORE_QAT_EXT_D  I73

TP_DACB         @BASEBOARD_FAB2_LIB.BASEBOARD_FAB2(SCH_1):TP_DACB
  U9F4    R4   DACB  AST1250_BGA  I347

TP_DACG         @BASEBOARD_FAB2_LIB.BASEBOARD_FAB2(SCH_1):TP_DACG
  U9F4    R3   DACG  AST1250_BGA  I347

TP_DACR         @BASEBOARD_FAB2_LIB.BASEBOARD_FAB2(SCH_1):TP_DACR
  U9F4    R2   DACR  AST1250_BGA  I347

TP_DDCCLK_GPIOJ6   @BASEBOARD_FAB2_LIB.BASEBOARD_FAB2(SCH_1):TP_DDCCLK_GPIOJ6
  U9F4    T2  DDCCLK_GPIOJ6  AST1250_BGA  I347

TP_DDCDAT_GPIOJ7   @BASEBOARD_FAB2_LIB.BASEBOARD_FAB2(SCH_1):TP_DDCDAT_GPIOJ7
  U9F4    T1  DDCDAT_GPIOJ7  AST1250_BGA  I347

TP_EXT_MDIO_I2C_SEL   @BASEBOARD_FAB2_LIB.BASEBOARD_FAB2(SCH_1):TP_EXT_MDIO_I2C_SEL
  J8E4     3    IO3  SCONN64_H87568002_A_SMT  I27

TP_FAN_0        @BASEBOARD_FAB2_LIB.BASEBOARD_FAB2(SCH_1):TP_FAN_0
  J1F2     6    IO6  CONN6_C74770005   I1

TP_FAN_1        @BASEBOARD_FAB2_LIB.BASEBOARD_FAB2(SCH_1):TP_FAN_1
  J1B2     6    IO6  CONN6_C74770005  I32

TP_FET_Q56_3    @BASEBOARD_FAB2_LIB.BASEBOARD_FAB2(SCH_1):TP_FET_Q56_3
  Q1L4     3  DRAIN<0>  FET_N_DUAL_SMLF  I18

TP_FET_Q56_4    @BASEBOARD_FAB2_LIB.BASEBOARD_FAB2(SCH_1):TP_FET_Q56_4
  Q1L4     4  SOURCE<0>  FET_N_DUAL_SMLF  I18
  Q1L4     5  GATE<0>  FET_N_DUAL_SMLF  I18

TP_FM_CPU1_CD_HFI0_MODPRST_N   @BASEBOARD_FAB2_LIB.BASEBOARD_FAB2(SCH_1):TP_FM_CPU1_CD_HFI0_MODPRST_N
  U2D1   BR20  CD_HFI0_MODPRST_N  SKX_EXT_B_BGA1  I23

TP_FM_QAT_CBL_PRSNT0_R_N   @BASEBOARD_FAB2_LIB.BASEBOARD_FAB2(SCH_1):TP_FM_QAT_CBL_PRSNT0_R_N
  J8A1   1A1  SIDEBANDA_7  CONN72_G97614002_A_CP  I163

TP_FM_QAT_CBL_PRSNT1_N_R   @BASEBOARD_FAB2_LIB.BASEBOARD_FAB2(SCH_1):TP_FM_QAT_CBL_PRSNT1_N_R
  J8A1   2A1  SIDEBANDB_7  CONN72_G97614002_A_CP  I163

TP_FM_QAT_CBL_PRSNT2_N   @BASEBOARD_FAB2_LIB.BASEBOARD_FAB2(SCH_1):TP_FM_QAT_CBL_PRSNT2_N
  J8A2    A1  SIDEBAND7  CONN36_G97614001_CP  I26

TP_FM_WAKE_N    @BASEBOARD_FAB2_LIB.BASEBOARD_FAB2(SCH_1):TP_FM_WAKE_N
  J1C1    B4   IOB4  CONN76_H22707001_THMT1  I18

TP_GPIO0_DSRB_N   @BASEBOARD_FAB2_LIB.BASEBOARD_FAB2(SCH_1):TP_GPIO0_DSRB_N
  EU9F3   13  GPIO0_DSRB_N  PI7C9X1172_QFN   I1

TP_GPIO1_DTRB_N   @BASEBOARD_FAB2_LIB.BASEBOARD_FAB2(SCH_1):TP_GPIO1_DTRB_N
  EU9F3   23  GPIO1_DTRB_N  PI7C9X1172_QFN   I1

TP_GPIO2_CDB_N   @BASEBOARD_FAB2_LIB.BASEBOARD_FAB2(SCH_1):TP_GPIO2_CDB_N
  EU9F3   11  GPIO2_CDB_N  PI7C9X1172_QFN   I1

TP_GPIO3_RIB_N   @BASEBOARD_FAB2_LIB.BASEBOARD_FAB2(SCH_1):TP_GPIO3_RIB_N
  EU9F3   14  GPIO3_RIB_N  PI7C9X1172_QFN   I1

TP_GPIO4_DSRA_N   @BASEBOARD_FAB2_LIB.BASEBOARD_FAB2(SCH_1):TP_GPIO4_DSRA_N
  EU9F3   26  GPIO4_DSRA_N  PI7C9X1172_QFN   I1

TP_GPIO5_DTRA_N   @BASEBOARD_FAB2_LIB.BASEBOARD_FAB2(SCH_1):TP_GPIO5_DTRA_N
  EU9F3   22  GPIO5_DTRA_N  PI7C9X1172_QFN   I1

TP_GPIO6_CDA_N   @BASEBOARD_FAB2_LIB.BASEBOARD_FAB2(SCH_1):TP_GPIO6_CDA_N
  EU9F3   27  GPIO6_CDA_N  PI7C9X1172_QFN   I1

TP_GPIO7_RIA_N   @BASEBOARD_FAB2_LIB.BASEBOARD_FAB2(SCH_1):TP_GPIO7_RIA_N
  EU9F3   28  GPIO7_RIA_N  PI7C9X1172_QFN   I1

TP_GPIOE7_RXD3   @BASEBOARD_FAB2_LIB.BASEBOARD_FAB2(SCH_1):TP_GPIOE7_RXD3
  U9F4   B14  GPIOE7_RXD3  AST1250_BGA  I100

TP_GPIOM5_NRTS2_VPIB7   @BASEBOARD_FAB2_LIB.BASEBOARD_FAB2(SCH_1):TP_GPIOM5_NRTS2_VPIB7
  U9F4    Y2  GPIOM5_NRTS2_VPIB7  AST1250_BGA  I100

TP_GPIOR5_ROMA25_VPOR7   @BASEBOARD_FAB2_LIB.BASEBOARD_FAB2(SCH_1):TP_GPIOR5_ROMA25_VPOR7
  U9F4   W22  GPIOR5_ROMA25_VPOR7  AST1250_BGA   I1

TP_HFI_IO_CONN0_RSVD_17   @BASEBOARD_FAB2_LIB.BASEBOARD_FAB2(SCH_1):TP_HFI_IO_CONN0_RSVD_17
  J8B1    17   IO17  SCONN24_H46321001_SM   I1

TP_HSC_ALERT2_N   @BASEBOARD_FAB2_LIB.BASEBOARD_FAB2(SCH_1):TP_HSC_ALERT2_N
  EU1D2   14  GPO2_ALERT2_N  ADM1278_SM  I10

TP_HSC_MCLK     @BASEBOARD_FAB2_LIB.BASEBOARD_FAB2(SCH_1):TP_HSC_MCLK
  EU1D2   10   MCLK  ADM1278_SM  I10

TP_HSC_MDAT     @BASEBOARD_FAB2_LIB.BASEBOARD_FAB2(SCH_1):TP_HSC_MDAT
  EU1D2   11   MDAT  ADM1278_SM  I10

TP_HSC_SPISSN   @BASEBOARD_FAB2_LIB.BASEBOARD_FAB2(SCH_1):TP_HSC_SPISSN
  EU1D2    9  SPISS_N  ADM1278_SM  I10

TP_IE_DEBUG_MODE   @BASEBOARD_FAB2_LIB.BASEBOARD_FAB2(SCH_1):TP_IE_DEBUG_MODE
  J9G1     7    IO7  CONN12_C73564003  I128

TP_IOA5         @BASEBOARD_FAB2_LIB.BASEBOARD_FAB2(SCH_1):TP_IOA5
  J1C1    A5   IOA5  CONN76_H22707001_THMT1  I18

TP_IOE4         @BASEBOARD_FAB2_LIB.BASEBOARD_FAB2(SCH_1):TP_IOE4
  J1C1    E4   IOE4  CONN76_H22707001_THMT1  I18

TP_IOF4         @BASEBOARD_FAB2_LIB.BASEBOARD_FAB2(SCH_1):TP_IOF4
  J1C1    F4   IOF4  CONN76_H22707001_THMT1  I18

TP_IOG3         @BASEBOARD_FAB2_LIB.BASEBOARD_FAB2(SCH_1):TP_IOG3
  J1C1    G3   IOG3  CONN76_H22707001_THMT1  I18

TP_IOH3         @BASEBOARD_FAB2_LIB.BASEBOARD_FAB2(SCH_1):TP_IOH3
  J1C1    H3   IOH3  CONN76_H22707001_THMT1  I18

TP_IOH4         @BASEBOARD_FAB2_LIB.BASEBOARD_FAB2(SCH_1):TP_IOH4
  J1C1    H4   IOH4  CONN76_H22707001_THMT1  I18

TP_IOI4         @BASEBOARD_FAB2_LIB.BASEBOARD_FAB2(SCH_1):TP_IOI4
  J1C1    I4   IOI4  CONN76_H22707001_THMT1  I18

TP_IRQ_CPU1_CD_HFI0_N   @BASEBOARD_FAB2_LIB.BASEBOARD_FAB2(SCH_1):TP_IRQ_CPU1_CD_HFI0_N
  U2D1   BP19  CD_HFI0_INT_N  SKX_EXT_B_BGA1  I23

TP_JTAG_BMC_RTCK   @BASEBOARD_FAB2_LIB.BASEBOARD_FAB2(SCH_1):TP_JTAG_BMC_RTCK
  U9F4    G4   RTCK  AST1250_BGA  I347

TP_JTAG_MCP_IO8_RSVD   @BASEBOARD_FAB2_LIB.BASEBOARD_FAB2(SCH_1):TP_JTAG_MCP_IO8_RSVD
  J9B4     8    IO8  SCONN10_C12536004  I175

TP_JUMPER_BLOCK_1_1   @BASEBOARD_FAB2_LIB.BASEBOARD_FAB2(SCH_1):TP_JUMPER_BLOCK_1_1
  J8G2     1    IO1  CONN12_C73564003  I124

TP_JUMPER_BLOCK_1_2   @BASEBOARD_FAB2_LIB.BASEBOARD_FAB2(SCH_1):TP_JUMPER_BLOCK_1_2
  J8G2     2    IO2  CONN12_C73564003  I124

TP_JUMPER_BLOCK_1_7   @BASEBOARD_FAB2_LIB.BASEBOARD_FAB2(SCH_1):TP_JUMPER_BLOCK_ 1_7
  J8G2     7    IO7  CONN12_C73564003  I124

TP_JUMPER_BLOCK_1_8   @BASEBOARD_FAB2_LIB.BASEBOARD_FAB2(SCH_1):TP_JUMPER_BLOCK_1_8
  J8G2     8    IO8  CONN12_C73564003  I124

TP_JUMPER_BLOCK_2_8   @BASEBOARD_FAB2_LIB.BASEBOARD_FAB2(SCH_1):TP_JUMPER_BLOCK_2_8
  J9G1     8    IO8  CONN12_C73564003  I128

TP_JUMPER_BLOCK_2_10   @BASEBOARD_FAB2_LIB.BASEBOARD_FAB2(SCH_1):TP_JUMPER_BLOCK_2_10
  J9G1    10   IO10  CONN12_C73564003  I128

TP_JUMPER_BLOCK_2_12   @BASEBOARD_FAB2_LIB.BASEBOARD_FAB2(SCH_1):TP_JUMPER_BLOCK_2_12
  J9G1    12   IO12  CONN12_C73564003  I128

TP_K4B1G16_BMC_NC0   @BASEBOARD_FAB2_LIB.BASEBOARD_FAB2(SCH_1):TP_K4B1G16_BMC_NC0
  U9F5    J1  NC<0>  K4B1G16_BGA1   I1

TP_K4B1G16_BMC_NC1   @BASEBOARD_FAB2_LIB.BASEBOARD_FAB2(SCH_1):TP_K4B1G16_BMC_NC1
  U9F5    J9  NC<1>  K4B1G16_BGA1   I1

TP_K4B1G16_BMC_NC2   @BASEBOARD_FAB2_LIB.BASEBOARD_FAB2(SCH_1):TP_K4B1G16_BMC_NC2
  U9F5    L1  NC<2>  K4B1G16_BGA1   I1

TP_K4B1G16_BMC_NC3   @BASEBOARD_FAB2_LIB.BASEBOARD_FAB2(SCH_1):TP_K4B1G16_BMC_NC3
  U9F5    L9  NC<3>  K4B1G16_BGA1   I1

TP_K4B1G16_BMC_NC4   @BASEBOARD_FAB2_LIB.BASEBOARD_FAB2(SCH_1):TP_K4B1G16_BMC_NC4
  U9F5    M7  NC<4>  K4B1G16_BGA1   I1

TP_LED_CPU1_CD_HFI0_N   @BASEBOARD_FAB2_LIB.BASEBOARD_FAB2(SCH_1):TP_LED_CPU1_CD_HFI0_N
  U2D1   BK21  CD_HFI0_LED_N  SKX_EXT_B_BGA1  I23

TP_LED_M2_ACT_N   @BASEBOARD_FAB2_LIB.BASEBOARD_FAB2(SCH_1):TP_LED_M2_ACT_N
  J8F1    10  DAS_DSS_N  SCONN75K_H17033002_SMT1  I53

TP_M2_32M_SUSCLK   @BASEBOARD_FAB2_LIB.BASEBOARD_FAB2(SCH_1):TP_M2_32M_SUSCLK
  J8F1    68  SUSCLK  SCONN75K_H17033002_SMT1  I53

TP_M2_DEVSLP    @BASEBOARD_FAB2_LIB.BASEBOARD_FAB2(SCH_1):TP_M2_DEVSLP
  J8F1    38  DEVSLP  SCONN75K_H17033002_SMT1  I53

TP_ME_RCVR_BOOT   @BASEBOARD_FAB2_LIB.BASEBOARD_FAB2(SCH_1):TP_ME_RCVR_BOOT
  J7G3     1    IO1  CONN12_C73564003  I174

TP_M_BMC_DDR3_MIOZ   @BASEBOARD_FAB2_LIB.BASEBOARD_FAB2(SCH_1):TP_M_BMC_DDR3_MIOZ
  U9F4   V16   MIOZ  AST1250_BGA  I281

TP_NMI_CPU0     @BASEBOARD_FAB2_LIB.BASEBOARD_FAB2(SCH_1):TP_NMI_CPU0
  U5D1   AP11    NMI  SKX_EXT_B_BGA1  I259

TP_P1V05_PCH_GL_0   @BASEBOARD_FAB2_LIB.BASEBOARD_FAB2(SCH_1):TP_P1V05_PCH_GL_0
  EU7A2    6  GL<0>  IR354XX_SM  I117

TP_P1V05_PCH_GL_1   @BASEBOARD_FAB2_LIB.BASEBOARD_FAB2(SCH_1):TP_P1V05_PCH_GL_1
  EU7A2   41  GL<1>  IR354XX_SM  I117

TP_P3E_CPU1_PE1_MP_RXN<0>   @BASEBOARD_FAB2_LIB.BASEBOARD_FAB2(SCH_1):TP_P3E_CPU1_PE1_MP_RXN<0>
  U2D1   CW8  PE1_RX_DN<0>  SKX_EXT_B_BGA1  I68

TP_P3E_CPU1_PE1_MP_RXN<1>   @BASEBOARD_FAB2_LIB.BASEBOARD_FAB2(SCH_1):TP_P3E_CPU1_PE1_MP_RXN<1>
  U2D1   DA8  PE1_RX_DN<1>  SKX_EXT_B_BGA1  I68

TP_P3E_CPU1_PE1_MP_RXN<2>   @BASEBOARD_FAB2_LIB.BASEBOARD_FAB2(SCH_1):TP_P3E_CPU1_PE1_MP_RXN<2>
  U2D1   DC8  PE1_RX_DN<2>  SKX_EXT_B_BGA1  I68

TP_P3E_CPU1_PE1_MP_RXN<3>   @BASEBOARD_FAB2_LIB.BASEBOARD_FAB2(SCH_1):TP_P3E_CPU1_PE1_MP_RXN<3>
  U2D1   DC10  PE1_RX_DN<3>  SKX_EXT_B_BGA1  I68

TP_P3E_CPU1_PE1_MP_RXN<4>   @BASEBOARD_FAB2_LIB.BASEBOARD_FAB2(SCH_1):TP_P3E_CPU1_PE1_MP_RXN<4>
  U2D1   DE10  PE1_RX_DN<4>  SKX_EXT_B_BGA1  I68

TP_P3E_CPU1_PE1_MP_RXN<5>   @BASEBOARD_FAB2_LIB.BASEBOARD_FAB2(SCH_1):TP_P3E_CPU1_PE1_MP_RXN<5>
  U2D1   DH9  PE1_RX_DN<5>  SKX_EXT_B_BGA1  I68

TP_P3E_CPU1_PE1_MP_RXN<6>   @BASEBOARD_FAB2_LIB.BASEBOARD_FAB2(SCH_1):TP_P3E_CPU1_PE1_MP_RXN<6>
  U2D1   DK9  PE1_RX_DN<6>  SKX_EXT_B_BGA1  I68

TP_P3E_CPU1_PE1_MP_RXN<7>   @BASEBOARD_FAB2_LIB.BASEBOARD_FAB2(SCH_1):TP_P3E_CPU1_PE1_MP_RXN<7>
  U2D1   DM9  PE1_RX_DN<7>  SKX_EXT_B_BGA1  I68

TP_P3E_CPU1_PE1_MP_RXP<0>   @BASEBOARD_FAB2_LIB.BASEBOARD_FAB2(SCH_1):TP_P3E_CPU1_PE1_MP_RXP<0>
  U2D1   CU8  PE1_RX_DP<0>  SKX_EXT_B_BGA1  I68

TP_P3E_CPU1_PE1_MP_RXP<1>   @BASEBOARD_FAB2_LIB.BASEBOARD_FAB2(SCH_1):TP_P3E_CPU1_PE1_MP_RXP<1>
  U2D1   CY7  PE1_RX_DP<1>  SKX_EXT_B_BGA1  I68

TP_P3E_CPU1_PE1_MP_RXP<2>   @BASEBOARD_FAB2_LIB.BASEBOARD_FAB2(SCH_1):TP_P3E_CPU1_PE1_MP_RXP<2>
  U2D1   DB9  PE1_RX_DP<2>  SKX_EXT_B_BGA1  I68

TP_P3E_CPU1_PE1_MP_RXP<3>   @BASEBOARD_FAB2_LIB.BASEBOARD_FAB2(SCH_1):TP_P3E_CPU1_PE1_MP_RXP<3>
  U2D1   DA10  PE1_RX_DP<3>  SKX_EXT_B_BGA1  I68

TP_P3E_CPU1_PE1_MP_RXP<4>   @BASEBOARD_FAB2_LIB.BASEBOARD_FAB2(SCH_1):TP_P3E_CPU1_PE1_MP_RXP<4>
  U2D1   DD9  PE1_RX_DP<4>  SKX_EXT_B_BGA1  I68

TP_P3E_CPU1_PE1_MP_RXP<5>   @BASEBOARD_FAB2_LIB.BASEBOARD_FAB2(SCH_1):TP_P3E_CPU1_PE1_MP_RXP<5>
  U2D1   DF9  PE1_RX_DP<5>  SKX_EXT_B_BGA1  I68

TP_P3E_CPU1_PE1_MP_RXP<6>   @BASEBOARD_FAB2_LIB.BASEBOARD_FAB2(SCH_1):TP_P3E_CPU1_PE1_MP_RXP<6>
  U2D1   DJ8  PE1_RX_DP<6>  SKX_EXT_B_BGA1  I68

TP_P3E_CPU1_PE1_MP_RXP<7>   @BASEBOARD_FAB2_LIB.BASEBOARD_FAB2(SCH_1):TP_P3E_CPU1_PE1_MP_RXP<7>
  U2D1   DL10  PE1_RX_DP<7>  SKX_EXT_B_BGA1  I68

TP_P3E_CPU1_PE1_MP_TXN<0>   @BASEBOARD_FAB2_LIB.BASEBOARD_FAB2(SCH_1):TP_P3E_CPU1_PE1_MP_TXN<0>
  U2D1   DA2  PE1_TX_DN<0>  SKX_EXT_B_BGA1  I68

TP_P3E_CPU1_PE1_MP_TXN<1>   @BASEBOARD_FAB2_LIB.BASEBOARD_FAB2(SCH_1):TP_P3E_CPU1_PE1_MP_TXN<1>
  U2D1   DC2  PE1_TX_DN<1>  SKX_EXT_B_BGA1  I68

TP_P3E_CPU1_PE1_MP_TXN<2>   @BASEBOARD_FAB2_LIB.BASEBOARD_FAB2(SCH_1):TP_P3E_CPU1_PE1_MP_TXN<2>
  U2D1   DE2  PE1_TX_DN<2>  SKX_EXT_B_BGA1  I68

TP_P3E_CPU1_PE1_MP_TXN<3>   @BASEBOARD_FAB2_LIB.BASEBOARD_FAB2(SCH_1):TP_P3E_CPU1_PE1_MP_TXN<3>
  U2D1   DE4  PE1_TX_DN<3>  SKX_EXT_B_BGA1  I68

TP_P3E_CPU1_PE1_MP_TXN<4>   @BASEBOARD_FAB2_LIB.BASEBOARD_FAB2(SCH_1):TP_P3E_CPU1_PE1_MP_TXN<4>
  U2D1   DG4  PE1_TX_DN<4>  SKX_EXT_B_BGA1  I68

TP_P3E_CPU1_PE1_MP_TXN<5>   @BASEBOARD_FAB2_LIB.BASEBOARD_FAB2(SCH_1):TP_P3E_CPU1_PE1_MP_TXN<5>
  U2D1   DK3  PE1_TX_DN<5>  SKX_EXT_B_BGA1  I68

TP_P3E_CPU1_PE1_MP_TXN<6>   @BASEBOARD_FAB2_LIB.BASEBOARD_FAB2(SCH_1):TP_P3E_CPU1_PE1_MP_TXN<6>
  U2D1   DM3  PE1_TX_DN<6>  SKX_EXT_B_BGA1  I68

TP_P3E_CPU1_PE1_MP_TXN<7>   @BASEBOARD_FAB2_LIB.BASEBOARD_FAB2(SCH_1):TP_P3E_CPU1_PE1_MP_TXN<7>
  U2D1   DN4  PE1_TX_DN<7>  SKX_EXT_B_BGA1  I68

TP_P3E_CPU1_PE1_MP_TXP<0>   @BASEBOARD_FAB2_LIB.BASEBOARD_FAB2(SCH_1):TP_P3E_CPU1_PE1_MP_TXP<0>
  U2D1   CW2  PE1_TX_DP<0>  SKX_EXT_B_BGA1  I68

TP_P3E_CPU1_PE1_MP_TXP<1>   @BASEBOARD_FAB2_LIB.BASEBOARD_FAB2(SCH_1):TP_P3E_CPU1_PE1_MP_TXP<1>
  U2D1   DB1  PE1_TX_DP<1>  SKX_EXT_B_BGA1  I68

TP_P3E_CPU1_PE1_MP_TXP<2>   @BASEBOARD_FAB2_LIB.BASEBOARD_FAB2(SCH_1):TP_P3E_CPU1_PE1_MP_TXP<2>
  U2D1   DD3  PE1_TX_DP<2>  SKX_EXT_B_BGA1  I68

TP_P3E_CPU1_PE1_MP_TXP<3>   @BASEBOARD_FAB2_LIB.BASEBOARD_FAB2(SCH_1):TP_P3E_CPU1_PE1_MP_TXP<3>
  U2D1   DC4  PE1_TX_DP<3>  SKX_EXT_B_BGA1  I68

TP_P3E_CPU1_PE1_MP_TXP<4>   @BASEBOARD_FAB2_LIB.BASEBOARD_FAB2(SCH_1):TP_P3E_CPU1_PE1_MP_TXP<4>
  U2D1   DF3  PE1_TX_DP<4>  SKX_EXT_B_BGA1  I68

TP_P3E_CPU1_PE1_MP_TXP<5>   @BASEBOARD_FAB2_LIB.BASEBOARD_FAB2(SCH_1):TP_P3E_CPU1_PE1_MP_TXP<5>
  U2D1   DH3  PE1_TX_DP<5>  SKX_EXT_B_BGA1  I68

TP_P3E_CPU1_PE1_MP_TXP<6>   @BASEBOARD_FAB2_LIB.BASEBOARD_FAB2(SCH_1):TP_P3E_CPU1_PE1_MP_TXP<6>
  U2D1   DL2  PE1_TX_DP<6>  SKX_EXT_B_BGA1  I68

TP_P3E_CPU1_PE1_MP_TXP<7>   @BASEBOARD_FAB2_LIB.BASEBOARD_FAB2(SCH_1):TP_P3E_CPU1_PE1_MP_TXP<7>
  U2D1   DP3  PE1_TX_DP<7>  SKX_EXT_B_BGA1  I68

TP_P3E_CPU1_PE1_RSR3_RXN<8>   @BASEBOARD_FAB2_LIB.BASEBOARD_FAB2(SCH_1):TP_P3E_CPU1_PE1_RSR3_RXN<8>
  U2D1   DM11  PE1_RX_DN<8>  SKX_EXT_B_BGA1  I68

TP_P3E_CPU1_PE1_RSR3_RXN<9>   @BASEBOARD_FAB2_LIB.BASEBOARD_FAB2(SCH_1):TP_P3E_CPU1_PE1_RSR3_RXN<9>
  U2D1   DP11  PE1_RX_DN<9>  SKX_EXT_B_BGA1  I68

TP_P3E_CPU1_PE1_RSR3_RXN<10>   @BASEBOARD_FAB2_LIB.BASEBOARD_FAB2(SCH_1):TP_P3E_CPU1_PE1_RSR3_RXN<10>
  U2D1   DT11  PE1_RX_DN<10>  SKX_EXT_B_BGA1  I68

TP_P3E_CPU1_PE1_RSR3_RXN<11>   @BASEBOARD_FAB2_LIB.BASEBOARD_FAB2(SCH_1):TP_P3E_CPU1_PE1_RSR3_RXN<11>
  U2D1   DT13  PE1_RX_DN<11>  SKX_EXT_B_BGA1  I68

TP_P3E_CPU1_PE1_RSR3_RXN<12>   @BASEBOARD_FAB2_LIB.BASEBOARD_FAB2(SCH_1):TP_P3E_CPU1_PE1_RSR3_RXN<12>
  U2D1   DV13  PE1_RX_DN<12>  SKX_EXT_B_BGA1  I68

TP_P3E_CPU1_PE1_RSR3_RXN<13>   @BASEBOARD_FAB2_LIB.BASEBOARD_FAB2(SCH_1):TP_P3E_CPU1_PE1_RSR3_RXN<13>
  U2D1   DW14  PE1_RX_DN<13>  SKX_EXT_B_BGA1  I68

TP_P3E_CPU1_PE1_RSR3_RXN<14>   @BASEBOARD_FAB2_LIB.BASEBOARD_FAB2(SCH_1):TP_P3E_CPU1_PE1_RSR3_RXN<14>
  U2D1   DY15  PE1_RX_DN<14>  SKX_EXT_B_BGA1  I68

TP_P3E_CPU1_PE1_RSR3_RXN<15>   @BASEBOARD_FAB2_LIB.BASEBOARD_FAB2(SCH_1):TP_P3E_CPU1_PE1_RSR3_RXN<15>
  U2D1   DU16  PE1_RX_DN<15>  SKX_EXT_B_BGA1  I68

TP_P3E_CPU1_PE1_RSR3_RXP<8>   @BASEBOARD_FAB2_LIB.BASEBOARD_FAB2(SCH_1):TP_P3E_CPU1_PE1_RSR3_RXP<8>
  U2D1   DK11  PE1_RX_DP<8>  SKX_EXT_B_BGA1  I68

TP_P3E_CPU1_PE1_RSR3_RXP<9>   @BASEBOARD_FAB2_LIB.BASEBOARD_FAB2(SCH_1):TP_P3E_CPU1_PE1_RSR3_RXP<9>
  U2D1   DN10  PE1_RX_DP<9>  SKX_EXT_B_BGA1  I68

TP_P3E_CPU1_PE1_RSR3_RXP<10>   @BASEBOARD_FAB2_LIB.BASEBOARD_FAB2(SCH_1):TP_P3E_CPU1_PE1_RSR3_RXP<10>
  U2D1   DR12  PE1_RX_DP<10>  SKX_EXT_B_BGA1  I68

TP_P3E_CPU1_PE1_RSR3_RXP<11>   @BASEBOARD_FAB2_LIB.BASEBOARD_FAB2(SCH_1):TP_P3E_CPU1_PE1_RSR3_RXP<11>
  U2D1   DP13  PE1_RX_DP<11>  SKX_EXT_B_BGA1  I68

TP_P3E_CPU1_PE1_RSR3_RXP<12>   @BASEBOARD_FAB2_LIB.BASEBOARD_FAB2(SCH_1):TP_P3E_CPU1_PE1_RSR3_RXP<12>
  U2D1   DU12  PE1_RX_DP<12>  SKX_EXT_B_BGA1  I68

TP_P3E_CPU1_PE1_RSR3_RXP<13>   @BASEBOARD_FAB2_LIB.BASEBOARD_FAB2(SCH_1):TP_P3E_CPU1_PE1_RSR3_RXP<13>
  U2D1   DY13  PE1_RX_DP<13>  SKX_EXT_B_BGA1  I68

TP_P3E_CPU1_PE1_RSR3_RXP<14>   @BASEBOARD_FAB2_LIB.BASEBOARD_FAB2(SCH_1):TP_P3E_CPU1_PE1_RSR3_RXP<14>
  U2D1   DV15  PE1_RX_DP<14>  SKX_EXT_B_BGA1  I68

TP_P3E_CPU1_PE1_RSR3_RXP<15>   @BASEBOARD_FAB2_LIB.BASEBOARD_FAB2(SCH_1):TP_P3E_CPU1_PE1_RSR3_RXP<15>
  U2D1   DT15  PE1_RX_DP<15>  SKX_EXT_B_BGA1  I68

TP_P3E_CPU1_PE1_RSR3_TXN<8>   @BASEBOARD_FAB2_LIB.BASEBOARD_FAB2(SCH_1):TP_P3E_CPU1_PE1_RSR3_TXN<8>
  U2D1   DT5  PE1_TX_DN<8>  SKX_EXT_B_BGA1  I68

TP_P3E_CPU1_PE1_RSR3_TXN<9>   @BASEBOARD_FAB2_LIB.BASEBOARD_FAB2(SCH_1):TP_P3E_CPU1_PE1_RSR3_TXN<9>
  U2D1   DV3  PE1_TX_DN<9>  SKX_EXT_B_BGA1  I68

TP_P3E_CPU1_PE1_RSR3_TXN<10>   @BASEBOARD_FAB2_LIB.BASEBOARD_FAB2(SCH_1):TP_P3E_CPU1_PE1_RSR3_TXN<10>
  U2D1   DW4  PE1_TX_DN<10>  SKX_EXT_B_BGA1  I68

TP_P3E_CPU1_PE1_RSR3_TXN<11>   @BASEBOARD_FAB2_LIB.BASEBOARD_FAB2(SCH_1):TP_P3E_CPU1_PE1_RSR3_TXN<11>
  U2D1   DU6  PE1_TX_DN<11>  SKX_EXT_B_BGA1  I68

TP_P3E_CPU1_PE1_RSR3_TXN<12>   @BASEBOARD_FAB2_LIB.BASEBOARD_FAB2(SCH_1):TP_P3E_CPU1_PE1_RSR3_TXN<12>
  U2D1   DV7  PE1_TX_DN<12>  SKX_EXT_B_BGA1  I68

TP_P3E_CPU1_PE1_RSR3_TXN<13>   @BASEBOARD_FAB2_LIB.BASEBOARD_FAB2(SCH_1):TP_P3E_CPU1_PE1_RSR3_TXN<13>
  U2D1   DY7  PE1_TX_DN<13>  SKX_EXT_B_BGA1  I68

TP_P3E_CPU1_PE1_RSR3_TXN<14>   @BASEBOARD_FAB2_LIB.BASEBOARD_FAB2(SCH_1):TP_P3E_CPU1_PE1_RSR3_TXN<14>
  U2D1   EA8  PE1_TX_DN<14>  SKX_EXT_B_BGA1  I68

TP_P3E_CPU1_PE1_RSR3_TXN<15>   @BASEBOARD_FAB2_LIB.BASEBOARD_FAB2(SCH_1):TP_P3E_CPU1_PE1_RSR3_TXN<15>
  U2D1   ED9  PE1_TX_DN<15>  SKX_EXT_B_BGA1  I68

TP_P3E_CPU1_PE1_RSR3_TXP<8>   @BASEBOARD_FAB2_LIB.BASEBOARD_FAB2(SCH_1):TP_P3E_CPU1_PE1_RSR3_TXP<8>
  U2D1   DR4  PE1_TX_DP<8>  SKX_EXT_B_BGA1  I68

TP_P3E_CPU1_PE1_RSR3_TXP<9>   @BASEBOARD_FAB2_LIB.BASEBOARD_FAB2(SCH_1):TP_P3E_CPU1_PE1_RSR3_TXP<9>
  U2D1   DU2  PE1_TX_DP<9>  SKX_EXT_B_BGA1  I68

TP_P3E_CPU1_PE1_RSR3_TXP<10>   @BASEBOARD_FAB2_LIB.BASEBOARD_FAB2(SCH_1):TP_P3E_CPU1_PE1_RSR3_TXP<10>
  U2D1   DU4  PE1_TX_DP<10>  SKX_EXT_B_BGA1  I68

TP_P3E_CPU1_PE1_RSR3_TXP<11>   @BASEBOARD_FAB2_LIB.BASEBOARD_FAB2(SCH_1):TP_P3E_CPU1_PE1_RSR3_TXP<11>
  U2D1   DV5  PE1_TX_DP<11>  SKX_EXT_B_BGA1  I68

TP_P3E_CPU1_PE1_RSR3_TXP<12>   @BASEBOARD_FAB2_LIB.BASEBOARD_FAB2(SCH_1):TP_P3E_CPU1_PE1_RSR3_TXP<12>
  U2D1   DT7  PE1_TX_DP<12>  SKX_EXT_B_BGA1  I68

TP_P3E_CPU1_PE1_RSR3_TXP<13>   @BASEBOARD_FAB2_LIB.BASEBOARD_FAB2(SCH_1):TP_P3E_CPU1_PE1_RSR3_TXP<13>
  U2D1   DW6  PE1_TX_DP<13>  SKX_EXT_B_BGA1  I68

TP_P3E_CPU1_PE1_RSR3_TXP<14>   @BASEBOARD_FAB2_LIB.BASEBOARD_FAB2(SCH_1):TP_P3E_CPU1_PE1_RSR3_TXP<14>
  U2D1   EB7  PE1_TX_DP<14>  SKX_EXT_B_BGA1  I68

TP_P3E_CPU1_PE1_RSR3_TXP<15>   @BASEBOARD_FAB2_LIB.BASEBOARD_FAB2(SCH_1):TP_P3E_CPU1_PE1_RSR3_TXP<15>
  U2D1   EC8  PE1_TX_DP<15>  SKX_EXT_B_BGA1  I68

TP_P3E_CPU1_PE2_RSR_RXN<0>   @BASEBOARD_FAB2_LIB.BASEBOARD_FAB2(SCH_1):TP_P3E_CPU1_PE2_RSR_RXN<0>
  U2D1   CT9  PE2_RX_DN<0>  SKX_EXT_B_BGA1  I68

TP_P3E_CPU1_PE2_RSR_RXN<1>   @BASEBOARD_FAB2_LIB.BASEBOARD_FAB2(SCH_1):TP_P3E_CPU1_PE2_RSR_RXN<1>
  U2D1   CP9  PE2_RX_DN<1>  SKX_EXT_B_BGA1  I68

TP_P3E_CPU1_PE2_RSR_RXN<2>   @BASEBOARD_FAB2_LIB.BASEBOARD_FAB2(SCH_1):TP_P3E_CPU1_PE2_RSR_RXN<2>
  U2D1   CP7  PE2_RX_DN<2>  SKX_EXT_B_BGA1  I68

TP_P3E_CPU1_PE2_RSR_RXN<3>   @BASEBOARD_FAB2_LIB.BASEBOARD_FAB2(SCH_1):TP_P3E_CPU1_PE2_RSR_RXN<3>
  U2D1   CM7  PE2_RX_DN<3>  SKX_EXT_B_BGA1  I68

TP_P3E_CPU1_PE2_RSR_RXN<4>   @BASEBOARD_FAB2_LIB.BASEBOARD_FAB2(SCH_1):TP_P3E_CPU1_PE2_RSR_RXN<4>
  U2D1   CK7  PE2_RX_DN<4>  SKX_EXT_B_BGA1  I68

TP_P3E_CPU1_PE2_RSR_RXN<5>   @BASEBOARD_FAB2_LIB.BASEBOARD_FAB2(SCH_1):TP_P3E_CPU1_PE2_RSR_RXN<5>
  U2D1   CG8  PE2_RX_DN<5>  SKX_EXT_B_BGA1  I68

TP_P3E_CPU1_PE2_RSR_RXN<6>   @BASEBOARD_FAB2_LIB.BASEBOARD_FAB2(SCH_1):TP_P3E_CPU1_PE2_RSR_RXN<6>
  U2D1   CE6  PE2_RX_DN<6>  SKX_EXT_B_BGA1  I68

TP_P3E_CPU1_PE2_RSR_RXN<7>   @BASEBOARD_FAB2_LIB.BASEBOARD_FAB2(SCH_1):TP_P3E_CPU1_PE2_RSR_RXN<7>
  U2D1   CE8  PE2_RX_DN<7>  SKX_EXT_B_BGA1  I68

TP_P3E_CPU1_PE2_RSR_RXN<8>   @BASEBOARD_FAB2_LIB.BASEBOARD_FAB2(SCH_1):TP_P3E_CPU1_PE2_RSR_RXN<8>
  U2D1   BY9  PE2_RX_DN<8>  SKX_EXT_B_BGA1  I68

TP_P3E_CPU1_PE2_RSR_RXN<9>   @BASEBOARD_FAB2_LIB.BASEBOARD_FAB2(SCH_1):TP_P3E_CPU1_PE2_RSR_RXN<9>
  U2D1   BY7  PE2_RX_DN<9>  SKX_EXT_B_BGA1  I68

TP_P3E_CPU1_PE2_RSR_RXN<10>   @BASEBOARD_FAB2_LIB.BASEBOARD_FAB2(SCH_1):TP_P3E_CPU1_PE2_RSR_RXN<10>
  U2D1   BV7  PE2_RX_DN<10>  SKX_EXT_B_BGA1  I68

TP_P3E_CPU1_PE2_RSR_RXN<11>   @BASEBOARD_FAB2_LIB.BASEBOARD_FAB2(SCH_1):TP_P3E_CPU1_PE2_RSR_RXN<11>
  U2D1   BT7  PE2_RX_DN<11>  SKX_EXT_B_BGA1  I68

TP_P3E_CPU1_PE2_RSR_RXN<12>   @BASEBOARD_FAB2_LIB.BASEBOARD_FAB2(SCH_1):TP_P3E_CPU1_PE2_RSR_RXN<12>
  U2D1   BR8  PE2_RX_DN<12>  SKX_EXT_B_BGA1  I68

TP_P3E_CPU1_PE2_RSR_RXN<13>   @BASEBOARD_FAB2_LIB.BASEBOARD_FAB2(SCH_1):TP_P3E_CPU1_PE2_RSR_RXN<13>
  U2D1   BN8  PE2_RX_DN<13>  SKX_EXT_B_BGA1  I68

TP_P3E_CPU1_PE2_RSR_RXN<14>   @BASEBOARD_FAB2_LIB.BASEBOARD_FAB2(SCH_1):TP_P3E_CPU1_PE2_RSR_RXN<14>
  U2D1   BL8  PE2_RX_DN<14>  SKX_EXT_B_BGA1  I68

TP_P3E_CPU1_PE2_RSR_RXN<15>   @BASEBOARD_FAB2_LIB.BASEBOARD_FAB2(SCH_1):TP_P3E_CPU1_PE2_RSR_RXN<15>
  U2D1   BK9  PE2_RX_DN<15>  SKX_EXT_B_BGA1  I68

TP_P3E_CPU1_PE2_RSR_RXP<0>   @BASEBOARD_FAB2_LIB.BASEBOARD_FAB2(SCH_1):TP_P3E_CPU1_PE2_RSR_RXP<0>
  U2D1   CR8  PE2_RX_DP<0>  SKX_EXT_B_BGA1  I68

TP_P3E_CPU1_PE2_RSR_RXP<1>   @BASEBOARD_FAB2_LIB.BASEBOARD_FAB2(SCH_1):TP_P3E_CPU1_PE2_RSR_RXP<1>
  U2D1   CM9  PE2_RX_DP<1>  SKX_EXT_B_BGA1  I68

TP_P3E_CPU1_PE2_RSR_RXP<2>   @BASEBOARD_FAB2_LIB.BASEBOARD_FAB2(SCH_1):TP_P3E_CPU1_PE2_RSR_RXP<2>
  U2D1   CN8  PE2_RX_DP<2>  SKX_EXT_B_BGA1  I68

TP_P3E_CPU1_PE2_RSR_RXP<3>   @BASEBOARD_FAB2_LIB.BASEBOARD_FAB2(SCH_1):TP_P3E_CPU1_PE2_RSR_RXP<3>
  U2D1   CL6  PE2_RX_DP<3>  SKX_EXT_B_BGA1  I68

TP_P3E_CPU1_PE2_RSR_RXP<4>   @BASEBOARD_FAB2_LIB.BASEBOARD_FAB2(SCH_1):TP_P3E_CPU1_PE2_RSR_RXP<4>
  U2D1   CH7  PE2_RX_DP<4>  SKX_EXT_B_BGA1  I68

TP_P3E_CPU1_PE2_RSR_RXP<5>   @BASEBOARD_FAB2_LIB.BASEBOARD_FAB2(SCH_1):TP_P3E_CPU1_PE2_RSR_RXP<5>
  U2D1   CF7  PE2_RX_DP<5>  SKX_EXT_B_BGA1  I68

TP_P3E_CPU1_PE2_RSR_RXP<6>   @BASEBOARD_FAB2_LIB.BASEBOARD_FAB2(SCH_1):TP_P3E_CPU1_PE2_RSR_RXP<6>
  U2D1   CD7  PE2_RX_DP<6>  SKX_EXT_B_BGA1  I68

TP_P3E_CPU1_PE2_RSR_RXP<7>   @BASEBOARD_FAB2_LIB.BASEBOARD_FAB2(SCH_1):TP_P3E_CPU1_PE2_RSR_RXP<7>
  U2D1   CC8  PE2_RX_DP<7>  SKX_EXT_B_BGA1  I68

TP_P3E_CPU1_PE2_RSR_RXP<8>   @BASEBOARD_FAB2_LIB.BASEBOARD_FAB2(SCH_1):TP_P3E_CPU1_PE2_RSR_RXP<8>
  U2D1   BV9  PE2_RX_DP<8>  SKX_EXT_B_BGA1  I68

TP_P3E_CPU1_PE2_RSR_RXP<9>   @BASEBOARD_FAB2_LIB.BASEBOARD_FAB2(SCH_1):TP_P3E_CPU1_PE2_RSR_RXP<9>
  U2D1   BW8  PE2_RX_DP<9>  SKX_EXT_B_BGA1  I68

TP_P3E_CPU1_PE2_RSR_RXP<10>   @BASEBOARD_FAB2_LIB.BASEBOARD_FAB2(SCH_1):TP_P3E_CPU1_PE2_RSR_RXP<10>
  U2D1   BU6  PE2_RX_DP<10>  SKX_EXT_B_BGA1  I68

TP_P3E_CPU1_PE2_RSR_RXP<11>   @BASEBOARD_FAB2_LIB.BASEBOARD_FAB2(SCH_1):TP_P3E_CPU1_PE2_RSR_RXP<11>
  U2D1   BP7  PE2_RX_DP<11>  SKX_EXT_B_BGA1  I68

TP_P3E_CPU1_PE2_RSR_RXP<12>   @BASEBOARD_FAB2_LIB.BASEBOARD_FAB2(SCH_1):TP_P3E_CPU1_PE2_RSR_RXP<12>
  U2D1   BP9  PE2_RX_DP<12>  SKX_EXT_B_BGA1  I68

TP_P3E_CPU1_PE2_RSR_RXP<13>   @BASEBOARD_FAB2_LIB.BASEBOARD_FAB2(SCH_1):TP_P3E_CPU1_PE2_RSR_RXP<13>
  U2D1   BM7  PE2_RX_DP<13>  SKX_EXT_B_BGA1  I68

TP_P3E_CPU1_PE2_RSR_RXP<14>   @BASEBOARD_FAB2_LIB.BASEBOARD_FAB2(SCH_1):TP_P3E_CPU1_PE2_RSR_RXP<14>
  U2D1   BJ8  PE2_RX_DP<14>  SKX_EXT_B_BGA1  I68

TP_P3E_CPU1_PE2_RSR_RXP<15>   @BASEBOARD_FAB2_LIB.BASEBOARD_FAB2(SCH_1):TP_P3E_CPU1_PE2_RSR_RXP<15>
  U2D1   BJ10  PE2_RX_DP<15>  SKX_EXT_B_BGA1  I68

TP_P3E_CPU1_PE2_RSR_TXN<0>   @BASEBOARD_FAB2_LIB.BASEBOARD_FAB2(SCH_1):TP_P3E_CPU1_PE2_RSR_TXN<0>
  U2D1   CY3  PE2_TX_DN<0>  SKX_EXT_B_BGA1  I68

TP_P3E_CPU1_PE2_RSR_TXN<1>   @BASEBOARD_FAB2_LIB.BASEBOARD_FAB2(SCH_1):TP_P3E_CPU1_PE2_RSR_TXN<1>
  U2D1   CV3  PE2_TX_DN<1>  SKX_EXT_B_BGA1  I68

TP_P3E_CPU1_PE2_RSR_TXN<2>   @BASEBOARD_FAB2_LIB.BASEBOARD_FAB2(SCH_1):TP_P3E_CPU1_PE2_RSR_TXN<2>
  U2D1   CT1  PE2_TX_DN<2>  SKX_EXT_B_BGA1  I68

TP_P3E_CPU1_PE2_RSR_TXN<3>   @BASEBOARD_FAB2_LIB.BASEBOARD_FAB2(SCH_1):TP_P3E_CPU1_PE2_RSR_TXN<3>
  U2D1   CT3  PE2_TX_DN<3>  SKX_EXT_B_BGA1  I68

TP_P3E_CPU1_PE2_RSR_TXN<4>   @BASEBOARD_FAB2_LIB.BASEBOARD_FAB2(SCH_1):TP_P3E_CPU1_PE2_RSR_TXN<4>
  U2D1   CM1  PE2_TX_DN<4>  SKX_EXT_B_BGA1  I68

TP_P3E_CPU1_PE2_RSR_TXN<5>   @BASEBOARD_FAB2_LIB.BASEBOARD_FAB2(SCH_1):TP_P3E_CPU1_PE2_RSR_TXN<5>
  U2D1   CL2  PE2_TX_DN<5>  SKX_EXT_B_BGA1  I68

TP_P3E_CPU1_PE2_RSR_TXN<6>   @BASEBOARD_FAB2_LIB.BASEBOARD_FAB2(SCH_1):TP_P3E_CPU1_PE2_RSR_TXN<6>
  U2D1   CG2  PE2_TX_DN<6>  SKX_EXT_B_BGA1  I68

TP_P3E_CPU1_PE2_RSR_TXN<7>   @BASEBOARD_FAB2_LIB.BASEBOARD_FAB2(SCH_1):TP_P3E_CPU1_PE2_RSR_TXN<7>
  U2D1   CF3  PE2_TX_DN<7>  SKX_EXT_B_BGA1  I68

TP_P3E_CPU1_PE2_RSR_TXN<8>   @BASEBOARD_FAB2_LIB.BASEBOARD_FAB2(SCH_1):TP_P3E_CPU1_PE2_RSR_TXN<8>
  U2D1   CC2  PE2_TX_DN<8>  SKX_EXT_B_BGA1  I68

TP_P3E_CPU1_PE2_RSR_TXN<9>   @BASEBOARD_FAB2_LIB.BASEBOARD_FAB2(SCH_1):TP_P3E_CPU1_PE2_RSR_TXN<9>
  U2D1   CB3  PE2_TX_DN<9>  SKX_EXT_B_BGA1  I68

TP_P3E_CPU1_PE2_RSR_TXN<10>   @BASEBOARD_FAB2_LIB.BASEBOARD_FAB2(SCH_1):TP_P3E_CPU1_PE2_RSR_TXN<10>
  U2D1   CA4  PE2_TX_DN<10>  SKX_EXT_B_BGA1  I68

TP_P3E_CPU1_PE2_RSR_TXN<11>   @BASEBOARD_FAB2_LIB.BASEBOARD_FAB2(SCH_1):TP_P3E_CPU1_PE2_RSR_TXN<11>
  U2D1   BW4  PE2_TX_DN<11>  SKX_EXT_B_BGA1  I68

TP_P3E_CPU1_PE2_RSR_TXN<12>   @BASEBOARD_FAB2_LIB.BASEBOARD_FAB2(SCH_1):TP_P3E_CPU1_PE2_RSR_TXN<12>
  U2D1   BU4  PE2_TX_DN<12>  SKX_EXT_B_BGA1  I68

TP_P3E_CPU1_PE2_RSR_TXN<13>   @BASEBOARD_FAB2_LIB.BASEBOARD_FAB2(SCH_1):TP_P3E_CPU1_PE2_RSR_TXN<13>
  U2D1   BP5  PE2_TX_DN<13>  SKX_EXT_B_BGA1  I68

TP_P3E_CPU1_PE2_RSR_TXN<14>   @BASEBOARD_FAB2_LIB.BASEBOARD_FAB2(SCH_1):TP_P3E_CPU1_PE2_RSR_TXN<14>
  U2D1   BL4  PE2_TX_DN<14>  SKX_EXT_B_BGA1  I68

TP_P3E_CPU1_PE2_RSR_TXN<15>   @BASEBOARD_FAB2_LIB.BASEBOARD_FAB2(SCH_1):TP_P3E_CPU1_PE2_RSR_TXN<15>
  U2D1   BM5  PE2_TX_DN<15>  SKX_EXT_B_BGA1  I68

TP_P3E_CPU1_PE2_RSR_TXP<0>   @BASEBOARD_FAB2_LIB.BASEBOARD_FAB2(SCH_1):TP_P3E_CPU1_PE2_RSR_TXP<0>
  U2D1   CW4  PE2_TX_DP<0>  SKX_EXT_B_BGA1  I68

TP_P3E_CPU1_PE2_RSR_TXP<1>   @BASEBOARD_FAB2_LIB.BASEBOARD_FAB2(SCH_1):TP_P3E_CPU1_PE2_RSR_TXP<1>
  U2D1   CU2  PE2_TX_DP<1>  SKX_EXT_B_BGA1  I68

TP_P3E_CPU1_PE2_RSR_TXP<2>   @BASEBOARD_FAB2_LIB.BASEBOARD_FAB2(SCH_1):TP_P3E_CPU1_PE2_RSR_TXP<2>
  U2D1   CR2  PE2_TX_DP<2>  SKX_EXT_B_BGA1  I68

TP_P3E_CPU1_PE2_RSR_TXP<3>   @BASEBOARD_FAB2_LIB.BASEBOARD_FAB2(SCH_1):TP_P3E_CPU1_PE2_RSR_TXP<3>
  U2D1   CP3  PE2_TX_DP<3>  SKX_EXT_B_BGA1  I68

TP_P3E_CPU1_PE2_RSR_TXP<4>   @BASEBOARD_FAB2_LIB.BASEBOARD_FAB2(SCH_1):TP_P3E_CPU1_PE2_RSR_TXP<4>
  U2D1   CK1  PE2_TX_DP<4>  SKX_EXT_B_BGA1  I68

TP_P3E_CPU1_PE2_RSR_TXP<5>   @BASEBOARD_FAB2_LIB.BASEBOARD_FAB2(SCH_1):TP_P3E_CPU1_PE2_RSR_TXP<5>
  U2D1   CK3  PE2_TX_DP<5>  SKX_EXT_B_BGA1  I68

TP_P3E_CPU1_PE2_RSR_TXP<6>   @BASEBOARD_FAB2_LIB.BASEBOARD_FAB2(SCH_1):TP_P3E_CPU1_PE2_RSR_TXP<6>
  U2D1   CE2  PE2_TX_DP<6>  SKX_EXT_B_BGA1  I68

TP_P3E_CPU1_PE2_RSR_TXP<7>   @BASEBOARD_FAB2_LIB.BASEBOARD_FAB2(SCH_1):TP_P3E_CPU1_PE2_RSR_TXP<7>
  U2D1   CE4  PE2_TX_DP<7>  SKX_EXT_B_BGA1  I68

TP_P3E_CPU1_PE2_RSR_TXP<8>   @BASEBOARD_FAB2_LIB.BASEBOARD_FAB2(SCH_1):TP_P3E_CPU1_PE2_RSR_TXP<8>
  U2D1   CD3  PE2_TX_DP<8>  SKX_EXT_B_BGA1  I68

TP_P3E_CPU1_PE2_RSR_TXP<9>   @BASEBOARD_FAB2_LIB.BASEBOARD_FAB2(SCH_1):TP_P3E_CPU1_PE2_RSR_TXP<9>
  U2D1   BY3  PE2_TX_DP<9>  SKX_EXT_B_BGA1  I68

TP_P3E_CPU1_PE2_RSR_TXP<10>   @BASEBOARD_FAB2_LIB.BASEBOARD_FAB2(SCH_1):TP_P3E_CPU1_PE2_RSR_TXP<10>
  U2D1   BY5  PE2_TX_DP<10>  SKX_EXT_B_BGA1  I68

TP_P3E_CPU1_PE2_RSR_TXP<11>   @BASEBOARD_FAB2_LIB.BASEBOARD_FAB2(SCH_1):TP_P3E_CPU1_PE2_RSR_TXP<11>
  U2D1   BV3  PE2_TX_DP<11>  SKX_EXT_B_BGA1  I68

TP_P3E_CPU1_PE2_RSR_TXP<12>   @BASEBOARD_FAB2_LIB.BASEBOARD_FAB2(SCH_1):TP_P3E_CPU1_PE2_RSR_TXP<12>
  U2D1   BR4  PE2_TX_DP<12>  SKX_EXT_B_BGA1  I68

TP_P3E_CPU1_PE2_RSR_TXP<13>   @BASEBOARD_FAB2_LIB.BASEBOARD_FAB2(SCH_1):TP_P3E_CPU1_PE2_RSR_TXP<13>
  U2D1   BN4  PE2_TX_DP<13>  SKX_EXT_B_BGA1  I68

TP_P3E_CPU1_PE2_RSR_TXP<14>   @BASEBOARD_FAB2_LIB.BASEBOARD_FAB2(SCH_1):TP_P3E_CPU1_PE2_RSR_TXP<14>
  U2D1   BM3  PE2_TX_DP<14>  SKX_EXT_B_BGA1  I68

TP_P3E_CPU1_PE2_RSR_TXP<15>   @BASEBOARD_FAB2_LIB.BASEBOARD_FAB2(SCH_1):TP_P3E_CPU1_PE2_RSR_TXP<15>
  U2D1   BK5  PE2_TX_DP<15>  SKX_EXT_B_BGA1  I68

TP_PASSWORD_CLEAR   @BASEBOARD_FAB2_LIB.BASEBOARD_FAB2(SCH_1):TP_PASSWORD_CLEAR
  J7G3     7    IO7  CONN12_C73564003  I174

TP_PCH_DISPA_BCLK   @BASEBOARD_FAB2_LIB.BASEBOARD_FAB2(SCH_1):TP_PCH_DISPA_BCLK
  U7C1   U20  RSVD<66>  LBG_CORE_QAT_EXT_D  I34

TP_PCH_DISPA_SDI   @BASEBOARD_FAB2_LIB.BASEBOARD_FAB2(SCH_1):TP_PCH_DISPA_SDI
  U7C1   R20  RSVD<67>  LBG_CORE_QAT_EXT_D  I34

TP_PCH_DISPA_SDO   @BASEBOARD_FAB2_LIB.BASEBOARD_FAB2(SCH_1):TP_PCH_DISPA_SDO
  U7C1   V22  RSVD<68>  LBG_CORE_QAT_EXT_D  I34

TP_PCH_GPP_D12   @BASEBOARD_FAB2_LIB.BASEBOARD_FAB2(SCH_1):TP_PCH_GPP_D12
  U7C1   BN40  GPP_D12_SSATA_SDATAOUT1  LBG_CORE_QAT_EXT_D  I115

TP_PCH_GPP_F12   @BASEBOARD_FAB2_LIB.BASEBOARD_FAB2(SCH_1):TP_PCH_GPP_F12
  U7C1   AP7  GPP_F12_SATA_SDATAOUT1  LBG_CORE_QAT_EXT_D  I147

TP_PCH_GPP_J17   @BASEBOARD_FAB2_LIB.BASEBOARD_FAB2(SCH_1):TP_PCH_GPP_J17
  U7C1   CA11  GPP_J17_LAN_SDP_P0_1  LBG_CORE_QAT_EXT_D  I147

TP_PCH_GPP_J19   @BASEBOARD_FAB2_LIB.BASEBOARD_FAB2(SCH_1):TP_PCH_GPP_J19
  U7C1   BY14  GPP_J19_LAN_SDP_P1_1  LBG_CORE_QAT_EXT_D  I147

TP_PCH_GPP_J21   @BASEBOARD_FAB2_LIB.BASEBOARD_FAB2(SCH_1):TP_PCH_GPP_J21
  U7C1   BV12  GPP_J21_LAN_SDP_P2_1  LBG_CORE_QAT_EXT_D  I147

TP_PCH_GPP_J23   @BASEBOARD_FAB2_LIB.BASEBOARD_FAB2(SCH_1):TP_PCH_GPP_J23
  U7C1   BV14  GPP_J23_LAN_SDP_P3_1  LBG_CORE_QAT_EXT_D  I147

TP_PCH_GPP_L10   @BASEBOARD_FAB2_LIB.BASEBOARD_FAB2(SCH_1):TP_PCH_GPP_L10
  U7C1   AF20  GPP_L10_TESTCH0_CLK  LBG_CORE_QAT_EXT_D  I34

TP_PCH_GPP_L11   @BASEBOARD_FAB2_LIB.BASEBOARD_FAB2(SCH_1):TP_PCH_GPP_L11
  U7C1   AD20  GPP_L11_TESTCH1_D0  LBG_CORE_QAT_EXT_D  I34

TP_PCH_HDA_BCLK   @BASEBOARD_FAB2_LIB.BASEBOARD_FAB2(SCH_1):TP_PCH_HDA_BCLK
  U7C1   P18  HDA_BCLK  LBG_CORE_QAT_EXT_D  I34

TP_PCH_HDA_SDI_0   @BASEBOARD_FAB2_LIB.BASEBOARD_FAB2(SCH_1):TP_PCH_HDA_SDI_0
  U7C1   K20  HDA_SDI_0  LBG_CORE_QAT_EXT_D  I34

TP_PCH_HDA_SDI_1   @BASEBOARD_FAB2_LIB.BASEBOARD_FAB2(SCH_1):TP_PCH_HDA_SDI_1
  U7C1   V18  HDA_SDI_1  LBG_CORE_QAT_EXT_D  I34

TP_PCH_HDA_SYNC   @BASEBOARD_FAB2_LIB.BASEBOARD_FAB2(SCH_1):TP_PCH_HDA_SYNC
  U7C1   H20  HDA_SYNC  LBG_CORE_QAT_EXT_D  I34

TP_PCH_HSA_RST_N   @BASEBOARD_FAB2_LIB.BASEBOARD_FAB2(SCH_1):TP_PCH_HSA_RST_N
  U7C1   M18  HDA_RST_N  LBG_CORE_QAT_EXT_D  I34

TP_PCH_RSVD0    @BASEBOARD_FAB2_LIB.BASEBOARD_FAB2(SCH_1):TP_PCH_RSVD0
  U7C1   AF61  RSVD<0>  LBG_CORE_QAT_EXT_D  I34

TP_PCH_RSVD1    @BASEBOARD_FAB2_LIB.BASEBOARD_FAB2(SCH_1):TP_PCH_RSVD1
  U7C1   AC56  RSVD<1>  LBG_CORE_QAT_EXT_D  I34

TP_PCH_RSVD2    @BASEBOARD_FAB2_LIB.BASEBOARD_FAB2(SCH_1):TP_PCH_RSVD2
  U7C1   AA58  RSVD<2>  LBG_CORE_QAT_EXT_D  I34

TP_PCH_RSVD3    @BASEBOARD_FAB2_LIB.BASEBOARD_FAB2(SCH_1):TP_PCH_RSVD3
  U7C1   V11  RSVD<3>  LBG_CORE_QAT_EXT_D  I34

TP_PCH_RSVD4    @BASEBOARD_FAB2_LIB.BASEBOARD_FAB2(SCH_1):TP_PCH_RSVD4
  U7C1   P37  RSVD<4>  LBG_CORE_QAT_EXT_D  I34

TP_PCH_RSVD5    @BASEBOARD_FAB2_LIB.BASEBOARD_FAB2(SCH_1):TP_PCH_RSVD5
  U7C1   AG15  RSVD<5>  LBG_CORE_QAT_EXT_D  I34

TP_PCH_RSVD6    @BASEBOARD_FAB2_LIB.BASEBOARD_FAB2(SCH_1):TP_PCH_RSVD6
  U7C1   AT69  RSVD<6>  LBG_CORE_QAT_EXT_D  I34

TP_PCH_RSVD7    @BASEBOARD_FAB2_LIB.BASEBOARD_FAB2(SCH_1):TP_PCH_RSVD7
  U7C1    F8  RSVD<7>  LBG_CORE_QAT_EXT_D  I34

TP_PCH_RSVD8    @BASEBOARD_FAB2_LIB.BASEBOARD_FAB2(SCH_1):TP_PCH_RSVD8
  U7C1   F69  RSVD<8>  LBG_CORE_QAT_EXT_D  I34

TP_PCH_RSVD9    @BASEBOARD_FAB2_LIB.BASEBOARD_FAB2(SCH_1):TP_PCH_RSVD9
  U7C1   F66  RSVD<9>  LBG_CORE_QAT_EXT_D  I34

TP_PCH_RSVD12   @BASEBOARD_FAB2_LIB.BASEBOARD_FAB2(SCH_1):TP_PCH_RSVD12
  U7C1   C68  RSVD<12>  LBG_CORE_QAT_EXT_D  I34

TP_PCH_RSVD13   @BASEBOARD_FAB2_LIB.BASEBOARD_FAB2(SCH_1):TP_PCH_RSVD13
  U7C1   C67  RSVD<13>  LBG_CORE_QAT_EXT_D  I34

TP_PCH_RSVD14   @BASEBOARD_FAB2_LIB.BASEBOARD_FAB2(SCH_1):TP_PCH_RSVD14
  U7C1   E18  RSVD<14>  LBG_CORE_QAT_EXT_D  I34

TP_PCH_RSVD15   @BASEBOARD_FAB2_LIB.BASEBOARD_FAB2(SCH_1):TP_PCH_RSVD15
  U7C1    C6  RSVD<15>  LBG_CORE_QAT_EXT_D  I34

TP_PCH_RSVD16   @BASEBOARD_FAB2_LIB.BASEBOARD_FAB2(SCH_1):TP_PCH_RSVD16
  U7C1    C5  RSVD<16>  LBG_CORE_QAT_EXT_D  I34

TP_PCH_RSVD17   @BASEBOARD_FAB2_LIB.BASEBOARD_FAB2(SCH_1):TP_PCH_RSVD17
  U7C1   B10  RSVD<17>  LBG_CORE_QAT_EXT_D  I34

TP_PCH_RSVD18   @BASEBOARD_FAB2_LIB.BASEBOARD_FAB2(SCH_1):TP_PCH_RSVD18
  U7C1   C11  RSVD<18>  LBG_CORE_QAT_EXT_D  I34

TP_PCH_RSVD19   @BASEBOARD_FAB2_LIB.BASEBOARD_FAB2(SCH_1):TP_PCH_RSVD19
  U7C1    C9  RSVD<19>  LBG_CORE_QAT_EXT_D  I34

TP_PCH_RSVD20   @BASEBOARD_FAB2_LIB.BASEBOARD_FAB2(SCH_1):TP_PCH_RSVD20
  U7C1   D10  RSVD<20>  LBG_CORE_QAT_EXT_D  I34

TP_PCH_RSVD21   @BASEBOARD_FAB2_LIB.BASEBOARD_FAB2(SCH_1):TP_PCH_RSVD21
  U7C1   A11  RSVD<21>  LBG_CORE_QAT_EXT_D  I34

TP_PCH_RSVD22   @BASEBOARD_FAB2_LIB.BASEBOARD_FAB2(SCH_1):TP_PCH_RSVD22
  U7C1   AT71  RSVD<22>  LBG_CORE_QAT_EXT_D  I34

TP_PCH_RSVD23   @BASEBOARD_FAB2_LIB.BASEBOARD_FAB2(SCH_1):TP_PCH_RSVD23
  U7C1   P40  RSVD<23>  LBG_CORE_QAT_EXT_D  I34

TP_PCH_RSVD24   @BASEBOARD_FAB2_LIB.BASEBOARD_FAB2(SCH_1):TP_PCH_RSVD24
  U7C1   P44  RSVD<24>  LBG_CORE_QAT_EXT_D  I34

TP_PCH_RSVD25   @BASEBOARD_FAB2_LIB.BASEBOARD_FAB2(SCH_1):TP_PCH_RSVD25
  U7C1   P48  RSVD<25>  LBG_CORE_QAT_EXT_D  I34

TP_PCH_RSVD26   @BASEBOARD_FAB2_LIB.BASEBOARD_FAB2(SCH_1):TP_PCH_RSVD26
  U7C1   BH24  RSVD<26>  LBG_CORE_QAT_EXT_D  I34

TP_PCH_RSVD27   @BASEBOARD_FAB2_LIB.BASEBOARD_FAB2(SCH_1):TP_PCH_RSVD27
  U7C1   BG26  RSVD<27>  LBG_CORE_QAT_EXT_D  I34

TP_PCH_RSVD28   @BASEBOARD_FAB2_LIB.BASEBOARD_FAB2(SCH_1):TP_PCH_RSVD28
  U7C1   R35  RSVD<28>  LBG_CORE_QAT_EXT_D  I63

TP_PCH_RSVD29   @BASEBOARD_FAB2_LIB.BASEBOARD_FAB2(SCH_1):TP_PCH_RSVD29
  U7C1   P33  RSVD<29>  LBG_CORE_QAT_EXT_D  I63

TP_PCH_RSVD30   @BASEBOARD_FAB2_LIB.BASEBOARD_FAB2(SCH_1):TP_PCH_RSVD30
  U7C1   R31  RSVD<30>  LBG_CORE_QAT_EXT_D  I63

TP_PCH_RSVD31   @BASEBOARD_FAB2_LIB.BASEBOARD_FAB2(SCH_1):TP_PCH_RSVD31
  U7C1   P29  RSVD<31>  LBG_CORE_QAT_EXT_D  I63

TP_PCH_RSVD32   @BASEBOARD_FAB2_LIB.BASEBOARD_FAB2(SCH_1):TP_PCH_RSVD32
  U7C1   AA54  RSVD<32>  LBG_CORE_QAT_EXT_D  I73

TP_PCH_RSVD33   @BASEBOARD_FAB2_LIB.BASEBOARD_FAB2(SCH_1):TP_PCH_RSVD33
  U7C1   V56  RSVD<33>  LBG_CORE_QAT_EXT_D  I73

TP_PCH_RSVD34   @BASEBOARD_FAB2_LIB.BASEBOARD_FAB2(SCH_1):TP_PCH_RSVD34
  U7C1   Y56  RSVD<34>  LBG_CORE_QAT_EXT_D  I73

TP_PCH_RSVD35   @BASEBOARD_FAB2_LIB.BASEBOARD_FAB2(SCH_1):TP_PCH_RSVD35
  U7C1   W54  RSVD<35>  LBG_CORE_QAT_EXT_D  I73

TP_PCH_RSVD36   @BASEBOARD_FAB2_LIB.BASEBOARD_FAB2(SCH_1):TP_PCH_RSVD36
  U7C1   AK54  RSVD<36>  LBG_CORE_QAT_EXT_D  I73

TP_PCH_RSVD37   @BASEBOARD_FAB2_LIB.BASEBOARD_FAB2(SCH_1):TP_PCH_RSVD37
  U7C1   BN29  RSVD<37>  LBG_CORE_QAT_EXT_D  I73

TP_PCH_RSVD38   @BASEBOARD_FAB2_LIB.BASEBOARD_FAB2(SCH_1):TP_PCH_RSVD38
  U7C1   BL29  RSVD<38>  LBG_CORE_QAT_EXT_D  I73

TP_PCH_RSVD41   @BASEBOARD_FAB2_LIB.BASEBOARD_FAB2(SCH_1):TP_PCH_RSVD41
  U7C1   BJ40  RSVD<41>  LBG_CORE_QAT_EXT_D  I73

TP_PCH_RSVD42   @BASEBOARD_FAB2_LIB.BASEBOARD_FAB2(SCH_1):TP_PCH_RSVD42
  U7C1   BG40  RSVD<42>  LBG_CORE_QAT_EXT_D  I73

TP_PCH_RSVD45   @BASEBOARD_FAB2_LIB.BASEBOARD_FAB2(SCH_1):TP_PCH_RSVD45
  U7C1   P22  RSVD<45>  LBG_CORE_QAT_EXT_D  I73

TP_PCH_RSVD46   @BASEBOARD_FAB2_LIB.BASEBOARD_FAB2(SCH_1):TP_PCH_RSVD46
  U7C1   BW3  RSVD<46>  LBG_CORE_QAT_EXT_D  I34

TP_PCH_RSVD47   @BASEBOARD_FAB2_LIB.BASEBOARD_FAB2(SCH_1):TP_PCH_RSVD47
  U7C1   AP69  RSVD<47>  LBG_CORE_QAT_EXT_D  I220

TP_PCH_RSVD48   @BASEBOARD_FAB2_LIB.BASEBOARD_FAB2(SCH_1):TP_PCH_RSVD48
  U7C1   AP71  RSVD<48>  LBG_CORE_QAT_EXT_D  I220

TP_PCH_RSVD49   @BASEBOARD_FAB2_LIB.BASEBOARD_FAB2(SCH_1):TP_PCH_RSVD49
  U7C1   G67  RSVD<49>  LBG_CORE_QAT_EXT_D  I220

TP_PCH_RSVD50   @BASEBOARD_FAB2_LIB.BASEBOARD_FAB2(SCH_1):TP_PCH_RSVD50
  U7C1   H69  RSVD<50>  LBG_CORE_QAT_EXT_D  I220

TP_PCH_RSVD51   @BASEBOARD_FAB2_LIB.BASEBOARD_FAB2(SCH_1):TP_PCH_RSVD51
  U7C1   AA69  RSVD<51>  LBG_CORE_QAT_EXT_D  I220

TP_PCH_RSVD52   @BASEBOARD_FAB2_LIB.BASEBOARD_FAB2(SCH_1):TP_PCH_RSVD52
  U7C1   AA71  RSVD<52>  LBG_CORE_QAT_EXT_D  I220

TP_PCH_RSVD53   @BASEBOARD_FAB2_LIB.BASEBOARD_FAB2(SCH_1):TP_PCH_RSVD53
  U7C1   P26  RSVD<53>  LBG_CORE_QAT_EXT_D  I73

TP_PCH_RSVD54   @BASEBOARD_FAB2_LIB.BASEBOARD_FAB2(SCH_1):TP_PCH_RSVD54
  U7C1   R24  RSVD<54>  LBG_CORE_QAT_EXT_D  I73

TP_PCH_RSVD55   @BASEBOARD_FAB2_LIB.BASEBOARD_FAB2(SCH_1):TP_PCH_RSVD55
  U7C1   BN68  RSVD<55>  LBG_CORE_QAT_EXT_D  I74

TP_PCH_RSVD58   @BASEBOARD_FAB2_LIB.BASEBOARD_FAB2(SCH_1):TP_PCH_RSVD58
  U7C1   AP27  RSVD<58>  LBG_CORE_QAT_EXT_D  I63

TP_PCH_RSVD59   @BASEBOARD_FAB2_LIB.BASEBOARD_FAB2(SCH_1):TP_PCH_RSVD59
  U7C1   AT27  RSVD<59>  LBG_CORE_QAT_EXT_D  I63

TP_PCH_RSVD64   @BASEBOARD_FAB2_LIB.BASEBOARD_FAB2(SCH_1):TP_PCH_RSVD64
  U7C1   C26  RSVD<64>  LBG_CORE_QAT_EXT_D  I40

TP_PCH_RSVD65   @BASEBOARD_FAB2_LIB.BASEBOARD_FAB2(SCH_1):TP_PCH_RSVD65
  U7C1   A26  RSVD<65>  LBG_CORE_QAT_EXT_D  I40

TP_PI7C9X1172_EN485_N   @BASEBOARD_FAB2_LIB.BASEBOARD_FAB2(SCH_1):TP_PI7C9X1172_EN485_N
  EU9F3   19  EN485_N  PI7C9X1172_QFN   I1

TP_PI7C9X1172_ENIR_N   @BASEBOARD_FAB2_LIB.BASEBOARD_FAB2(SCH_1):TP_PI7C9X1172_ENIR_N
  EU9F3   18  ENIR_N  PI7C9X1172_QFN   I1

TP_PI7C9X1172_RTSA_N   @BASEBOARD_FAB2_LIB.BASEBOARD_FAB2(SCH_1):TP_PI7C9X1172_RTSA_N
  EU9F3   21  RTSA_N  PI7C9X1172_QFN   I1

TP_PI7C9X1172_RTSB_N   @BASEBOARD_FAB2_LIB.BASEBOARD_FAB2(SCH_1):TP_PI7C9X1172_RTSB_N
  EU9F3   15  RTSB_N  PI7C9X1172_QFN   I1

TP_PI7C9X1172_SO   @BASEBOARD_FAB2_LIB.BASEBOARD_FAB2(SCH_1):TP_PI7C9X1172_SO
  EU9F3    2     SO  PI7C9X1172_QFN   I1

TP_PLTRST_CPU_N   @BASEBOARD_FAB2_LIB.BASEBOARD_FAB2(SCH_1):TP_PLTRST_CPU_N
  U7C1   U17  PLTRST_CPU_N  LBG_CORE_QAT_EXT_D  I73

TP_PM_SYNC_GTL   @BASEBOARD_FAB2_LIB.BASEBOARD_FAB2(SCH_1):TP_PM_SYNC_GTL
  U7C1    V7  PM_SYNC2  LBG_CORE_QAT_EXT_D  I73

TP_PVCCINC_CPU1_PH1_GL_0   @BASEBOARD_FAB2_LIB.BASEBOARD_FAB2(SCH_1):TP_PVCCINC_CPU1_PH1_GL_0
  EU1E2    6  GL<0>  IR354XX_SM  I20

TP_PVCCINC_CPU1_PH1_GL_1   @BASEBOARD_FAB2_LIB.BASEBOARD_FAB2(SCH_1):TP_PVCCINC_CPU1_PH1_GL_1
  EU1E2   41  GL<1>  IR354XX_SM  I20

TP_PVCCINC_CPU1_PH2_GL_0   @BASEBOARD_FAB2_LIB.BASEBOARD_FAB2(SCH_1):TP_PVCCINC_CPU1_PH2_GL_0
  EU1D4    6  GL<0>  IR354XX_SM  I24

TP_PVCCINC_CPU1_PH2_GL_1   @BASEBOARD_FAB2_LIB.BASEBOARD_FAB2(SCH_1):TP_PVCCINC_CPU1_PH2_GL_1
  EU1D4   41  GL<1>  IR354XX_SM  I24

TP_PVCCIN_CPU0_AIREF6   @BASEBOARD_FAB2_LIB.BASEBOARD_FAB2(SCH_1):TP_PVCCIN_CPU0_AIREF6
  EU4D4   33  AIREF6  PXE1610B_QFN  I155

TP_PVCCIN_CPU0_AISEN6   @BASEBOARD_FAB2_LIB.BASEBOARD_FAB2(SCH_1):TP_PVCCIN_CPU0_AISEN6
  EU4D4   34  AISEN6  PXE1610B_QFN  I155

TP_PVCCIN_CPU0_APWM6   @BASEBOARD_FAB2_LIB.BASEBOARD_FAB2(SCH_1):TP_PVCCIN_CPU0_APWM6
  EU4D4    2  APWM6  PXE1610B_QFN  I155

TP_PVCCIN_CPU0_FAULT1_20   @BASEBOARD_FAB2_LIB.BASEBOARD_FAB2(SCH_1):TP_PVCCIN_CPU0_FAULT1_20
  EU4D4   40    MP4  PXE1610B_QFN  I155

TP_PVCCIN_CPU0_GP1   @BASEBOARD_FAB2_LIB.BASEBOARD_FAB2(SCH_1):TP_PVCCIN_CPU0_GP1
  EU4D4   16    MP1  PXE1610B_QFN  I155

TP_PVCCIN_CPU0_PH1_GL_0   @BASEBOARD_FAB2_LIB.BASEBOARD_FAB2(SCH_1):TP_PVCCIN_CPU0_PH1_GL_0
  EU4E1    6  GL<0>  IR354XX_SM  I63

TP_PVCCIN_CPU0_PH1_GL_1   @BASEBOARD_FAB2_LIB.BASEBOARD_FAB2(SCH_1):TP_PVCCIN_CPU0_PH1_GL_1
  EU4E1   41  GL<1>  IR354XX_SM  I63

TP_PVCCIN_CPU0_PH2_GL_0   @BASEBOARD_FAB2_LIB.BASEBOARD_FAB2(SCH_1):TP_PVCCIN_CPU0_PH2_GL_0
  EU4D6    6  GL<0>  IR354XX_SM  I64

TP_PVCCIN_CPU0_PH2_GL_1   @BASEBOARD_FAB2_LIB.BASEBOARD_FAB2(SCH_1):TP_PVCCIN_CPU0_PH2_GL_1
  EU4D6   41  GL<1>  IR354XX_SM  I64

TP_PVCCIN_CPU0_PH3_GL_0   @BASEBOARD_FAB2_LIB.BASEBOARD_FAB2(SCH_1):TP_PVCCIN_CPU0_PH3_GL_0
  EU4D3    6  GL<0>  IR354XX_SM  I70

TP_PVCCIN_CPU0_PH3_GL_1   @BASEBOARD_FAB2_LIB.BASEBOARD_FAB2(SCH_1):TP_PVCCIN_CPU0_PH3_GL_1
  EU4D3   41  GL<1>  IR354XX_SM  I70

TP_PVCCIN_CPU0_PH4_GL_0   @BASEBOARD_FAB2_LIB.BASEBOARD_FAB2(SCH_1):TP_PVCCIN_CPU0_PH4_GL_0
  EU4D1    6  GL<0>  IR354XX_SM  I71

TP_PVCCIN_CPU0_PH4_GL_1   @BASEBOARD_FAB2_LIB.BASEBOARD_FAB2(SCH_1):TP_PVCCIN_CPU0_PH4_GL_1
  EU4D1   41  GL<1>  IR354XX_SM  I71

TP_PVCCIN_CPU0_PH5_GL_0   @BASEBOARD_FAB2_LIB.BASEBOARD_FAB2(SCH_1):TP_PVCCIN_CPU0_PH5_GL_0
  EU4C2    6  GL<0>  IR354XX_SM  I71

TP_PVCCIN_CPU0_PH5_GL_1   @BASEBOARD_FAB2_LIB.BASEBOARD_FAB2(SCH_1):TP_PVCCIN_CPU0_PH5_GL_1
  EU4C2   41  GL<1>  IR354XX_SM  I71

TP_PVCCIN_CPU0_RESET   @BASEBOARD_FAB2_LIB.BASEBOARD_FAB2(SCH_1):TP_PVCCIN_CPU0_RESET
  EU4D4   10  RESET_N  PXE1610B_QFN  I155

TP_PVCCIN_CPU1_AIREF6   @BASEBOARD_FAB2_LIB.BASEBOARD_FAB2(SCH_1):TP_PVCCIN_CPU1_AIREF6
  EU1C2   33  AIREF6  PXE1610B_QFN  I130

TP_PVCCIN_CPU1_AISEN6   @BASEBOARD_FAB2_LIB.BASEBOARD_FAB2(SCH_1):TP_PVCCIN_CPU1_AISEN6
  EU1C2   34  AISEN6  PXE1610B_QFN  I130

TP_PVCCIN_CPU1_APWM6   @BASEBOARD_FAB2_LIB.BASEBOARD_FAB2(SCH_1):TP_PVCCIN_CPU1_APWM6
  EU1C2    2  APWM6  PXE1610B_QFN  I130

TP_PVCCIN_CPU1_FAULT1_20   @BASEBOARD_FAB2_LIB.BASEBOARD_FAB2(SCH_1):TP_PVCCIN_CPU1_FAULT1_20
  EU1C2   40    MP4  PXE1610B_QFN  I130

TP_PVCCIN_CPU1_GP1   @BASEBOARD_FAB2_LIB.BASEBOARD_FAB2(SCH_1):TP_PVCCIN_CPU1_GP1
  EU1C2   16    MP1  PXE1610B_QFN  I130

TP_PVCCIN_CPU1_PH3_GL_0   @BASEBOARD_FAB2_LIB.BASEBOARD_FAB2(SCH_1):TP_PVCCIN_CPU1_PH3_GL_0
  EU1D3    6  GL<0>  IR354XX_SM  I27

TP_PVCCIN_CPU1_PH3_GL_1   @BASEBOARD_FAB2_LIB.BASEBOARD_FAB2(SCH_1):TP_PVCCIN_CPU1_PH3_GL_1
  EU1D3   41  GL<1>  IR354XX_SM  I27

TP_PVCCIN_CPU1_PH4_GL_0   @BASEBOARD_FAB2_LIB.BASEBOARD_FAB2(SCH_1):TP_PVCCIN_CPU1_PH4_GL_0
  EU1D1    6  GL<0>  IR354XX_SM  I71

TP_PVCCIN_CPU1_PH4_GL_1   @BASEBOARD_FAB2_LIB.BASEBOARD_FAB2(SCH_1):TP_PVCCIN_CPU1_PH4_GL_1
  EU1D1   41  GL<1>  IR354XX_SM  I71

TP_PVCCIN_CPU1_PH5_GL_0   @BASEBOARD_FAB2_LIB.BASEBOARD_FAB2(SCH_1):TP_PVCCIN_CPU1_PH5_GL_0
  EU1C3    6  GL<0>  IR354XX_SM  I56

TP_PVCCIN_CPU1_PH5_GL_1   @BASEBOARD_FAB2_LIB.BASEBOARD_FAB2(SCH_1):TP_PVCCIN_CPU1_PH5_GL_1
  EU1C3   41  GL<1>  IR354XX_SM  I56

TP_PVCCIN_CPU1_RESET_N   @BASEBOARD_FAB2_LIB.BASEBOARD_FAB2(SCH_1):TP_PVCCIN_CPU1_RESET_N
  EU1C2   10  RESET_N  PXE1610B_QFN  I130

TP_PVCCIO_CPU0_BIREF1   @BASEBOARD_FAB2_LIB.BASEBOARD_FAB2(SCH_1):TP_PVCCIO_CPU0_BIREF1
  EU3P1   25  BIREF1  PXE1110B_QFN  I93

TP_PVCCIO_CPU0_BPWM1   @BASEBOARD_FAB2_LIB.BASEBOARD_FAB2(SCH_1):TP_PVCCIO_CPU0_BPWM1
  EU3P1    3  BPWM1  PXE1110B_QFN  I93

TP_PVCCIO_CPU0_BTSEN   @BASEBOARD_FAB2_LIB.BASEBOARD_FAB2(SCH_1):TP_PVCCIO_CPU0_BTSEN
  EU3P1   34  BTSEN  PXE1110B_QFN  I93

TP_PVCCIO_CPU0_BVREF   @BASEBOARD_FAB2_LIB.BASEBOARD_FAB2(SCH_1):TP_PVCCIO_CPU0_BVREF
  EU3P1   30  BVREF  PXE1110B_QFN  I93

TP_PVCCIO_CPU0_BVSEN   @BASEBOARD_FAB2_LIB.BASEBOARD_FAB2(SCH_1):TP_PVCCIO_CPU0_BVSEN
  EU3P1   29  BVSEN  PXE1110B_QFN  I93

TP_PVCCIO_CPU0_GL_0   @BASEBOARD_FAB2_LIB.BASEBOARD_FAB2(SCH_1):TP_PVCCIO_CPU0_GL_0
  EU7C1    6  GL<0>  IR354XX_SM  I101

TP_PVCCIO_CPU0_GL_1   @BASEBOARD_FAB2_LIB.BASEBOARD_FAB2(SCH_1):TP_PVCCIO_CPU0_GL_1
  EU7C1   41  GL<1>  IR354XX_SM  I101

TP_PVCCIO_CPU0_PINALRT_N   @BASEBOARD_FAB2_LIB.BASEBOARD_FAB2(SCH_1):TP_PVCCIO_CPU0_PINALRT_N
  EU3P1   12  PINALRT_N  PXE1110B_QFN  I93

TP_PVCCIO_CPU0_RESET_N   @BASEBOARD_FAB2_LIB.BASEBOARD_FAB2(SCH_1):TP_PVCCIO_CPU0_RESET_N
  EU3P1    8  RESET_N  PXE1110B_QFN  I93

TP_PVCCIO_CPU1_BIREF1   @BASEBOARD_FAB2_LIB.BASEBOARD_FAB2(SCH_1):TP_PVCCIO_CPU1_BIREF1
  EU4D5   25  BIREF1  PXE1110B_QFN  I96

TP_PVCCIO_CPU1_BPWM1   @BASEBOARD_FAB2_LIB.BASEBOARD_FAB2(SCH_1):TP_PVCCIO_CPU1_BPWM1
  EU4D5    3  BPWM1  PXE1110B_QFN  I96

TP_PVCCIO_CPU1_BTSEN   @BASEBOARD_FAB2_LIB.BASEBOARD_FAB2(SCH_1):TP_PVCCIO_CPU1_BTSEN
  EU4D5   34  BTSEN  PXE1110B_QFN  I96

TP_PVCCIO_CPU1_BVREF   @BASEBOARD_FAB2_LIB.BASEBOARD_FAB2(SCH_1):TP_PVCCIO_CPU1_BVREF
  EU4D5   30  BVREF  PXE1110B_QFN  I96

TP_PVCCIO_CPU1_BVSEN   @BASEBOARD_FAB2_LIB.BASEBOARD_FAB2(SCH_1):TP_PVCCIO_CPU1_BVSEN
  EU4D5   29  BVSEN  PXE1110B_QFN  I96

TP_PVCCIO_CPU1_GL_0   @BASEBOARD_FAB2_LIB.BASEBOARD_FAB2(SCH_1):TP_PVCCIO_CPU1_GL_0
  EU4E2    6  GL<0>  IR354XX_SM  I126

TP_PVCCIO_CPU1_GL_1   @BASEBOARD_FAB2_LIB.BASEBOARD_FAB2(SCH_1):TP_PVCCIO_CPU1_GL_1
  EU4E2   41  GL<1>  IR354XX_SM  I126

TP_PVCCIO_CPU1_PINALRT_N   @BASEBOARD_FAB2_LIB.BASEBOARD_FAB2(SCH_1):TP_PVCCIO_CPU1_PINALRT_N
  EU4D5   12  PINALRT_N  PXE1110B_QFN  I96

TP_PVCCIO_CPU1_RESET_N   @BASEBOARD_FAB2_LIB.BASEBOARD_FAB2(SCH_1):TP_PVCCIO_CPU1_RESET_N
  EU4D5    8  RESET_N  PXE1110B_QFN  I96

TP_PVDDQ_ABC_BPWM1   @BASEBOARD_FAB2_LIB.BASEBOARD_FAB2(SCH_1):TP_PVDDQ_ABC_BPWM1
  EU7G1    1  BPWM1  PXM1310B_QFN  I358

TP_PVDDQ_ABC_BREF1   @BASEBOARD_FAB2_LIB.BASEBOARD_FAB2(SCH_1):TP_PVDDQ_ABC_BREF1
  EU7G1   31  BIREF1  PXM1310B_QFN  I358

TP_PVDDQ_ABC_BTSEN   @BASEBOARD_FAB2_LIB.BASEBOARD_FAB2(SCH_1):TP_PVDDQ_ABC_BTSEN
  EU7G1   34  BTSEN  PXM1310B_QFN  I358

TP_PVDDQ_ABC_BVREF   @BASEBOARD_FAB2_LIB.BASEBOARD_FAB2(SCH_1):TP_PVDDQ_ABC_BVREF
  EU7G1   30  BVREF  PXM1310B_QFN  I358

TP_PVDDQ_ABC_BVSEN   @BASEBOARD_FAB2_LIB.BASEBOARD_FAB2(SCH_1):TP_PVDDQ_ABC_BVSEN
  EU7G1   29  BVSEN  PXM1310B_QFN  I358

TP_PVDDQ_ABC_MP1   @BASEBOARD_FAB2_LIB.BASEBOARD_FAB2(SCH_1):TP_PVDDQ_ABC_MP1
  EU7G1   14    MP1  PXM1310B_QFN  I358

TP_PVDDQ_ABC_MP2   @BASEBOARD_FAB2_LIB.BASEBOARD_FAB2(SCH_1):TP_PVDDQ_ABC_MP2
  EU7G1   18    MP2  PXM1310B_QFN  I358

TP_PVDDQ_ABC_PH1_GL_0   @BASEBOARD_FAB2_LIB.BASEBOARD_FAB2(SCH_1):TP_PVDDQ_ABC_PH1_GL_0
  EU7G2    6  GL<0>  IR354XX_SM  I102

TP_PVDDQ_ABC_PH1_GL_1   @BASEBOARD_FAB2_LIB.BASEBOARD_FAB2(SCH_1):TP_PVDDQ_ABC_PH1_GL_1
  EU7G2   41  GL<1>  IR354XX_SM  I102

TP_PVDDQ_ABC_PH2_GL_0   @BASEBOARD_FAB2_LIB.BASEBOARD_FAB2(SCH_1):TP_PVDDQ_ABC_PH2_GL_0
  EU7G3    6  GL<0>  IR354XX_SM  I103

TP_PVDDQ_ABC_PH2_GL_1   @BASEBOARD_FAB2_LIB.BASEBOARD_FAB2(SCH_1):TP_PVDDQ_ABC_PH2_GL_1
  EU7G3   41  GL<1>  IR354XX_SM  I103

TP_PVDDQ_ABC_PH3_IMON   @BASEBOARD_FAB2_LIB.BASEBOARD_FAB2(SCH_1):TP_PVDDQ_ABC_PH3_IMON
  EU7G1   26  AISEN3  PXM1310B_QFN  I358

TP_PVDDQ_ABC_PH3_IMON_REF   @BASEBOARD_FAB2_LIB.BASEBOARD_FAB2(SCH_1):TP_PVDDQ_ABC_PH3_IMON_REF
  EU7G1   25  AIREF3  PXM1310B_QFN  I358

TP_PVDDQ_ABC_PINALRT_N   @BASEBOARD_FAB2_LIB.BASEBOARD_FAB2(SCH_1):TP_PVDDQ_ABC_PINALRT_N
  EU7G1   12  PINALRT_N  PXM1310B_QFN  I358

TP_PVDDQ_ABC_PWM3   @BASEBOARD_FAB2_LIB.BASEBOARD_FAB2(SCH_1):TP_PVDDQ_ABC_PWM3
  EU7G1    3  APWM3  PXM1310B_QFN  I358

TP_PVDDQ_ABC_RESET_N   @BASEBOARD_FAB2_LIB.BASEBOARD_FAB2(SCH_1):TP_PVDDQ_ABC_RESET_N
  EU7G1    8  RESET_N  PXM1310B_QFN  I358

TP_PVDDQ_DEF_BPWM1   @BASEBOARD_FAB2_LIB.BASEBOARD_FAB2(SCH_1):TP_PVDDQ_DEF_BPWM1
  EU7A5    1  BPWM1  PXM1310B_QFN  I75

TP_PVDDQ_DEF_BREF1   @BASEBOARD_FAB2_LIB.BASEBOARD_FAB2(SCH_1):TP_PVDDQ_DEF_BREF1
  EU7A5   31  BIREF1  PXM1310B_QFN  I75

TP_PVDDQ_DEF_BTSEN   @BASEBOARD_FAB2_LIB.BASEBOARD_FAB2(SCH_1):TP_PVDDQ_DEF_BTSEN
  EU7A5   34  BTSEN  PXM1310B_QFN  I75

TP_PVDDQ_DEF_BVREF   @BASEBOARD_FAB2_LIB.BASEBOARD_FAB2(SCH_1):TP_PVDDQ_DEF_BVREF
  EU7A5   30  BVREF  PXM1310B_QFN  I75

TP_PVDDQ_DEF_BVSEN   @BASEBOARD_FAB2_LIB.BASEBOARD_FAB2(SCH_1):TP_PVDDQ_DEF_BVSEN
  EU7A5   29  BVSEN  PXM1310B_QFN  I75

TP_PVDDQ_DEF_MP1   @BASEBOARD_FAB2_LIB.BASEBOARD_FAB2(SCH_1):TP_PVDDQ_DEF_MP1
  EU7A5   14    MP1  PXM1310B_QFN  I75

TP_PVDDQ_DEF_MP2   @BASEBOARD_FAB2_LIB.BASEBOARD_FAB2(SCH_1):TP_PVDDQ_DEF_MP2
  EU7A5   18    MP2  PXM1310B_QFN  I75

TP_PVDDQ_DEF_PH1_GL_0   @BASEBOARD_FAB2_LIB.BASEBOARD_FAB2(SCH_1):TP_PVDDQ_DEF_PH1_GL_0
  EU7A1    6  GL<0>  IR354XX_SM  I106

TP_PVDDQ_DEF_PH1_GL_1   @BASEBOARD_FAB2_LIB.BASEBOARD_FAB2(SCH_1):TP_PVDDQ_DEF_PH1_GL_1
  EU7A1   41  GL<1>  IR354XX_SM  I106

TP_PVDDQ_DEF_PH2_GL_0   @BASEBOARD_FAB2_LIB.BASEBOARD_FAB2(SCH_1):TP_PVDDQ_DEF_PH2_GL_0
  EU7A4    6  GL<0>  IR354XX_SM  I107

TP_PVDDQ_DEF_PH2_GL_1   @BASEBOARD_FAB2_LIB.BASEBOARD_FAB2(SCH_1):TP_PVDDQ_DEF_PH2_GL_1
  EU7A4   41  GL<1>  IR354XX_SM  I107

TP_PVDDQ_DEF_PH3_IMON   @BASEBOARD_FAB2_LIB.BASEBOARD_FAB2(SCH_1):TP_PVDDQ_DEF_PH3_IMON
  EU7A5   26  AISEN3  PXM1310B_QFN  I75

TP_PVDDQ_DEF_PH3_IMON_REF   @BASEBOARD_FAB2_LIB.BASEBOARD_FAB2(SCH_1):TP_PVDDQ_DEF_PH3_IMON_REF
  EU7A5   25  AIREF3  PXM1310B_QFN  I75

TP_PVDDQ_DEF_PINALRT_N   @BASEBOARD_FAB2_LIB.BASEBOARD_FAB2(SCH_1):TP_PVDDQ_DEF_PINALRT_N
  EU7A5   12  PINALRT_N  PXM1310B_QFN  I75

TP_PVDDQ_DEF_PWM3   @BASEBOARD_FAB2_LIB.BASEBOARD_FAB2(SCH_1):TP_PVDDQ_DEF_PWM3
  EU7A5    3  APWM3  PXM1310B_QFN  I75

TP_PVDDQ_DEF_RESET_N   @BASEBOARD_FAB2_LIB.BASEBOARD_FAB2(SCH_1):TP_PVDDQ_DEF_RESET_N
  EU7A5    8  RESET_N  PXM1310B_QFN  I75

TP_PVDDQ_GHJ_BPWM1   @BASEBOARD_FAB2_LIB.BASEBOARD_FAB2(SCH_1):TP_PVDDQ_GHJ_BPWM1
  EU1G2    1  BPWM1  PXM1310B_QFN  I90

TP_PVDDQ_GHJ_BREF1   @BASEBOARD_FAB2_LIB.BASEBOARD_FAB2(SCH_1):TP_PVDDQ_GHJ_BREF1
  EU1G2   31  BIREF1  PXM1310B_QFN  I90

TP_PVDDQ_GHJ_BTSEN   @BASEBOARD_FAB2_LIB.BASEBOARD_FAB2(SCH_1):TP_PVDDQ_GHJ_BTSEN
  EU1G2   34  BTSEN  PXM1310B_QFN  I90

TP_PVDDQ_GHJ_BVREF   @BASEBOARD_FAB2_LIB.BASEBOARD_FAB2(SCH_1):TP_PVDDQ_GHJ_BVREF
  EU1G2   30  BVREF  PXM1310B_QFN  I90

TP_PVDDQ_GHJ_BVSEN   @BASEBOARD_FAB2_LIB.BASEBOARD_FAB2(SCH_1):TP_PVDDQ_GHJ_BVSEN
  EU1G2   29  BVSEN  PXM1310B_QFN  I90

TP_PVDDQ_GHJ_MP1   @BASEBOARD_FAB2_LIB.BASEBOARD_FAB2(SCH_1):TP_PVDDQ_GHJ_MP1
  EU1G2   14    MP1  PXM1310B_QFN  I90

TP_PVDDQ_GHJ_MP2   @BASEBOARD_FAB2_LIB.BASEBOARD_FAB2(SCH_1):TP_PVDDQ_GHJ_MP2
  EU1G2   18    MP2  PXM1310B_QFN  I90

TP_PVDDQ_GHJ_PH1_GL_0   @BASEBOARD_FAB2_LIB.BASEBOARD_FAB2(SCH_1):TP_PVDDQ_GHJ_PH1_GL_0
  EU1G1    6  GL<0>  IR354XX_SM  I110

TP_PVDDQ_GHJ_PH1_GL_1   @BASEBOARD_FAB2_LIB.BASEBOARD_FAB2(SCH_1):TP_PVDDQ_GHJ_PH1_GL_1
  EU1G1   41  GL<1>  IR354XX_SM  I110

TP_PVDDQ_GHJ_PH2_GL_0   @BASEBOARD_FAB2_LIB.BASEBOARD_FAB2(SCH_1):TP_PVDDQ_GHJ_PH2_GL_0
  EU1F1    6  GL<0>  IR354XX_SM  I111

TP_PVDDQ_GHJ_PH2_GL_1   @BASEBOARD_FAB2_LIB.BASEBOARD_FAB2(SCH_1):TP_PVDDQ_GHJ_PH2_GL_1
  EU1F1   41  GL<1>  IR354XX_SM  I111

TP_PVDDQ_GHJ_PH3_IMON   @BASEBOARD_FAB2_LIB.BASEBOARD_FAB2(SCH_1):TP_PVDDQ_GHJ_PH3_IMON
  EU1G2   26  AISEN3  PXM1310B_QFN  I90

TP_PVDDQ_GHJ_PH3_IMON_REF   @BASEBOARD_FAB2_LIB.BASEBOARD_FAB2(SCH_1):TP_PVDDQ_GHJ_PH3_IMON_REF
  EU1G2   25  AIREF3  PXM1310B_QFN  I90

TP_PVDDQ_GHJ_PWM3   @BASEBOARD_FAB2_LIB.BASEBOARD_FAB2(SCH_1):TP_PVDDQ_GHJ_PWM3
  EU1G2    3  APWM3  PXM1310B_QFN  I90

TP_PVDDQ_GHJ_RESET_N   @BASEBOARD_FAB2_LIB.BASEBOARD_FAB2(SCH_1):TP_PVDDQ_GHJ_RESET_N
  EU1G2    8  RESET_N  PXM1310B_QFN  I90

TP_PVDDQ_KLM_BPWM1   @BASEBOARD_FAB2_LIB.BASEBOARD_FAB2(SCH_1):TP_PVDDQ_KLM_BPWM1
  EU1B1    1  BPWM1  PXM1310B_QFN  I90

TP_PVDDQ_KLM_BREF1   @BASEBOARD_FAB2_LIB.BASEBOARD_FAB2(SCH_1):TP_PVDDQ_KLM_BREF1
  EU1B1   31  BIREF1  PXM1310B_QFN  I90

TP_PVDDQ_KLM_BTSEN   @BASEBOARD_FAB2_LIB.BASEBOARD_FAB2(SCH_1):TP_PVDDQ_KLM_BTSEN
  EU1B1   34  BTSEN  PXM1310B_QFN  I90

TP_PVDDQ_KLM_BVREF   @BASEBOARD_FAB2_LIB.BASEBOARD_FAB2(SCH_1):TP_PVDDQ_KLM_BVREF
  EU1B1   30  BVREF  PXM1310B_QFN  I90

TP_PVDDQ_KLM_BVSEN   @BASEBOARD_FAB2_LIB.BASEBOARD_FAB2(SCH_1):TP_PVDDQ_KLM_BVSEN
  EU1B1   29  BVSEN  PXM1310B_QFN  I90

TP_PVDDQ_KLM_PH1_GL_0   @BASEBOARD_FAB2_LIB.BASEBOARD_FAB2(SCH_1):TP_PVDDQ_KLM_PH1_GL_0
  EU1A2    6  GL<0>  IR354XX_SM  I101

TP_PVDDQ_KLM_PH1_GL_1   @BASEBOARD_FAB2_LIB.BASEBOARD_FAB2(SCH_1):TP_PVDDQ_KLM_PH1_GL_1
  EU1A2   41  GL<1>  IR354XX_SM  I101

TP_PVDDQ_KLM_PH2_GL_0   @BASEBOARD_FAB2_LIB.BASEBOARD_FAB2(SCH_1):TP_PVDDQ_KLM_PH2_GL_0
  EU1A1    6  GL<0>  IR354XX_SM  I102

TP_PVDDQ_KLM_PH2_GL_1   @BASEBOARD_FAB2_LIB.BASEBOARD_FAB2(SCH_1):TP_PVDDQ_KLM_PH2_GL_1
  EU1A1   41  GL<1>  IR354XX_SM  I102

TP_PVDDQ_KLM_PH3_IMON   @BASEBOARD_FAB2_LIB.BASEBOARD_FAB2(SCH_1):TP_PVDDQ_KLM_PH3_IMON
  EU1B1   26  AISEN3  PXM1310B_QFN  I90

TP_PVDDQ_KLM_PH3_IMON_REF   @BASEBOARD_FAB2_LIB.BASEBOARD_FAB2(SCH_1):TP_PVDDQ_KLM_PH3_IMON_REF
  EU1B1   25  AIREF3  PXM1310B_QFN  I90

TP_PVDDQ_KLM_RESET_N   @BASEBOARD_FAB2_LIB.BASEBOARD_FAB2(SCH_1):TP_PVDDQ_KLM_RESET_N
  EU1B1    8  RESET_N  PXM1310B_QFN  I90

TP_PVNN_PCH_GL_0   @BASEBOARD_FAB2_LIB.BASEBOARD_FAB2(SCH_1):TP_PVNN_PCH_GL_0
  EU7A3    6  GL<0>  IR354XX_SM  I116

TP_PVNN_PCH_GL_1   @BASEBOARD_FAB2_LIB.BASEBOARD_FAB2(SCH_1):TP_PVNN_PCH_GL_1
  EU7A3   41  GL<1>  IR354XX_SM  I116

TP_PVNN_PCH_MP2   @BASEBOARD_FAB2_LIB.BASEBOARD_FAB2(SCH_1):TP_PVNN_PCH_MP2
  EU8A1   18    MP2  PXE1110B_QFN  I229

TP_PVNN_PCH_MP3   @BASEBOARD_FAB2_LIB.BASEBOARD_FAB2(SCH_1):TP_PVNN_PCH_MP3
  EU8A1   31    MP3  PXE1110B_QFN  I229

TP_PVNN_PCH_PINALRT_N   @BASEBOARD_FAB2_LIB.BASEBOARD_FAB2(SCH_1):TP_PVNN_PCH_PINALRT_N
  EU8A1   12  PINALRT_N  PXE1110B_QFN  I229

TP_PVNN_PCH_RESET_N   @BASEBOARD_FAB2_LIB.BASEBOARD_FAB2(SCH_1):TP_PVNN_PCH_RESET_N
  EU8A1    8  RESET_N  PXE1110B_QFN  I229

TP_PVNN_PCH_SVID_ALERT   @BASEBOARD_FAB2_LIB.BASEBOARD_FAB2(SCH_1):TP_PVNN_PCH_SVID_ALERT
  EU8A1   17  VALRT_N  PXE1110B_QFN  I229

TP_PVNN_PCH_VCLK   @BASEBOARD_FAB2_LIB.BASEBOARD_FAB2(SCH_1):TP_PVNN_PCH_VCLK
  EU8A1   15   VCLK  PXE1110B_QFN  I229

TP_PVNN_PCH_VDIO   @BASEBOARD_FAB2_LIB.BASEBOARD_FAB2(SCH_1):TP_PVNN_PCH_VDIO
  EU8A1   16   VDIO  PXE1110B_QFN  I229

TP_PVSA_CPU0_GL_0   @BASEBOARD_FAB2_LIB.BASEBOARD_FAB2(SCH_1):TP_PVSA_CPU0_GL_0
  EU4C1    6  GL<0>  IR354XX_SM  I46

TP_PVSA_CPU0_GL_1   @BASEBOARD_FAB2_LIB.BASEBOARD_FAB2(SCH_1):TP_PVSA_CPU0_GL_1
  EU4C1   41  GL<1>  IR354XX_SM  I46

TP_PVSA_CPU1_GL_0   @BASEBOARD_FAB2_LIB.BASEBOARD_FAB2(SCH_1):TP_PVSA_CPU1_GL_0
  EU1C1    6  GL<0>  IR354XX_SM  I51

TP_PVSA_CPU1_GL_1   @BASEBOARD_FAB2_LIB.BASEBOARD_FAB2(SCH_1):TP_PVSA_CPU1_GL_1
  EU1C1   41  GL<1>  IR354XX_SM  I51

TP_RGMII1TXCTL_GPIOT1   @BASEBOARD_FAB2_LIB.BASEBOARD_FAB2(SCH_1):TP_RGMII1TXCTL_GPIOT1
  U9F4    E9  RGMII2TXCTL_GPIOT7  AST1250_BGA   I1

TP_RGMII1TXD2_GPIOT4   @BASEBOARD_FAB2_LIB.BASEBOARD_FAB2(SCH_1):TP_RGMII1TXD2_GPIOT4
  U9F4   C10  RGMII2TXD2_GPIOU2  AST1250_BGA   I1

TP_RGMII1TXD3_GPIOT5   @BASEBOARD_FAB2_LIB.BASEBOARD_FAB2(SCH_1):TP_RGMII1TXD3_GPIOT5
  U9F4   D10  RGMII2TXD3_GPIOU3  AST1250_BGA   I1

TP_RGMII2TXCTL_GPIOT7   @BASEBOARD_FAB2_LIB.BASEBOARD_FAB2(SCH_1):TP_RGMII2TXCTL_GPIOT7
  U9F4   B12  RGMII1TXCTL_GPIOT1  AST1250_BGA   I1

TP_RGMII2TXD2_GPIOT4   @BASEBOARD_FAB2_LIB.BASEBOARD_FAB2(SCH_1):TP_RGMII2TXD2_GPIOT4
  U9F4   E12  RGMII1TXD2_GPIOT4  AST1250_BGA   I1

TP_RGMII2TXD3_GPIOT5   @BASEBOARD_FAB2_LIB.BASEBOARD_FAB2(SCH_1):TP_RGMII2TXD3_GPIOT5
  U9F4   A13  RGMII1TXD3_GPIOT5  AST1250_BGA   I1

TP_RST_CPU1_CD_HFI0_N   @BASEBOARD_FAB2_LIB.BASEBOARD_FAB2(SCH_1):TP_RST_CPU1_CD_HFI0_N
  U2D1   BN24  CD_HFI0_RESET_N  SKX_EXT_B_BGA1  I23

TP_RST_RTCRST_N   @BASEBOARD_FAB2_LIB.BASEBOARD_FAB2(SCH_1):TP_RST_RTCRST_N
  J9G1     2    IO2  CONN12_C73564003  I128

TP_RSVD<0>      @BASEBOARD_FAB2_LIB.BASEBOARD_FAB2(SCH_1):TP_RSVD<0>
  J8E4    36   IO36  SCONN64_H87568002_A_SMT  I27

TP_RSVD_B1      @BASEBOARD_FAB2_LIB.BASEBOARD_FAB2(SCH_1):TP_RSVD_B1
  J8E3     6    IO6  SCONN80_E67482007_SM  I119

TP_SGPIO_SATA_CLOCK1_R   @BASEBOARD_FAB2_LIB.BASEBOARD_FAB2(SCH_1):TP_SGPIO_SATA_CLOCK1_R
  J8A1   2A2  SIDEBANDB_0  CONN72_G97614002_A_CP  I163

TP_SGPIO_SATA_DATA1_R   @BASEBOARD_FAB2_LIB.BASEBOARD_FAB2(SCH_1):TP_SGPIO_SATA_DATA1_R
  J8A1   2C1  SIDEBANDB_4  CONN72_G97614002_A_CP  I163

TP_SGPIO_SATA_LOAD1_R   @BASEBOARD_FAB2_LIB.BASEBOARD_FAB2(SCH_1):TP_SGPIO_SATA_LOAD1_R
  J8A1   2B2  SIDEBANDB_1  CONN72_G97614002_A_CP  I163

TP_SHARED_KR_MDC_0   @BASEBOARD_FAB2_LIB.BASEBOARD_FAB2(SCH_1):TP_SHARED_KR_MDC_0
  J8E4    49   IO49  SCONN64_H87568002_A_SMT  I27

TP_SHARED_KR_MDIO_0   @BASEBOARD_FAB2_LIB.BASEBOARD_FAB2(SCH_1):TP_SHARED_KR_MDIO_0
  J8E4    50   IO50  SCONN64_H87568002_A_SMT  I27

TP_SLG55021_P12V_FAN_8   @BASEBOARD_FAB2_LIB.BASEBOARD_FAB2(SCH_1):TP_SLG55021_P12V_FAN_8
  EU9M1    8     PG  SLG55021_SM  I69

TP_SLG55021_P12V_MAIN_8   @BASEBOARD_FAB2_LIB.BASEBOARD_FAB2(SCH_1):TP_SLG55021_P12V_MAIN_8
  EU7E1    8     PG  SLG55021_SM  I19

TP_SLG55021_P3V3_8   @BASEBOARD_FAB2_LIB.BASEBOARD_FAB2(SCH_1):TP_SLG55021_P3V3_8
  EU2T1    8     PG  SLG55021_SM   I1

TP_SLG55021_P5V_8   @BASEBOARD_FAB2_LIB.BASEBOARD_FAB2(SCH_1):TP_SLG55021_P5V_8
  EU8B1    8     PG  SLG55021_SM  I13

TP_SLP_LAN_N    @BASEBOARD_FAB2_LIB.BASEBOARD_FAB2(SCH_1):TP_SLP_LAN_N
  U7C1   M15  SLP_GBE_N  LBG_CORE_QAT_EXT_D  I73

TP_SMB_CPU1_CD_HFI0_I2CCLK   @BASEBOARD_FAB2_LIB.BASEBOARD_FAB2(SCH_1):TP_SMB_CPU1_CD_HFI0_I2CCLK
  U2D1   BN22  CD_HFI0_I2CCLK  SKX_EXT_B_BGA1  I23

TP_SMB_CPU1_CD_HFI0_I2CDAT   @BASEBOARD_FAB2_LIB.BASEBOARD_FAB2(SCH_1):TP_SMB_CPU1_CD_HFI0_I2CDAT
  U2D1   BP23  CD_HFI0_I2CDAT  SKX_EXT_B_BGA1  I23

TP_SMB_DDR_ABC_EN   @BASEBOARD_FAB2_LIB.BASEBOARD_FAB2(SCH_1):TP_SMB_DDR_ABC_EN
  U6F1     5     EN  PCA9617_SSOP  I15

TP_SMB_DDR_DEF_EN   @BASEBOARD_FAB2_LIB.BASEBOARD_FAB2(SCH_1):TP_SMB_DDR_DEF_EN
  U7E1     5     EN  PCA9617_SSOP  I61

TP_SMB_DDR_GHJ_EN   @BASEBOARD_FAB2_LIB.BASEBOARD_FAB2(SCH_1):TP_SMB_DDR_GHJ_EN
  U4G1     5     EN  PCA9617_SSOP  I63

TP_SMB_DDR_KLM_EN   @BASEBOARD_FAB2_LIB.BASEBOARD_FAB2(SCH_1):TP_SMB_DDR_KLM_EN
  U3B1     5     EN  PCA9617_SSOP  I75

TP_SMB_PEHPCPU1_EN   @BASEBOARD_FAB2_LIB.BASEBOARD_FAB2(SCH_1):TP_SMB_PEHPCPU1_EN
  U1B2     5     EN  PCA9517_SM   I1

TP_SPI_0_0      @BASEBOARD_FAB2_LIB.BASEBOARD_FAB2(SCH_1):TP_SPI_0_0
  U7F1    14  NC<0>  W25Q256_XSOI  I146

TP_SPI_0_1      @BASEBOARD_FAB2_LIB.BASEBOARD_FAB2(SCH_1):TP_SPI_0_1
  U7F1    13  NC<1>  W25Q256_XSOI  I146

TP_SPI_0_2      @BASEBOARD_FAB2_LIB.BASEBOARD_FAB2(SCH_1):TP_SPI_0_2
  U7F1    12  NC<2>  W25Q256_XSOI  I146

TP_SPI_0_3      @BASEBOARD_FAB2_LIB.BASEBOARD_FAB2(SCH_1):TP_SPI_0_3
  U7F1    11  NC<3>  W25Q256_XSOI  I146

TP_SPI_0_4      @BASEBOARD_FAB2_LIB.BASEBOARD_FAB2(SCH_1):TP_SPI_0_4
  U7F1     6  NC<4>  W25Q256_XSOI  I146

TP_SPI_0_5      @BASEBOARD_FAB2_LIB.BASEBOARD_FAB2(SCH_1):TP_SPI_0_5
  U7F1     5  NC<5>  W25Q256_XSOI  I146

TP_SPI_0_6      @BASEBOARD_FAB2_LIB.BASEBOARD_FAB2(SCH_1):TP_SPI_0_6
  U7F1     4  NC<6>  W25Q256_XSOI  I146

TP_SPI_1_0      @BASEBOARD_FAB2_LIB.BASEBOARD_FAB2(SCH_1):TP_SPI_1_0
  U3T1    14  NC<0>  W25Q256_XSOI  I165

TP_SPI_1_1      @BASEBOARD_FAB2_LIB.BASEBOARD_FAB2(SCH_1):TP_SPI_1_1
  U3T1    13  NC<1>  W25Q256_XSOI  I165

TP_SPI_1_2      @BASEBOARD_FAB2_LIB.BASEBOARD_FAB2(SCH_1):TP_SPI_1_2
  U3T1    12  NC<2>  W25Q256_XSOI  I165

TP_SPI_1_3      @BASEBOARD_FAB2_LIB.BASEBOARD_FAB2(SCH_1):TP_SPI_1_3
  U3T1    11  NC<3>  W25Q256_XSOI  I165

TP_SPI_1_4      @BASEBOARD_FAB2_LIB.BASEBOARD_FAB2(SCH_1):TP_SPI_1_4
  U3T1     6  NC<4>  W25Q256_XSOI  I165

TP_SPI_1_5      @BASEBOARD_FAB2_LIB.BASEBOARD_FAB2(SCH_1):TP_SPI_1_5
  U3T1     5  NC<5>  W25Q256_XSOI  I165

TP_SPI_1_6      @BASEBOARD_FAB2_LIB.BASEBOARD_FAB2(SCH_1):TP_SPI_1_6
  U3T1     4  NC<6>  W25Q256_XSOI  I165

TP_SPI_2_0      @BASEBOARD_FAB2_LIB.BASEBOARD_FAB2(SCH_1):TP_SPI_2_0
  U8F2     4  NC<0>  W25Q128_SKT16  I32

TP_SPI_2_1      @BASEBOARD_FAB2_LIB.BASEBOARD_FAB2(SCH_1):TP_SPI_2_1
  U8F2     5  NC<1>  W25Q128_SKT16  I32

TP_SPI_2_2      @BASEBOARD_FAB2_LIB.BASEBOARD_FAB2(SCH_1):TP_SPI_2_2
  U8F2     6  NC<2>  W25Q128_SKT16  I32

TP_SPI_2_3      @BASEBOARD_FAB2_LIB.BASEBOARD_FAB2(SCH_1):TP_SPI_2_3
  U8F2    11  NC<3>  W25Q128_SKT16  I32

TP_SPI_2_4      @BASEBOARD_FAB2_LIB.BASEBOARD_FAB2(SCH_1):TP_SPI_2_4
  U8F2    12  NC<4>  W25Q128_SKT16  I32

TP_SPI_2_5      @BASEBOARD_FAB2_LIB.BASEBOARD_FAB2(SCH_1):TP_SPI_2_5
  U8F2    13  NC<5>  W25Q128_SKT16  I32

TP_SPI_2_6      @BASEBOARD_FAB2_LIB.BASEBOARD_FAB2(SCH_1):TP_SPI_2_6
  U8F2    14  NC<6>  W25Q128_SKT16  I32

TP_SPI_BMC_BT_D2   @BASEBOARD_FAB2_LIB.BASEBOARD_FAB2(SCH_1):TP_SPI_BMC_BT_D2
  U9F4   U22  ROMD3  AST1250_BGA   I1

TP_SPI_PCH_BIOS_CLK_R   @BASEBOARD_FAB2_LIB.BASEBOARD_FAB2(SCH_1):TP_SPI_PCH_BIOS_CLK_R
  U9F4   G18  GPIOI1_SYSCK  AST1250_BGA  I347

TP_SPI_PCH_BIOS_CS0_R_N   @BASEBOARD_FAB2_LIB.BASEBOARD_FAB2(SCH_1):TP_SPI_PCH_BIOS_CS0_R_N
  U9F4   C22  GPIOI0_SYSCS_N  AST1250_BGA  I347

TP_SPI_PCH_BIOS_MISO_R   @BASEBOARD_FAB2_LIB.BASEBOARD_FAB2(SCH_1):TP_SPI_PCH_BIOS_MISO_R
  U9F4   C20  GPIOI3_SYSDI  AST1250_BGA  I347

TP_SPI_PCH_BIOS_MOSI_R   @BASEBOARD_FAB2_LIB.BASEBOARD_FAB2(SCH_1):TP_SPI_PCH_BIOS_MOSI_R
  U9F4   D19  GPIOI2_SYSDO  AST1250_BGA  I347

TP_SPI_PCH_CS1_R1_N   @BASEBOARD_FAB2_LIB.BASEBOARD_FAB2(SCH_1):TP_SPI_PCH_CS1_R1_N
  U7C1    G7  SPI0_FLASH_CS1_N  LBG_CORE_QAT_EXT_D  I34

TP_SPI_SWITCH1_3   @BASEBOARD_FAB2_LIB.BASEBOARD_FAB2(SCH_1):TP_SPI_SWITCH1_3
  U2T1     3    IA1  PI3B3257A_TSSOPLF  I75

TP_SPI_SWITCH1_6   @BASEBOARD_FAB2_LIB.BASEBOARD_FAB2(SCH_1):TP_SPI_SWITCH1_6
  U2T1     6    IB1  PI3B3257A_TSSOPLF  I75

TP_SPI_SWITCH1_9   @BASEBOARD_FAB2_LIB.BASEBOARD_FAB2(SCH_1):TP_SPI_SWITCH1_9
  U2T1     9     YC  PI3B3257A_TSSOPLF  I75

TP_SPI_SWITCH1_10   @BASEBOARD_FAB2_LIB.BASEBOARD_FAB2(SCH_1):TP_SPI_SWITCH1_10
  U2T1    10    IC1  PI3B3257A_TSSOPLF  I75

TP_SPI_SWITCH1_11   @BASEBOARD_FAB2_LIB.BASEBOARD_FAB2(SCH_1):TP_SPI_SWITCH1_11
  U2T1    11    IC0  PI3B3257A_TSSOPLF  I75

TP_SPI_SWITCH1_12   @BASEBOARD_FAB2_LIB.BASEBOARD_FAB2(SCH_1):TP_SPI_SWITCH1_12
  U2T1    12     YD  PI3B3257A_TSSOPLF  I75

TP_SPI_SWITCH1_13   @BASEBOARD_FAB2_LIB.BASEBOARD_FAB2(SCH_1):TP_SPI_SWITCH1_13
  U2T1    13    ID1  PI3B3257A_TSSOPLF  I75

TP_SPI_SWITCH1_14   @BASEBOARD_FAB2_LIB.BASEBOARD_FAB2(SCH_1):TP_SPI_SWITCH1_14
  U2T1    14    ID0  PI3B3257A_TSSOPLF  I75

TP_SPRV_SDP0    @BASEBOARD_FAB2_LIB.BASEBOARD_FAB2(SCH_1):TP_SPRV_SDP0
  EU9E1   63   SDP0  SPRINGVILLE_SM1  I72

TP_SPRV_SDP1    @BASEBOARD_FAB2_LIB.BASEBOARD_FAB2(SCH_1):TP_SPRV_SDP1
  EU9E1   61  SDP1_PCIE_DIS_SDP1  SPRINGVILLE_SM1  I72

TP_SPRV_SDP2    @BASEBOARD_FAB2_LIB.BASEBOARD_FAB2(SCH_1):TP_SPRV_SDP2
  EU9E1   62   SDP2  SPRINGVILLE_SM1  I72

TP_SPRV_SDP3    @BASEBOARD_FAB2_LIB.BASEBOARD_FAB2(SCH_1):TP_SPRV_SDP3
  EU9E1   60   SDP3  SPRINGVILLE_SM1  I72

TP_USB2_P02_DN   @BASEBOARD_FAB2_LIB.BASEBOARD_FAB2(SCH_1):TP_USB2_P02_DN
  U7C1   CA61  USB2N_2  LBG_CORE_QAT_EXT_D  I74

TP_USB2_P02_DP   @BASEBOARD_FAB2_LIB.BASEBOARD_FAB2(SCH_1):TP_USB2_P02_DP
  U7C1   BW61  USB2P_2  LBG_CORE_QAT_EXT_D  I74

TP_USB2_P03_DN   @BASEBOARD_FAB2_LIB.BASEBOARD_FAB2(SCH_1):TP_USB2_P03_DN
  U7C1   CA59  USB2N_3  LBG_CORE_QAT_EXT_D  I74

TP_USB2_P03_DP   @BASEBOARD_FAB2_LIB.BASEBOARD_FAB2(SCH_1):TP_USB2_P03_DP
  U7C1   BW59  USB2P_3  LBG_CORE_QAT_EXT_D  I74

TP_USB2_P06_DN   @BASEBOARD_FAB2_LIB.BASEBOARD_FAB2(SCH_1):TP_USB2_P06_DN
  U7C1   CA63  USB2N_6  LBG_CORE_QAT_EXT_D  I74

TP_USB2_P06_DP   @BASEBOARD_FAB2_LIB.BASEBOARD_FAB2(SCH_1):TP_USB2_P06_DP
  U7C1   BW63  USB2P_6  LBG_CORE_QAT_EXT_D  I74

TP_USB2_P07_DN   @BASEBOARD_FAB2_LIB.BASEBOARD_FAB2(SCH_1):TP_USB2_P07_DN
  U7C1   CA57  USB2N_7  LBG_CORE_QAT_EXT_D  I74

TP_USB2_P07_DP   @BASEBOARD_FAB2_LIB.BASEBOARD_FAB2(SCH_1):TP_USB2_P07_DP
  U7C1   BW57  USB2P_7  LBG_CORE_QAT_EXT_D  I74

TP_USB2_P10_DN   @BASEBOARD_FAB2_LIB.BASEBOARD_FAB2(SCH_1):TP_USB2_P10_DN
  U7C1   BW65  USB2N_10  LBG_CORE_QAT_EXT_D  I74

TP_USB2_P10_DP   @BASEBOARD_FAB2_LIB.BASEBOARD_FAB2(SCH_1):TP_USB2_P10_DP
  U7C1   BU65  USB2P_10  LBG_CORE_QAT_EXT_D  I74

TP_USB2_P11_DN   @BASEBOARD_FAB2_LIB.BASEBOARD_FAB2(SCH_1):TP_USB2_P11_DN
  U7C1   CA54  USB2N_11  LBG_CORE_QAT_EXT_D  I74

TP_USB2_P11_DP   @BASEBOARD_FAB2_LIB.BASEBOARD_FAB2(SCH_1):TP_USB2_P11_DP
  U7C1   BW54  USB2P_11  LBG_CORE_QAT_EXT_D  I74

TP_USB2_P12_DN   @BASEBOARD_FAB2_LIB.BASEBOARD_FAB2(SCH_1):TP_USB2_P12_DN
  U7C1   BW67  USB2N_12  LBG_CORE_QAT_EXT_D  I74

TP_USB2_P12_DP   @BASEBOARD_FAB2_LIB.BASEBOARD_FAB2(SCH_1):TP_USB2_P12_DP
  U7C1   BV66  USB2P_12  LBG_CORE_QAT_EXT_D  I74

TP_USB2_P13_DN   @BASEBOARD_FAB2_LIB.BASEBOARD_FAB2(SCH_1):TP_USB2_P13_DN
  U7C1   BY53  USB2N_13  LBG_CORE_QAT_EXT_D  I74

TP_USB2_P13_DP   @BASEBOARD_FAB2_LIB.BASEBOARD_FAB2(SCH_1):TP_USB2_P13_DP
  U7C1   BV53  USB2P_13  LBG_CORE_QAT_EXT_D  I74

TP_USB2_P14_DN   @BASEBOARD_FAB2_LIB.BASEBOARD_FAB2(SCH_1):TP_USB2_P14_DN
  U7C1   BW68  USB2N_14  LBG_CORE_QAT_EXT_D  I74

TP_USB2_P14_DP   @BASEBOARD_FAB2_LIB.BASEBOARD_FAB2(SCH_1):TP_USB2_P14_DP
  U7C1   BU67  USB2P_14  LBG_CORE_QAT_EXT_D  I74

TP_USB2_P8_DN   @BASEBOARD_FAB2_LIB.BASEBOARD_FAB2(SCH_1):TP_USB2_P8_DN
  U7C1   BY64  USB2N_8  LBG_CORE_QAT_EXT_D  I74

TP_USB2_P8_DP   @BASEBOARD_FAB2_LIB.BASEBOARD_FAB2(SCH_1):TP_USB2_P8_DP
  U7C1   BV64  USB2P_8  LBG_CORE_QAT_EXT_D  I74

TP_USB2_P9_DN   @BASEBOARD_FAB2_LIB.BASEBOARD_FAB2(SCH_1):TP_USB2_P9_DN
  U7C1   BY55  USB2N_9  LBG_CORE_QAT_EXT_D  I74

TP_USB2_P9_DP   @BASEBOARD_FAB2_LIB.BASEBOARD_FAB2(SCH_1):TP_USB2_P9_DP
  U7C1   BV55  USB2P_9  LBG_CORE_QAT_EXT_D  I74

TP_USB3_P02_RXN   @BASEBOARD_FAB2_LIB.BASEBOARD_FAB2(SCH_1):TP_USB3_P02_RXN
  U7C1   BJ72  USB3_2_RXN  LBG_CORE_QAT_EXT_D  I74

TP_USB3_P02_RXP   @BASEBOARD_FAB2_LIB.BASEBOARD_FAB2(SCH_1):TP_USB3_P02_RXP
  U7C1   BJ70  USB3_2_RXP  LBG_CORE_QAT_EXT_D  I74

TP_USB3_P02_TXN   @BASEBOARD_FAB2_LIB.BASEBOARD_FAB2(SCH_1):TP_USB3_P02_TXN
  U7C1   BL56  USB3_2_TXN  LBG_CORE_QAT_EXT_D  I74

TP_USB3_P02_TXP   @BASEBOARD_FAB2_LIB.BASEBOARD_FAB2(SCH_1):TP_USB3_P02_TXP
  U7C1   BJ56  USB3_2_TXP  LBG_CORE_QAT_EXT_D  I74

TP_USB3_P03_RXN   @BASEBOARD_FAB2_LIB.BASEBOARD_FAB2(SCH_1):TP_USB3_P03_RXN
  U7C1   BH71  USB3_3_RXN  LBG_CORE_QAT_EXT_D  I74

TP_USB3_P03_RXP   @BASEBOARD_FAB2_LIB.BASEBOARD_FAB2(SCH_1):TP_USB3_P03_RXP
  U7C1   BH69  USB3_3_RXP  LBG_CORE_QAT_EXT_D  I74

TP_USB3_P03_TXN   @BASEBOARD_FAB2_LIB.BASEBOARD_FAB2(SCH_1):TP_USB3_P03_TXN
  U7C1   BM54  USB3_3_TXN  LBG_CORE_QAT_EXT_D  I74

TP_USB3_P03_TXP   @BASEBOARD_FAB2_LIB.BASEBOARD_FAB2(SCH_1):TP_USB3_P03_TXP
  U7C1   BN56  USB3_3_TXP  LBG_CORE_QAT_EXT_D  I74

TP_USB3_P04_RXN   @BASEBOARD_FAB2_LIB.BASEBOARD_FAB2(SCH_1):TP_USB3_P04_RXN
  U7C1   BF72  USB3_4_RXN  LBG_CORE_QAT_EXT_D  I74

TP_USB3_P04_RXP   @BASEBOARD_FAB2_LIB.BASEBOARD_FAB2(SCH_1):TP_USB3_P04_RXP
  U7C1   BF70  USB3_4_RXP  LBG_CORE_QAT_EXT_D  I74

TP_USB3_P04_TXN   @BASEBOARD_FAB2_LIB.BASEBOARD_FAB2(SCH_1):TP_USB3_P04_TXN
  U7C1   BH58  USB3_4_TXN  LBG_CORE_QAT_EXT_D  I74

TP_USB3_P04_TXP   @BASEBOARD_FAB2_LIB.BASEBOARD_FAB2(SCH_1):TP_USB3_P04_TXP
  U7C1   BG56  USB3_4_TXP  LBG_CORE_QAT_EXT_D  I74

TP_USB3_P05_RXN   @BASEBOARD_FAB2_LIB.BASEBOARD_FAB2(SCH_1):TP_USB3_P05_RXN
  U7C1   BE71  USB3_5_RXN  LBG_CORE_QAT_EXT_D  I74

TP_USB3_P05_RXP   @BASEBOARD_FAB2_LIB.BASEBOARD_FAB2(SCH_1):TP_USB3_P05_RXP
  U7C1   BE69  USB3_5_RXP  LBG_CORE_QAT_EXT_D  I74

TP_USB3_P05_TXN   @BASEBOARD_FAB2_LIB.BASEBOARD_FAB2(SCH_1):TP_USB3_P05_TXN
  U7C1   BK58  USB3_5_TXN  LBG_CORE_QAT_EXT_D  I74

TP_USB3_P05_TXP   @BASEBOARD_FAB2_LIB.BASEBOARD_FAB2(SCH_1):TP_USB3_P05_TXP
  U7C1   BJ59  USB3_5_TXP  LBG_CORE_QAT_EXT_D  I74

TP_USB3_P06_RXN   @BASEBOARD_FAB2_LIB.BASEBOARD_FAB2(SCH_1):TP_USB3_P06_RXN
  U7C1   BD72  USB3_6_RXN  LBG_CORE_QAT_EXT_D  I74

TP_USB3_P06_RXP   @BASEBOARD_FAB2_LIB.BASEBOARD_FAB2(SCH_1):TP_USB3_P06_RXP
  U7C1   BD70  USB3_6_RXP  LBG_CORE_QAT_EXT_D  I74

TP_USB3_P06_TXN   @BASEBOARD_FAB2_LIB.BASEBOARD_FAB2(SCH_1):TP_USB3_P06_TXN
  U7C1   BL59  USB3_6_TXN  LBG_CORE_QAT_EXT_D  I74

TP_USB3_P06_TXP   @BASEBOARD_FAB2_LIB.BASEBOARD_FAB2(SCH_1):TP_USB3_P06_TXP
  U7C1   BM61  USB3_6_TXP  LBG_CORE_QAT_EXT_D  I74

TP_USB_ESD_AC2   @BASEBOARD_FAB2_LIB.BASEBOARD_FAB2(SCH_1):TP_USB_ESD_AC2
  CR1M2    4    AC2  DIODEAC_DUAL_ARRAY_SM9  I98

TP_USB_ESD_AC3   @BASEBOARD_FAB2_LIB.BASEBOARD_FAB2(SCH_1):TP_USB_ESD_AC3
  CR1M2    5    AC3  DIODEAC_DUAL_ARRAY_SM9  I98

TP_USB_ESD_OUT2   @BASEBOARD_FAB2_LIB.BASEBOARD_FAB2(SCH_1):TP_USB_ESD_OUT2
  CR1M2    7   OUT2  DIODEAC_DUAL_ARRAY_SM9  I98

TP_USB_ESD_OUT3   @BASEBOARD_FAB2_LIB.BASEBOARD_FAB2(SCH_1):TP_USB_ESD_OUT3
  CR1M2    6   OUT3  DIODEAC_DUAL_ARRAY_SM9  I98

TP_VGAHS_GPIOJ4   @BASEBOARD_FAB2_LIB.BASEBOARD_FAB2(SCH_1):TP_VGAHS_GPIOJ4
  U9F4    T4  VGAHS_GPIOJ4  AST1250_BGA  I347

TP_VGAVS_GPIOJ5   @BASEBOARD_FAB2_LIB.BASEBOARD_FAB2(SCH_1):TP_VGAVS_GPIOJ5
  U9F4    U2  VGAVS_GPIOJ5  AST1250_BGA  I347

TP_VR_PVCCIO_CPU0_AIINSEN   @BASEBOARD_FAB2_LIB.BASEBOARD_FAB2(SCH_1):TP_VR_PVCCIO_CPU0_AIINSEN
  EU3P1   38  IINSEN  PXE1110B_QFN  I93

TP_VR_PVCCIO_CPU0_MP0   @BASEBOARD_FAB2_LIB.BASEBOARD_FAB2(SCH_1):TP_VR_PVCCIO_CPU0_MP0
  EU3P1   13    MP0  PXE1110B_QFN  I93

TP_VR_PVCCIO_CPU0_MP1   @BASEBOARD_FAB2_LIB.BASEBOARD_FAB2(SCH_1):TP_VR_PVCCIO_CPU0_MP1
  EU3P1   14    MP1  PXE1110B_QFN  I93

TP_VR_PVCCIO_CPU0_MP2   @BASEBOARD_FAB2_LIB.BASEBOARD_FAB2(SCH_1):TP_VR_PVCCIO_CPU0_MP2
  EU3P1   18    MP2  PXE1110B_QFN  I93

TP_VR_PVCCIO_CPU0_MP3   @BASEBOARD_FAB2_LIB.BASEBOARD_FAB2(SCH_1):TP_VR_PVCCIO_CPU0_MP3
  EU3P1   31    MP3  PXE1110B_QFN  I93

TP_VR_PVCCIO_CPU1_AIINSEN   @BASEBOARD_FAB2_LIB.BASEBOARD_FAB2(SCH_1):TP_VR_PVCCIO_CPU1_AIINSEN
  EU4D5   38  IINSEN  PXE1110B_QFN  I96

TP_VR_PVCCIO_CPU1_MP0   @BASEBOARD_FAB2_LIB.BASEBOARD_FAB2(SCH_1):TP_VR_PVCCIO_CPU1_MP0
  EU4D5   13    MP0  PXE1110B_QFN  I96

TP_VR_PVCCIO_CPU1_MP1   @BASEBOARD_FAB2_LIB.BASEBOARD_FAB2(SCH_1):TP_VR_PVCCIO_CPU1_MP1
  EU4D5   14    MP1  PXE1110B_QFN  I96

TP_VR_PVCCIO_CPU1_MP2   @BASEBOARD_FAB2_LIB.BASEBOARD_FAB2(SCH_1):TP_VR_PVCCIO_CPU1_MP2
  EU4D5   18    MP2  PXE1110B_QFN  I96

TP_VR_PVCCIO_CPU1_MP3   @BASEBOARD_FAB2_LIB.BASEBOARD_FAB2(SCH_1):TP_VR_PVCCIO_CPU1_MP3
  EU4D5   31    MP3  PXE1110B_QFN  I96

TP_VR_PVNN_PCH_AIINSEN   @BASEBOARD_FAB2_LIB.BASEBOARD_FAB2(SCH_1):TP_VR_PVNN_PCH_AIINSEN
  EU8A1   38  IINSEN  PXE1110B_QFN  I229

TP_XDP_CPU0_OBSDATA_A0_MBP2_N   @BASEBOARD_FAB2_LIB.BASEBOARD_FAB2(SCH_1):TP_XDP_CPU0_OBSDATA_A0_MBP2_N
  U5D1   AG10  BPM_N<2>  SKX_EXT_B_BGA1  I259

TP_XDP_CPU0_OBSDATA_A1_MBP3_N   @BASEBOARD_FAB2_LIB.BASEBOARD_FAB2(SCH_1):TP_XDP_CPU0_OBSDATA_A1_MBP3_N
  U5D1   AF11  BPM_N<3>  SKX_EXT_B_BGA1  I259

TP_XDP_CPU0_OBSDATA_A2_MBP4_N   @BASEBOARD_FAB2_LIB.BASEBOARD_FAB2(SCH_1):TP_XDP_CPU0_OBSDATA_A2_MBP4_N
  U5D1   AA12  BPM_N<4>  SKX_EXT_B_BGA1  I259

TP_XDP_CPU0_OBSDATA_A3_MBP5_N   @BASEBOARD_FAB2_LIB.BASEBOARD_FAB2(SCH_1):TP_XDP_CPU0_OBSDATA_A3_MBP5_N
  U5D1   Y11  BPM_N<5>  SKX_EXT_B_BGA1  I259

TP_XDP_CPU1_OBSDATA_B0_MBP2_N   @BASEBOARD_FAB2_LIB.BASEBOARD_FAB2(SCH_1):TP_XDP_CPU1_OBSDATA_B0_MBP2_N
  U2D1   AG10  BPM_N<2>  SKX_EXT_B_BGA1  I172

TP_XDP_CPU1_OBSDATA_B1_MBP3_N   @BASEBOARD_FAB2_LIB.BASEBOARD_FAB2(SCH_1):TP_XDP_CPU1_OBSDATA_B1_MBP3_N
  U2D1   AF11  BPM_N<3>  SKX_EXT_B_BGA1  I172

TP_XDP_CPU1_OBSDATA_B2_MBP4_N   @BASEBOARD_FAB2_LIB.BASEBOARD_FAB2(SCH_1):TP_XDP_CPU1_OBSDATA_B2_MBP4_N
  U2D1   AA12  BPM_N<4>  SKX_EXT_B_BGA1  I172

TP_XDP_CPU1_OBSDATA_B3_MBP5_N   @BASEBOARD_FAB2_LIB.BASEBOARD_FAB2(SCH_1):TP_XDP_CPU1_OBSDATA_B3_MBP5_N
  U2D1   Y11  BPM_N<5>  SKX_EXT_B_BGA1  I172

TP_XDP_CPU_OBSDATA_C0   @BASEBOARD_FAB2_LIB.BASEBOARD_FAB2(SCH_1):TP_XDP_CPU_OBSDATA_C0
  J9A3    10   IO10  SCONN60_C21100002  I26

TP_XDP_CPU_OBSDATA_C1   @BASEBOARD_FAB2_LIB.BASEBOARD_FAB2(SCH_1):TP_XDP_CPU_OBSDATA_C1
  J9A3    12   IO12  SCONN60_C21100002  I26

TP_XDP_CPU_OBSDATA_C2   @BASEBOARD_FAB2_LIB.BASEBOARD_FAB2(SCH_1):TP_XDP_CPU_OBSDATA_C2
  J9A3    16   IO16  SCONN60_C21100002  I26

TP_XDP_CPU_OBSDATA_C3   @BASEBOARD_FAB2_LIB.BASEBOARD_FAB2(SCH_1):TP_XDP_CPU_OBSDATA_C3
  J9A3    18   IO18  SCONN60_C21100002  I26

TP_XDP_CPU_OBSDATA_D0   @BASEBOARD_FAB2_LIB.BASEBOARD_FAB2(SCH_1):TP_XDP_CPU_OBSDATA_D0
  J9A3    28   IO28  SCONN60_C21100002  I26

TP_XDP_CPU_OBSDATA_D1   @BASEBOARD_FAB2_LIB.BASEBOARD_FAB2(SCH_1):TP_XDP_CPU_OBSDATA_D1
  J9A3    30   IO30  SCONN60_C21100002  I26

TP_XDP_CPU_OBSDATA_D2   @BASEBOARD_FAB2_LIB.BASEBOARD_FAB2(SCH_1):TP_XDP_CPU_OBSDATA_D2
  J9A3    34   IO34  SCONN60_C21100002  I26

TP_XDP_CPU_OBSDATA_D3   @BASEBOARD_FAB2_LIB.BASEBOARD_FAB2(SCH_1):TP_XDP_CPU_OBSDATA_D3
  J9A3    36   IO36  SCONN60_C21100002  I26

TP_XDP_CPU_OBSFN_C0   @BASEBOARD_FAB2_LIB.BASEBOARD_FAB2(SCH_1):TP_XDP_CPU_OBSFN_C0
  J9A3     4    IO4  SCONN60_C21100002  I26

TP_XDP_OBSDATA_A0   @BASEBOARD_FAB2_LIB.BASEBOARD_FAB2(SCH_1):TP_XDP_OBSDATA_A0
  J9A3     9    IO9  SCONN60_C21100002  I26

TP_XDP_OBSDATA_A1   @BASEBOARD_FAB2_LIB.BASEBOARD_FAB2(SCH_1):TP_XDP_OBSDATA_A1
  J9A3    11   IO11  SCONN60_C21100002  I26

TP_XDP_OBSDATA_A2   @BASEBOARD_FAB2_LIB.BASEBOARD_FAB2(SCH_1):TP_XDP_OBSDATA_A2
  J9A3    15   IO15  SCONN60_C21100002  I26

TP_XDP_OBSDATA_A3   @BASEBOARD_FAB2_LIB.BASEBOARD_FAB2(SCH_1):TP_XDP_OBSDATA_A3
  J9A3    17   IO17  SCONN60_C21100002  I26

TP_XDP_OBSDATA_B0   @BASEBOARD_FAB2_LIB.BASEBOARD_FAB2(SCH_1):TP_XDP_OBSDATA_B0
  J9A3    27   IO27  SCONN60_C21100002  I26

TP_XDP_OBSDATA_B1   @BASEBOARD_FAB2_LIB.BASEBOARD_FAB2(SCH_1):TP_XDP_OBSDATA_B1
  J9A3    29   IO29  SCONN60_C21100002  I26

TP_XDP_OBSDATA_B2   @BASEBOARD_FAB2_LIB.BASEBOARD_FAB2(SCH_1):TP_XDP_OBSDATA_B2
  J9A3    33   IO33  SCONN60_C21100002  I26

TP_XDP_OBSDATA_B3   @BASEBOARD_FAB2_LIB.BASEBOARD_FAB2(SCH_1):TP_XDP_OBSDATA_B3
  J9A3    35   IO35  SCONN60_C21100002  I26

TP_XDP_OBSFN_B0   @BASEBOARD_FAB2_LIB.BASEBOARD_FAB2(SCH_1):TP_XDP_OBSFN_B0
  J9A3    21   IO21  SCONN60_C21100002  I26

TP_XDP_OBSFN_B1   @BASEBOARD_FAB2_LIB.BASEBOARD_FAB2(SCH_1):TP_XDP_OBSFN_B1
  J9A3    23   IO23  SCONN60_C21100002  I26

UART_BMC_RXD5   @BASEBOARD_FAB2_LIB.BASEBOARD_FAB2(SCH_1):UART_BMC_RXD5
  R9F53    1      A  RES         I53
  U8D7    J5  PL10C  LCMXO2_A_256BGA  I179
  U9F1     2     B1  FSA3357_SM  I75
  U9F4    G1   RXD5  AST1250_BGA  I100

UART_BMC_TXD5   @BASEBOARD_FAB2_LIB.BASEBOARD_FAB2(SCH_1):UART_BMC_TXD5
  R9F57    2      B  RES         I48
  U8D7    K6  PL10D  LCMXO2_A_256BGA  I179
  U9F2     2     B1  FSA3357_SM  I74
  U9F4    H5   TXD5  AST1250_BGA  I100

UART_BRIDGE_RXD5   @BASEBOARD_FAB2_LIB.BASEBOARD_FAB2(SCH_1):UART_BRIDGE_RXD5
  EU9F3    4    RXB  PI7C9X1172_QFN   I1
  R9F53    2      B  RES         I53

UART_BRIDGE_TXD5   @BASEBOARD_FAB2_LIB.BASEBOARD_FAB2(SCH_1):UART_BRIDGE_TXD5
  EU9F3    7    TXB  PI7C9X1172_QFN   I1
  R9F57    1      A  RES         I48

UART_MUX_IN_R   @BASEBOARD_FAB2_LIB.BASEBOARD_FAB2(SCH_1):UART_MUX_IN_R
  R9F25    2      B  RES         I86
  U9F1     7      A  FSA3357_SM  I75

UART_MUX_OUT_R   @BASEBOARD_FAB2_LIB.BASEBOARD_FAB2(SCH_1):UART_MUX_OUT_R
  R9F27    1      A  RES         I91
  U9F2     7      A  FSA3357_SM  I74

UNNAMED_202_3D01R5F-GP_I75_2   @BASEBOARD_FAB2_LIB.BASEBOARD_FAB2(SCH_1):UNNAMED_202_3D01R5F-GP_I75_2
  CTI3     2      2  SC2K2P50V3KX-GP_SMD-BCG6  I76
  RTI2     2      2  3D01R5F-GP_SMD-RG5  I75

UNNAMED_202_3D01R5F-GP_I83_2   @BASEBOARD_FAB2_LIB.BASEBOARD_FAB2(SCH_1):UNNAMED_202_3D01R5F-GP_I83_2
  CTI5     2      2  SC2K2P50V3KX-GP_SMD-BCG6  I82
  RTI4     2      2  3D01R5F-GP_SMD-RG5  I83

UNNAMED_203_3D01R5F-GP_I102_2   @BASEBOARD_FAB2_LIB.BASEBOARD_FAB2(SCH_1):UNNAMED_203_3D01R5F-GP_I102_2
  CTI38    2      2  SC2K2P50V3KX-GP_SMD-BCG6  I101
  RTI26    2      2  3D01R5F-GP_SMD-RG5  I102

UNNAMED_203_3D01R5F-GP_I105_2   @BASEBOARD_FAB2_LIB.BASEBOARD_FAB2(SCH_1):UNNAMED_203_3D01R5F-GP_I105_2
  CTI41    2      2  SC2K2P50V3KX-GP_SMD-BCG6  I106
  RTI27    2      2  3D01R5F-GP_SMD-RG5  I105

UNNAMED_204_3D01R5F-GP_I91_2   @BASEBOARD_FAB2_LIB.BASEBOARD_FAB2(SCH_1):UNNAMED_204_3D01R5F-GP_I91_2
  CTI35    2      2  SC2K2P50V3KX-GP_SMD-BCG6  I90
  RTI24    2      2  3D01R5F-GP_SMD-RG5  I91

UNNAMED_205_3D01R5F-GP_I68_2   @BASEBOARD_FAB2_LIB.BASEBOARD_FAB2(SCH_1):UNNAMED_205_3D01R5F-GP_I68_2
  CTI59    2      2  SC2K2P50V3KX-GP_SMD-BCG6  I64
  RTI39    2      2  3D01R5F-GP_SMD-RG5  I68

UNNAMED_207_3D01R5F-GP_I76_2   @BASEBOARD_FAB2_LIB.BASEBOARD_FAB2(SCH_1):UNNAMED_207_3D01R5F-GP_I76_2
  CTI23    2      2  SC2K2P50V3KX-GP_SMD-BCG6  I77
  RTI16    2      2  3D01R5F-GP_SMD-RG5  I76

UNNAMED_207_3D01R5F-GP_I85_2   @BASEBOARD_FAB2_LIB.BASEBOARD_FAB2(SCH_1):UNNAMED_207_3D01R5F-GP_I85_2
  CTI27    2      2  SC2K2P50V3KX-GP_SMD-BCG6  I84
  RTI18    2      2  3D01R5F-GP_SMD-RG5  I85

UNNAMED_208_3D01R5F-GP_I86_2   @BASEBOARD_FAB2_LIB.BASEBOARD_FAB2(SCH_1):UNNAMED_208_3D01R5F-GP_I86_2
  CTI18    2      2  SC2K2P50V3KX-GP_SMD-BCG6  I84
  RTI12    2      2  3D01R5F-GP_SMD-RG5  I86

UNNAMED_208_3D01R5F-GP_I94_2   @BASEBOARD_FAB2_LIB.BASEBOARD_FAB2(SCH_1):UNNAMED_208_3D01R5F-GP_I94_2
  CTI20    2      2  SC2K2P50V3KX-GP_SMD-BCG6  I92
  RTI13    2      2  3D01R5F-GP_SMD-RG5  I94

UNNAMED_209_3D01R5F-GP_I66_2   @BASEBOARD_FAB2_LIB.BASEBOARD_FAB2(SCH_1):UNNAMED_209_3D01R5F-GP_I66_2
  CTI14    2      2  SC2K2P50V3KX-GP_SMD-BCG6  I64
  RTI10    2      2  3D01R5F-GP_SMD-RG5  I66

UNNAMED_210_3D01R5F-GP_I59_2   @BASEBOARD_FAB2_LIB.BASEBOARD_FAB2(SCH_1):UNNAMED_210_3D01R5F-GP_I59_2
  CTI56    2      2  SC2K2P50V3KX-GP_SMD-BCG6  I57
  RTI38    2      2  3D01R5F-GP_SMD-RG5  I59

UNNAMED_212_3D01R5F-GP_I112_2   @BASEBOARD_FAB2_LIB.BASEBOARD_FAB2(SCH_1):UNNAMED_212_3D01R5F-GP_I112_2
  CTI72    2      2  SC2K2P50V3KX-GP_SMD-BCG6  I111
  RTI48    2      2  3D01R5F-GP_SMD-RG5  I112

UNNAMED_214_3D01R5F-GP_I132_2   @BASEBOARD_FAB2_LIB.BASEBOARD_FAB2(SCH_1):UNNAMED_214_3D01R5F-GP_I132_2
  CTI62    2      2  SC2K2P50V3KX-GP_SMD-BCG6  I131
  RTI42    2      2  3D01R5F-GP_SMD-RG5  I132

UNNAMED_216_3D01R5F-GP_I114_2   @BASEBOARD_FAB2_LIB.BASEBOARD_FAB2(SCH_1):UNNAMED_216_3D01R5F-GP_I114_2
  CTI50    2      2  SC2K2P50V3KX-GP_SMD-BCG6  I124
  RTI34    2      2  3D01R5F-GP_SMD-RG5  I114

UNNAMED_216_3D01R5F-GP_I123_2   @BASEBOARD_FAB2_LIB.BASEBOARD_FAB2(SCH_1):UNNAMED_216_3D01R5F-GP_I123_2
  CTI53    2      2  SC2K2P50V3KX-GP_SMD-BCG6  I119
  RTI35    2      2  3D01R5F-GP_SMD-RG5  I123

UNNAMED_219_3D01R5F-GP_I123_2   @BASEBOARD_FAB2_LIB.BASEBOARD_FAB2(SCH_1):UNNAMED_219_3D01R5F-GP_I123_2
  CTI47    2      2  SC2K2P50V3KX-GP_SMD-BCG6  I121
  RTI32    2      2  3D01R5F-GP_SMD-RG5  I123

UNNAMED_219_3D01R5F-GP_I126_2   @BASEBOARD_FAB2_LIB.BASEBOARD_FAB2(SCH_1):UNNAMED_219_3D01R5F-GP_I126_2
  CTI44    2      2  SC2K2P50V3KX-GP_SMD-BCG6  I127
  RTI29    2      2  3D01R5F-GP_SMD-RG5  I126

UNNAMED_224_3D01R5F-GP_I119_2   @BASEBOARD_FAB2_LIB.BASEBOARD_FAB2(SCH_1):UNNAMED_224_3D01R5F-GP_I119_2
  CTI29    2      2  SC2K2P50V3KX-GP_SMD-BCG6  I121
  RTI20    2      2  3D01R5F-GP_SMD-RG5  I119

UNNAMED_224_3D01R5F-GP_I129_2   @BASEBOARD_FAB2_LIB.BASEBOARD_FAB2(SCH_1):UNNAMED_224_3D01R5F-GP_I129_2
  CTI33    2      2  SC2K2P50V3KX-GP_SMD-BCG6  I127
  RTI22    2      2  3D01R5F-GP_SMD-RG5  I129

UNNAMED_227_3D01R5F-GP_I124_1   @BASEBOARD_FAB2_LIB.BASEBOARD_FAB2(SCH_1):UNNAMED_227_3D01R5F-GP_I124_1
  CTI11    2      2  SC2K2P50V3KX-GP_SMD-BCG6  I116
  RTI7     1      1  3D01R5F-GP_SMD-RG5  I124

UNNAMED_227_3D01R5F-GP_I125_1   @BASEBOARD_FAB2_LIB.BASEBOARD_FAB2(SCH_1):UNNAMED_227_3D01R5F-GP_I125_1
  CTI9     2      2  SC2K2P50V3KX-GP_SMD-BCG6  I111
  RTI6     1      1  3D01R5F-GP_SMD-RG5  I125

UNNAMED_236_3D01R5F-GP_I132_2   @BASEBOARD_FAB2_LIB.BASEBOARD_FAB2(SCH_1):UNNAMED_236_3D01R5F-GP_I132_2
  CTI65    2      2  SC2K2P50V3KX-GP_SMD-BCG6  I131
  RTI43    2      2  3D01R5F-GP_SMD-RG5  I132

UNNAMED_236_3D01R5F-GP_I137_2   @BASEBOARD_FAB2_LIB.BASEBOARD_FAB2(SCH_1):UNNAMED_236_3D01R5F-GP_I137_2
  CTI68    2      2  SC2K2P50V3KX-GP_SMD-BCG6  I140
  RTI45    2      2  3D01R5F-GP_SMD-RG5  I137

UPI_CPU0_CPU1_P0P0_DN<0>   @BASEBOARD_FAB2_LIB.BASEBOARD_FAB2(SCH_1):UPI_CPU0_CPU1_P0P0_DN<0>
  U2D1   AB9  UPI0_RX_DP<0>  SKX_EXT_B_BGA1  I132
  U5D1   BG4  UPI0_TX_DN<19>  SKX_EXT_B_BGA1  I86

UPI_CPU0_CPU1_P0P0_DN<1>   @BASEBOARD_FAB2_LIB.BASEBOARD_FAB2(SCH_1):UPI_CPU0_CPU1_P0P0_DN<1>
  U2D1   AA8  UPI0_RX_DN<1>  SKX_EXT_B_BGA1  I132
  U5D1   BF3  UPI0_TX_DN<18>  SKX_EXT_B_BGA1  I86

UPI_CPU0_CPU1_P0P0_DN<2>   @BASEBOARD_FAB2_LIB.BASEBOARD_FAB2(SCH_1):UPI_CPU0_CPU1_P0P0_DN<2>
  U2D1   AB7  UPI0_RX_DN<2>  SKX_EXT_B_BGA1  I132
  U5D1   BB3  UPI0_TX_DN<17>  SKX_EXT_B_BGA1  I86

UPI_CPU0_CPU1_P0P0_DN<3>   @BASEBOARD_FAB2_LIB.BASEBOARD_FAB2(SCH_1):UPI_CPU0_CPU1_P0P0_DN<3>
  U2D1   AC6  UPI0_RX_DP<3>  SKX_EXT_B_BGA1  I132
  U5D1   BA4  UPI0_TX_DN<16>  SKX_EXT_B_BGA1  I86

UPI_CPU0_CPU1_P0P0_DN<4>   @BASEBOARD_FAB2_LIB.BASEBOARD_FAB2(SCH_1):UPI_CPU0_CPU1_P0P0_DN<4>
  U2D1   AG6  UPI0_RX_DP<4>  SKX_EXT_B_BGA1  I132
  U5D1   AV5  UPI0_TX_DN<15>  SKX_EXT_B_BGA1  I86

UPI_CPU0_CPU1_P0P0_DN<5>   @BASEBOARD_FAB2_LIB.BASEBOARD_FAB2(SCH_1):UPI_CPU0_CPU1_P0P0_DN<5>
  U2D1   AF7  UPI0_RX_DP<5>  SKX_EXT_B_BGA1  I132
  U5D1   AU4  UPI0_TX_DN<14>  SKX_EXT_B_BGA1  I86

UPI_CPU0_CPU1_P0P0_DN<6>   @BASEBOARD_FAB2_LIB.BASEBOARD_FAB2(SCH_1):UPI_CPU0_CPU1_P0P0_DN<6>
  U2D1   AH7  UPI0_RX_DP<6>  SKX_EXT_B_BGA1  I132
  U5D1   AT3  UPI0_TX_DN<13>  SKX_EXT_B_BGA1  I86

UPI_CPU0_CPU1_P0P0_DN<7>   @BASEBOARD_FAB2_LIB.BASEBOARD_FAB2(SCH_1):UPI_CPU0_CPU1_P0P0_DN<7>
  U2D1   AK5  UPI0_RX_DP<7>  SKX_EXT_B_BGA1  I132
  U5D1   AT1  UPI0_TX_DN<12>  SKX_EXT_B_BGA1  I86

UPI_CPU0_CPU1_P0P0_DN<8>   @BASEBOARD_FAB2_LIB.BASEBOARD_FAB2(SCH_1):UPI_CPU0_CPU1_P0P0_DN<8>
  U2D1   AM7  UPI0_RX_DP<8>  SKX_EXT_B_BGA1  I132
  U5D1   AN4  UPI0_TX_DN<11>  SKX_EXT_B_BGA1  I86

UPI_CPU0_CPU1_P0P0_DN<9>   @BASEBOARD_FAB2_LIB.BASEBOARD_FAB2(SCH_1):UPI_CPU0_CPU1_P0P0_DN<9>
  U2D1   AL8  UPI0_RX_DP<9>  SKX_EXT_B_BGA1  I132
  U5D1   AM3  UPI0_TX_DN<10>  SKX_EXT_B_BGA1  I86

UPI_CPU0_CPU1_P0P0_DN<10>   @BASEBOARD_FAB2_LIB.BASEBOARD_FAB2(SCH_1):UPI_CPU0_CPU1_P0P0_DN<10>
  U2D1   AP7  UPI0_RX_DN<10>  SKX_EXT_B_BGA1  I132
  U5D1   AL2  UPI0_TX_DN<9>  SKX_EXT_B_BGA1  I86

UPI_CPU0_CPU1_P0P0_DN<11>   @BASEBOARD_FAB2_LIB.BASEBOARD_FAB2(SCH_1):UPI_CPU0_CPU1_P0P0_DN<11>
  U2D1   AU8  UPI0_RX_DP<11>  SKX_EXT_B_BGA1  I132
  U5D1   AH3  UPI0_TX_DN<8>  SKX_EXT_B_BGA1  I86

UPI_CPU0_CPU1_P0P0_DN<12>   @BASEBOARD_FAB2_LIB.BASEBOARD_FAB2(SCH_1):UPI_CPU0_CPU1_P0P0_DN<12>
  U2D1   AU10  UPI0_RX_DN<12>  SKX_EXT_B_BGA1  I132
  U5D1   AE2  UPI0_TX_DN<7>  SKX_EXT_B_BGA1  I86

UPI_CPU0_CPU1_P0P0_DN<13>   @BASEBOARD_FAB2_LIB.BASEBOARD_FAB2(SCH_1):UPI_CPU0_CPU1_P0P0_DN<13>
  U2D1   BA8  UPI0_RX_DN<13>  SKX_EXT_B_BGA1  I132
  U5D1   AG4  UPI0_TX_DN<6>  SKX_EXT_B_BGA1  I86

UPI_CPU0_CPU1_P0P0_DN<14>   @BASEBOARD_FAB2_LIB.BASEBOARD_FAB2(SCH_1):UPI_CPU0_CPU1_P0P0_DN<14>
  U2D1   BB7  UPI0_RX_DP<14>  SKX_EXT_B_BGA1  I132
  U5D1   AC2  UPI0_TX_DN<5>  SKX_EXT_B_BGA1  I86

UPI_CPU0_CPU1_P0P0_DN<15>   @BASEBOARD_FAB2_LIB.BASEBOARD_FAB2(SCH_1):UPI_CPU0_CPU1_P0P0_DN<15>
  U2D1   BD7  UPI0_RX_DN<15>  SKX_EXT_B_BGA1  I132
  U5D1   AB3  UPI0_TX_DN<4>  SKX_EXT_B_BGA1  I86

UPI_CPU0_CPU1_P0P0_DN<16>   @BASEBOARD_FAB2_LIB.BASEBOARD_FAB2(SCH_1):UPI_CPU0_CPU1_P0P0_DN<16>
  U2D1   AW8  UPI0_RX_DN<16>  SKX_EXT_B_BGA1  I132
  U5D1    Y1  UPI0_TX_DN<3>  SKX_EXT_B_BGA1  I86

UPI_CPU0_CPU1_P0P0_DN<17>   @BASEBOARD_FAB2_LIB.BASEBOARD_FAB2(SCH_1):UPI_CPU0_CPU1_P0P0_DN<17>
  U2D1   AY9  UPI0_RX_DN<17>  SKX_EXT_B_BGA1  I132
  U5D1    V3  UPI0_TX_DN<2>  SKX_EXT_B_BGA1  I86

UPI_CPU0_CPU1_P0P0_DN<18>   @BASEBOARD_FAB2_LIB.BASEBOARD_FAB2(SCH_1):UPI_CPU0_CPU1_P0P0_DN<18>
  U2D1   BC10  UPI0_RX_DP<18>  SKX_EXT_B_BGA1  I132
  U5D1    P1  UPI0_TX_DN<1>  SKX_EXT_B_BGA1  I86

UPI_CPU0_CPU1_P0P0_DN<19>   @BASEBOARD_FAB2_LIB.BASEBOARD_FAB2(SCH_1):UPI_CPU0_CPU1_P0P0_DN<19>
  U2D1   BA10  UPI0_RX_DP<19>  SKX_EXT_B_BGA1  I132
  U5D1    N2  UPI0_TX_DN<0>  SKX_EXT_B_BGA1  I86

UPI_CPU0_CPU1_P0P0_DP<0>   @BASEBOARD_FAB2_LIB.BASEBOARD_FAB2(SCH_1):UPI_CPU0_CPU1_P0P0_DP<0>
  U2D1   AC10  UPI0_RX_DN<0>  SKX_EXT_B_BGA1  I132
  U5D1   BH3  UPI0_TX_DP<19>  SKX_EXT_B_BGA1  I86

UPI_CPU0_CPU1_P0P0_DP<1>   @BASEBOARD_FAB2_LIB.BASEBOARD_FAB2(SCH_1):UPI_CPU0_CPU1_P0P0_DP<1>
  U2D1   AC8  UPI0_RX_DP<1>  SKX_EXT_B_BGA1  I132
  U5D1   BD3  UPI0_TX_DP<18>  SKX_EXT_B_BGA1  I86

UPI_CPU0_CPU1_P0P0_DP<2>   @BASEBOARD_FAB2_LIB.BASEBOARD_FAB2(SCH_1):UPI_CPU0_CPU1_P0P0_DP<2>
  U2D1   AA6  UPI0_RX_DP<2>  SKX_EXT_B_BGA1  I132
  U5D1   BC2  UPI0_TX_DP<17>  SKX_EXT_B_BGA1  I86

UPI_CPU0_CPU1_P0P0_DP<3>   @BASEBOARD_FAB2_LIB.BASEBOARD_FAB2(SCH_1):UPI_CPU0_CPU1_P0P0_DP<3>
  U2D1   AD5  UPI0_RX_DN<3>  SKX_EXT_B_BGA1  I132
  U5D1   AY3  UPI0_TX_DP<16>  SKX_EXT_B_BGA1  I86

UPI_CPU0_CPU1_P0P0_DP<4>   @BASEBOARD_FAB2_LIB.BASEBOARD_FAB2(SCH_1):UPI_CPU0_CPU1_P0P0_DP<4>
  U2D1   AE6  UPI0_RX_DN<4>  SKX_EXT_B_BGA1  I132
  U5D1   AW4  UPI0_TX_DP<15>  SKX_EXT_B_BGA1  I86

UPI_CPU0_CPU1_P0P0_DP<5>   @BASEBOARD_FAB2_LIB.BASEBOARD_FAB2(SCH_1):UPI_CPU0_CPU1_P0P0_DP<5>
  U2D1   AG8  UPI0_RX_DN<5>  SKX_EXT_B_BGA1  I132
  U5D1   AR4  UPI0_TX_DP<14>  SKX_EXT_B_BGA1  I86

UPI_CPU0_CPU1_P0P0_DP<6>   @BASEBOARD_FAB2_LIB.BASEBOARD_FAB2(SCH_1):UPI_CPU0_CPU1_P0P0_DP<6>
  U2D1   AJ6  UPI0_RX_DN<6>  SKX_EXT_B_BGA1  I132
  U5D1   AR2  UPI0_TX_DP<13>  SKX_EXT_B_BGA1  I86

UPI_CPU0_CPU1_P0P0_DP<7>   @BASEBOARD_FAB2_LIB.BASEBOARD_FAB2(SCH_1):UPI_CPU0_CPU1_P0P0_DP<7>
  U2D1   AL6  UPI0_RX_DN<7>  SKX_EXT_B_BGA1  I132
  U5D1   AP1  UPI0_TX_DP<12>  SKX_EXT_B_BGA1  I86

UPI_CPU0_CPU1_P0P0_DP<8>   @BASEBOARD_FAB2_LIB.BASEBOARD_FAB2(SCH_1):UPI_CPU0_CPU1_P0P0_DP<8>
  U2D1   AK7  UPI0_RX_DN<8>  SKX_EXT_B_BGA1  I132
  U5D1   AP3  UPI0_TX_DP<11>  SKX_EXT_B_BGA1  I86

UPI_CPU0_CPU1_P0P0_DP<9>   @BASEBOARD_FAB2_LIB.BASEBOARD_FAB2(SCH_1):UPI_CPU0_CPU1_P0P0_DP<9>
  U2D1   AM9  UPI0_RX_DN<9>  SKX_EXT_B_BGA1  I132
  U5D1   AK3  UPI0_TX_DP<10>  SKX_EXT_B_BGA1  I86

UPI_CPU0_CPU1_P0P0_DP<10>   @BASEBOARD_FAB2_LIB.BASEBOARD_FAB2(SCH_1):UPI_CPU0_CPU1_P0P0_DP<10>
  U2D1   AN8  UPI0_RX_DP<10>  SKX_EXT_B_BGA1  I132
  U5D1   AK1  UPI0_TX_DP<9>  SKX_EXT_B_BGA1  I86

UPI_CPU0_CPU1_P0P0_DP<11>   @BASEBOARD_FAB2_LIB.BASEBOARD_FAB2(SCH_1):UPI_CPU0_CPU1_P0P0_DP<11>
  U2D1   AR8  UPI0_RX_DN<11>  SKX_EXT_B_BGA1  I132
  U5D1   AJ2  UPI0_TX_DP<8>  SKX_EXT_B_BGA1  I86

UPI_CPU0_CPU1_P0P0_DP<12>   @BASEBOARD_FAB2_LIB.BASEBOARD_FAB2(SCH_1):UPI_CPU0_CPU1_P0P0_DP<12>
  U2D1   AT9  UPI0_RX_DP<12>  SKX_EXT_B_BGA1  I132
  U5D1   AG2  UPI0_TX_DP<7>  SKX_EXT_B_BGA1  I86

UPI_CPU0_CPU1_P0P0_DP<13>   @BASEBOARD_FAB2_LIB.BASEBOARD_FAB2(SCH_1):UPI_CPU0_CPU1_P0P0_DP<13>
  U2D1   AY7  UPI0_RX_DP<13>  SKX_EXT_B_BGA1  I132
  U5D1   AF3  UPI0_TX_DP<6>  SKX_EXT_B_BGA1  I86

UPI_CPU0_CPU1_P0P0_DP<14>   @BASEBOARD_FAB2_LIB.BASEBOARD_FAB2(SCH_1):UPI_CPU0_CPU1_P0P0_DP<14>
  U2D1   BC6  UPI0_RX_DN<14>  SKX_EXT_B_BGA1  I132
  U5D1   AD1  UPI0_TX_DP<5>  SKX_EXT_B_BGA1  I86

UPI_CPU0_CPU1_P0P0_DP<15>   @BASEBOARD_FAB2_LIB.BASEBOARD_FAB2(SCH_1):UPI_CPU0_CPU1_P0P0_DP<15>
  U2D1   BF7  UPI0_RX_DP<15>  SKX_EXT_B_BGA1  I132
  U5D1   AA2  UPI0_TX_DP<4>  SKX_EXT_B_BGA1  I86

UPI_CPU0_CPU1_P0P0_DP<16>   @BASEBOARD_FAB2_LIB.BASEBOARD_FAB2(SCH_1):UPI_CPU0_CPU1_P0P0_DP<16>
  U2D1   AV9  UPI0_RX_DP<16>  SKX_EXT_B_BGA1  I132
  U5D1    W2  UPI0_TX_DP<3>  SKX_EXT_B_BGA1  I86

UPI_CPU0_CPU1_P0P0_DP<17>   @BASEBOARD_FAB2_LIB.BASEBOARD_FAB2(SCH_1):UPI_CPU0_CPU1_P0P0_DP<17>
  U2D1   BB9  UPI0_RX_DP<17>  SKX_EXT_B_BGA1  I132
  U5D1    Y3  UPI0_TX_DP<2>  SKX_EXT_B_BGA1  I86

UPI_CPU0_CPU1_P0P0_DP<18>   @BASEBOARD_FAB2_LIB.BASEBOARD_FAB2(SCH_1):UPI_CPU0_CPU1_P0P0_DP<18>
  U2D1   BD9  UPI0_RX_DN<18>  SKX_EXT_B_BGA1  I132
  U5D1    T1  UPI0_TX_DP<1>  SKX_EXT_B_BGA1  I86

UPI_CPU0_CPU1_P0P0_DP<19>   @BASEBOARD_FAB2_LIB.BASEBOARD_FAB2(SCH_1):UPI_CPU0_CPU1_P0P0_DP<19>
  U2D1   BB11  UPI0_RX_DN<19>  SKX_EXT_B_BGA1  I132
  U5D1    M1  UPI0_TX_DP<0>  SKX_EXT_B_BGA1  I86

UPI_CPU0_CPU1_P1P1_DN<0>   @BASEBOARD_FAB2_LIB.BASEBOARD_FAB2(SCH_1):UPI_CPU0_CPU1_P1P1_DN<0>
  U2D1    R6  UPI1_RX_DP<0>  SKX_EXT_B_BGA1  I125
  U5D1   H21  UPI1_TX_DN<19>  SKX_EXT_B_BGA1  I86

UPI_CPU0_CPU1_P1P1_DN<1>   @BASEBOARD_FAB2_LIB.BASEBOARD_FAB2(SCH_1):UPI_CPU0_CPU1_P1P1_DN<1>
  U2D1    P7  UPI1_RX_DN<1>  SKX_EXT_B_BGA1  I125
  U5D1   F21  UPI1_TX_DN<18>  SKX_EXT_B_BGA1  I86

UPI_CPU0_CPU1_P1P1_DN<2>   @BASEBOARD_FAB2_LIB.BASEBOARD_FAB2(SCH_1):UPI_CPU0_CPU1_P1P1_DN<2>
  U2D1    V7  UPI1_RX_DN<2>  SKX_EXT_B_BGA1  I125
  U5D1   J20  UPI1_TX_DN<17>  SKX_EXT_B_BGA1  I86

UPI_CPU0_CPU1_P1P1_DN<3>   @BASEBOARD_FAB2_LIB.BASEBOARD_FAB2(SCH_1):UPI_CPU0_CPU1_P1P1_DN<3>
  U2D1    T9  UPI1_RX_DN<3>  SKX_EXT_B_BGA1  I125
  U5D1   G18  UPI1_TX_DN<16>  SKX_EXT_B_BGA1  I86

UPI_CPU0_CPU1_P1P1_DN<4>   @BASEBOARD_FAB2_LIB.BASEBOARD_FAB2(SCH_1):UPI_CPU0_CPU1_P1P1_DN<4>
  U2D1    P9  UPI1_RX_DN<4>  SKX_EXT_B_BGA1  I125
  U5D1   K19  UPI1_TX_DN<15>  SKX_EXT_B_BGA1  I86

UPI_CPU0_CPU1_P1P1_DN<5>   @BASEBOARD_FAB2_LIB.BASEBOARD_FAB2(SCH_1):UPI_CPU0_CPU1_P1P1_DN<5>
  U2D1   R10  UPI1_RX_DN<5>  SKX_EXT_B_BGA1  I125
  U5D1   H17  UPI1_TX_DN<14>  SKX_EXT_B_BGA1  I86

UPI_CPU0_CPU1_P1P1_DN<6>   @BASEBOARD_FAB2_LIB.BASEBOARD_FAB2(SCH_1):UPI_CPU0_CPU1_P1P1_DN<6>
  U2D1   U12  UPI1_RX_DN<6>  SKX_EXT_B_BGA1  I125
  U5D1   F15  UPI1_TX_DN<13>  SKX_EXT_B_BGA1  I86

UPI_CPU0_CPU1_P1P1_DN<7>   @BASEBOARD_FAB2_LIB.BASEBOARD_FAB2(SCH_1):UPI_CPU0_CPU1_P1P1_DN<7>
  U2D1   L12  UPI1_RX_DN<7>  SKX_EXT_B_BGA1  I125
  U5D1   D15  UPI1_TX_DN<12>  SKX_EXT_B_BGA1  I86

UPI_CPU0_CPU1_P1P1_DN<8>   @BASEBOARD_FAB2_LIB.BASEBOARD_FAB2(SCH_1):UPI_CPU0_CPU1_P1P1_DN<8>
  U2D1   M13  UPI1_RX_DP<8>  SKX_EXT_B_BGA1  I125
  U5D1   G14  UPI1_TX_DN<11>  SKX_EXT_B_BGA1  I86

UPI_CPU0_CPU1_P1P1_DN<9>   @BASEBOARD_FAB2_LIB.BASEBOARD_FAB2(SCH_1):UPI_CPU0_CPU1_P1P1_DN<9>
  U2D1   R12  UPI1_RX_DN<9>  SKX_EXT_B_BGA1  I125
  U5D1   E12  UPI1_TX_DN<10>  SKX_EXT_B_BGA1  I86

UPI_CPU0_CPU1_P1P1_DN<10>   @BASEBOARD_FAB2_LIB.BASEBOARD_FAB2(SCH_1):UPI_CPU0_CPU1_P1P1_DN<10>
  U2D1   R16  UPI1_RX_DN<10>  SKX_EXT_B_BGA1  I125
  U5D1   G10  UPI1_TX_DN<9>  SKX_EXT_B_BGA1  I86

UPI_CPU0_CPU1_P1P1_DN<11>   @BASEBOARD_FAB2_LIB.BASEBOARD_FAB2(SCH_1):UPI_CPU0_CPU1_P1P1_DN<11>
  U2D1   N16  UPI1_RX_DP<11>  SKX_EXT_B_BGA1  I125
  U5D1   F11  UPI1_TX_DN<8>  SKX_EXT_B_BGA1  I86

UPI_CPU0_CPU1_P1P1_DN<12>   @BASEBOARD_FAB2_LIB.BASEBOARD_FAB2(SCH_1):UPI_CPU0_CPU1_P1P1_DN<12>
  U2D1   W16  UPI1_RX_DP<12>  SKX_EXT_B_BGA1  I125
  U5D1    D9  UPI1_TX_DN<7>  SKX_EXT_B_BGA1  I86

UPI_CPU0_CPU1_P1P1_DN<13>   @BASEBOARD_FAB2_LIB.BASEBOARD_FAB2(SCH_1):UPI_CPU0_CPU1_P1P1_DN<13>
  U2D1   V17  UPI1_RX_DP<13>  SKX_EXT_B_BGA1  I125
  U5D1    K9  UPI1_TX_DN<6>  SKX_EXT_B_BGA1  I86

UPI_CPU0_CPU1_P1P1_DN<14>   @BASEBOARD_FAB2_LIB.BASEBOARD_FAB2(SCH_1):UPI_CPU0_CPU1_P1P1_DN<14>
  U2D1   R20  UPI1_RX_DN<14>  SKX_EXT_B_BGA1  I125
  U5D1    H7  UPI1_TX_DN<5>  SKX_EXT_B_BGA1  I86

UPI_CPU0_CPU1_P1P1_DN<15>   @BASEBOARD_FAB2_LIB.BASEBOARD_FAB2(SCH_1):UPI_CPU0_CPU1_P1P1_DN<15>
  U2D1   U18  UPI1_RX_DN<15>  SKX_EXT_B_BGA1  I125
  U5D1    G6  UPI1_TX_DN<4>  SKX_EXT_B_BGA1  I86

UPI_CPU0_CPU1_P1P1_DN<16>   @BASEBOARD_FAB2_LIB.BASEBOARD_FAB2(SCH_1):UPI_CPU0_CPU1_P1P1_DN<16>
  U2D1   P21  UPI1_RX_DN<16>  SKX_EXT_B_BGA1  I125
  U5D1    J6  UPI1_TX_DN<3>  SKX_EXT_B_BGA1  I86

UPI_CPU0_CPU1_P1P1_DN<17>   @BASEBOARD_FAB2_LIB.BASEBOARD_FAB2(SCH_1):UPI_CPU0_CPU1_P1P1_DN<17>
  U2D1   V19  UPI1_RX_DN<17>  SKX_EXT_B_BGA1  I125
  U5D1    K5  UPI1_TX_DN<2>  SKX_EXT_B_BGA1  I86

UPI_CPU0_CPU1_P1P1_DN<18>   @BASEBOARD_FAB2_LIB.BASEBOARD_FAB2(SCH_1):UPI_CPU0_CPU1_P1P1_DN<18>
  U2D1   W20  UPI1_RX_DP<18>  SKX_EXT_B_BGA1  I125
  U5D1    L4  UPI1_TX_DN<1>  SKX_EXT_B_BGA1  I86

UPI_CPU0_CPU1_P1P1_DN<19>   @BASEBOARD_FAB2_LIB.BASEBOARD_FAB2(SCH_1):UPI_CPU0_CPU1_P1P1_DN<19>
  U2D1   AA20  UPI1_RX_DP<19>  SKX_EXT_B_BGA1  I125
  U5D1    M3  UPI1_TX_DN<0>  SKX_EXT_B_BGA1  I86

UPI_CPU0_CPU1_P1P1_DP<0>   @BASEBOARD_FAB2_LIB.BASEBOARD_FAB2(SCH_1):UPI_CPU0_CPU1_P1P1_DP<0>
  U2D1    T5  UPI1_RX_DN<0>  SKX_EXT_B_BGA1  I125
  U5D1   K21  UPI1_TX_DP<19>  SKX_EXT_B_BGA1  I86

UPI_CPU0_CPU1_P1P1_DP<1>   @BASEBOARD_FAB2_LIB.BASEBOARD_FAB2(SCH_1):UPI_CPU0_CPU1_P1P1_DP<1>
  U2D1    T7  UPI1_RX_DP<1>  SKX_EXT_B_BGA1  I125
  U5D1   G20  UPI1_TX_DP<18>  SKX_EXT_B_BGA1  I86

UPI_CPU0_CPU1_P1P1_DP<2>   @BASEBOARD_FAB2_LIB.BASEBOARD_FAB2(SCH_1):UPI_CPU0_CPU1_P1P1_DP<2>
  U2D1    U8  UPI1_RX_DP<2>  SKX_EXT_B_BGA1  I125
  U5D1   H19  UPI1_TX_DP<17>  SKX_EXT_B_BGA1  I86

UPI_CPU0_CPU1_P1P1_DP<3>   @BASEBOARD_FAB2_LIB.BASEBOARD_FAB2(SCH_1):UPI_CPU0_CPU1_P1P1_DP<3>
  U2D1    R8  UPI1_RX_DP<3>  SKX_EXT_B_BGA1  I125
  U5D1   J18  UPI1_TX_DP<16>  SKX_EXT_B_BGA1  I86

UPI_CPU0_CPU1_P1P1_DP<4>   @BASEBOARD_FAB2_LIB.BASEBOARD_FAB2(SCH_1):UPI_CPU0_CPU1_P1P1_DP<4>
  U2D1   N10  UPI1_RX_DP<4>  SKX_EXT_B_BGA1  I125
  U5D1   L18  UPI1_TX_DP<15>  SKX_EXT_B_BGA1  I86

UPI_CPU0_CPU1_P1P1_DP<5>   @BASEBOARD_FAB2_LIB.BASEBOARD_FAB2(SCH_1):UPI_CPU0_CPU1_P1P1_DP<5>
  U2D1   U10  UPI1_RX_DP<5>  SKX_EXT_B_BGA1  I125
  U5D1   G16  UPI1_TX_DP<14>  SKX_EXT_B_BGA1  I86

UPI_CPU0_CPU1_P1P1_DP<6>   @BASEBOARD_FAB2_LIB.BASEBOARD_FAB2(SCH_1):UPI_CPU0_CPU1_P1P1_DP<6>
  U2D1   T11  UPI1_RX_DP<6>  SKX_EXT_B_BGA1  I125
  U5D1   H15  UPI1_TX_DP<13>  SKX_EXT_B_BGA1  I86

UPI_CPU0_CPU1_P1P1_DP<7>   @BASEBOARD_FAB2_LIB.BASEBOARD_FAB2(SCH_1):UPI_CPU0_CPU1_P1P1_DP<7>
  U2D1   N12  UPI1_RX_DP<7>  SKX_EXT_B_BGA1  I125
  U5D1   E14  UPI1_TX_DP<12>  SKX_EXT_B_BGA1  I86

UPI_CPU0_CPU1_P1P1_DP<8>   @BASEBOARD_FAB2_LIB.BASEBOARD_FAB2(SCH_1):UPI_CPU0_CPU1_P1P1_DP<8>
  U2D1   N14  UPI1_RX_DN<8>  SKX_EXT_B_BGA1  I125
  U5D1   F13  UPI1_TX_DP<11>  SKX_EXT_B_BGA1  I86

UPI_CPU0_CPU1_P1P1_DP<9>   @BASEBOARD_FAB2_LIB.BASEBOARD_FAB2(SCH_1):UPI_CPU0_CPU1_P1P1_DP<9>
  U2D1   P13  UPI1_RX_DP<9>  SKX_EXT_B_BGA1  I125
  U5D1   G12  UPI1_TX_DP<10>  SKX_EXT_B_BGA1  I86

UPI_CPU0_CPU1_P1P1_DP<10>   @BASEBOARD_FAB2_LIB.BASEBOARD_FAB2(SCH_1):UPI_CPU0_CPU1_P1P1_DP<10>
  U2D1   T15  UPI1_RX_DP<10>  SKX_EXT_B_BGA1  I125
  U5D1    H9  UPI1_TX_DP<9>  SKX_EXT_B_BGA1  I86

UPI_CPU0_CPU1_P1P1_DP<11>   @BASEBOARD_FAB2_LIB.BASEBOARD_FAB2(SCH_1):UPI_CPU0_CPU1_P1P1_DP<11>
  U2D1   P17  UPI1_RX_DN<11>  SKX_EXT_B_BGA1  I125
  U5D1   E10  UPI1_TX_DP<8>  SKX_EXT_B_BGA1  I86

UPI_CPU0_CPU1_P1P1_DP<12>   @BASEBOARD_FAB2_LIB.BASEBOARD_FAB2(SCH_1):UPI_CPU0_CPU1_P1P1_DP<12>
  U2D1   U16  UPI1_RX_DN<12>  SKX_EXT_B_BGA1  I125
  U5D1    F9  UPI1_TX_DP<7>  SKX_EXT_B_BGA1  I86

UPI_CPU0_CPU1_P1P1_DP<13>   @BASEBOARD_FAB2_LIB.BASEBOARD_FAB2(SCH_1):UPI_CPU0_CPU1_P1P1_DP<13>
  U2D1   W18  UPI1_RX_DN<13>  SKX_EXT_B_BGA1  I125
  U5D1    J8  UPI1_TX_DP<6>  SKX_EXT_B_BGA1  I86

UPI_CPU0_CPU1_P1P1_DP<14>   @BASEBOARD_FAB2_LIB.BASEBOARD_FAB2(SCH_1):UPI_CPU0_CPU1_P1P1_DP<14>
  U2D1   P19  UPI1_RX_DP<14>  SKX_EXT_B_BGA1  I125
  U5D1    K7  UPI1_TX_DP<5>  SKX_EXT_B_BGA1  I86

UPI_CPU0_CPU1_P1P1_DP<15>   @BASEBOARD_FAB2_LIB.BASEBOARD_FAB2(SCH_1):UPI_CPU0_CPU1_P1P1_DP<15>
  U2D1   T19  UPI1_RX_DP<15>  SKX_EXT_B_BGA1  I125
  U5D1    F7  UPI1_TX_DP<4>  SKX_EXT_B_BGA1  I86

UPI_CPU0_CPU1_P1P1_DP<16>   @BASEBOARD_FAB2_LIB.BASEBOARD_FAB2(SCH_1):UPI_CPU0_CPU1_P1P1_DP<16>
  U2D1   T21  UPI1_RX_DP<16>  SKX_EXT_B_BGA1  I125
  U5D1    H5  UPI1_TX_DP<3>  SKX_EXT_B_BGA1  I86

UPI_CPU0_CPU1_P1P1_DP<17>   @BASEBOARD_FAB2_LIB.BASEBOARD_FAB2(SCH_1):UPI_CPU0_CPU1_P1P1_DP<17>
  U2D1   Y19  UPI1_RX_DP<17>  SKX_EXT_B_BGA1  I125
  U5D1    M5  UPI1_TX_DP<2>  SKX_EXT_B_BGA1  I86

UPI_CPU0_CPU1_P1P1_DP<18>   @BASEBOARD_FAB2_LIB.BASEBOARD_FAB2(SCH_1):UPI_CPU0_CPU1_P1P1_DP<18>
  U2D1   Y21  UPI1_RX_DN<18>  SKX_EXT_B_BGA1  I125
  U5D1    K3  UPI1_TX_DP<1>  SKX_EXT_B_BGA1  I86

UPI_CPU0_CPU1_P1P1_DP<19>   @BASEBOARD_FAB2_LIB.BASEBOARD_FAB2(SCH_1):UPI_CPU0_CPU1_P1P1_DP<19>
  U2D1   AB19  UPI1_RX_DN<19>  SKX_EXT_B_BGA1  I125
  U5D1    P3  UPI1_TX_DP<0>  SKX_EXT_B_BGA1  I86

UPI_CPU1_CPU0_P0P0_DN<0>   @BASEBOARD_FAB2_LIB.BASEBOARD_FAB2(SCH_1):UPI_CPU1_CPU0_P0P0_DN<0>
  U2D1    M1  UPI0_TX_DP<0>  SKX_EXT_B_BGA1  I132
  U5D1   BB11  UPI0_RX_DN<19>  SKX_EXT_B_BGA1  I86

UPI_CPU1_CPU0_P0P0_DN<1>   @BASEBOARD_FAB2_LIB.BASEBOARD_FAB2(SCH_1):UPI_CPU1_CPU0_P0P0_DN<1>
  U2D1    T1  UPI0_TX_DP<1>  SKX_EXT_B_BGA1  I132
  U5D1   BD9  UPI0_RX_DN<18>  SKX_EXT_B_BGA1  I86

UPI_CPU1_CPU0_P0P0_DN<2>   @BASEBOARD_FAB2_LIB.BASEBOARD_FAB2(SCH_1):UPI_CPU1_CPU0_P0P0_DN<2>
  U2D1    V3  UPI0_TX_DN<2>  SKX_EXT_B_BGA1  I132
  U5D1   AY9  UPI0_RX_DN<17>  SKX_EXT_B_BGA1  I86

UPI_CPU1_CPU0_P0P0_DN<3>   @BASEBOARD_FAB2_LIB.BASEBOARD_FAB2(SCH_1):UPI_CPU1_CPU0_P0P0_DN<3>
  U2D1    Y1  UPI0_TX_DN<3>  SKX_EXT_B_BGA1  I132
  U5D1   AW8  UPI0_RX_DN<16>  SKX_EXT_B_BGA1  I86

UPI_CPU1_CPU0_P0P0_DN<4>   @BASEBOARD_FAB2_LIB.BASEBOARD_FAB2(SCH_1):UPI_CPU1_CPU0_P0P0_DN<4>
  U2D1   AB3  UPI0_TX_DN<4>  SKX_EXT_B_BGA1  I132
  U5D1   BD7  UPI0_RX_DN<15>  SKX_EXT_B_BGA1  I86

UPI_CPU1_CPU0_P0P0_DN<5>   @BASEBOARD_FAB2_LIB.BASEBOARD_FAB2(SCH_1):UPI_CPU1_CPU0_P0P0_DN<5>
  U2D1   AD1  UPI0_TX_DP<5>  SKX_EXT_B_BGA1  I132
  U5D1   BC6  UPI0_RX_DN<14>  SKX_EXT_B_BGA1  I86

UPI_CPU1_CPU0_P0P0_DN<6>   @BASEBOARD_FAB2_LIB.BASEBOARD_FAB2(SCH_1):UPI_CPU1_CPU0_P0P0_DN<6>
  U2D1   AG4  UPI0_TX_DN<6>  SKX_EXT_B_BGA1  I132
  U5D1   BA8  UPI0_RX_DN<13>  SKX_EXT_B_BGA1  I86

UPI_CPU1_CPU0_P0P0_DN<7>   @BASEBOARD_FAB2_LIB.BASEBOARD_FAB2(SCH_1):UPI_CPU1_CPU0_P0P0_DN<7>
  U2D1   AE2  UPI0_TX_DN<7>  SKX_EXT_B_BGA1  I132
  U5D1   AU10  UPI0_RX_DN<12>  SKX_EXT_B_BGA1  I86

UPI_CPU1_CPU0_P0P0_DN<8>   @BASEBOARD_FAB2_LIB.BASEBOARD_FAB2(SCH_1):UPI_CPU1_CPU0_P0P0_DN<8>
  U2D1   AJ2  UPI0_TX_DP<8>  SKX_EXT_B_BGA1  I132
  U5D1   AR8  UPI0_RX_DN<11>  SKX_EXT_B_BGA1  I86

UPI_CPU1_CPU0_P0P0_DN<9>   @BASEBOARD_FAB2_LIB.BASEBOARD_FAB2(SCH_1):UPI_CPU1_CPU0_P0P0_DN<9>
  U2D1   AL2  UPI0_TX_DN<9>  SKX_EXT_B_BGA1  I132
  U5D1   AP7  UPI0_RX_DN<10>  SKX_EXT_B_BGA1  I86

UPI_CPU1_CPU0_P0P0_DN<10>   @BASEBOARD_FAB2_LIB.BASEBOARD_FAB2(SCH_1):UPI_CPU1_CPU0_P0P0_DN<10>
  U2D1   AK3  UPI0_TX_DP<10>  SKX_EXT_B_BGA1  I132
  U5D1   AM9  UPI0_RX_DN<9>  SKX_EXT_B_BGA1  I86

UPI_CPU1_CPU0_P0P0_DN<11>   @BASEBOARD_FAB2_LIB.BASEBOARD_FAB2(SCH_1):UPI_CPU1_CPU0_P0P0_DN<11>
  U2D1   AP3  UPI0_TX_DP<11>  SKX_EXT_B_BGA1  I132
  U5D1   AK7  UPI0_RX_DN<8>  SKX_EXT_B_BGA1  I86

UPI_CPU1_CPU0_P0P0_DN<12>   @BASEBOARD_FAB2_LIB.BASEBOARD_FAB2(SCH_1):UPI_CPU1_CPU0_P0P0_DN<12>
  U2D1   AP1  UPI0_TX_DP<12>  SKX_EXT_B_BGA1  I132
  U5D1   AL6  UPI0_RX_DN<7>  SKX_EXT_B_BGA1  I86

UPI_CPU1_CPU0_P0P0_DN<13>   @BASEBOARD_FAB2_LIB.BASEBOARD_FAB2(SCH_1):UPI_CPU1_CPU0_P0P0_DN<13>
  U2D1   AR2  UPI0_TX_DP<13>  SKX_EXT_B_BGA1  I132
  U5D1   AJ6  UPI0_RX_DN<6>  SKX_EXT_B_BGA1  I86

UPI_CPU1_CPU0_P0P0_DN<14>   @BASEBOARD_FAB2_LIB.BASEBOARD_FAB2(SCH_1):UPI_CPU1_CPU0_P0P0_DN<14>
  U2D1   AR4  UPI0_TX_DP<14>  SKX_EXT_B_BGA1  I132
  U5D1   AG8  UPI0_RX_DN<5>  SKX_EXT_B_BGA1  I86

UPI_CPU1_CPU0_P0P0_DN<15>   @BASEBOARD_FAB2_LIB.BASEBOARD_FAB2(SCH_1):UPI_CPU1_CPU0_P0P0_DN<15>
  U2D1   AW4  UPI0_TX_DP<15>  SKX_EXT_B_BGA1  I132
  U5D1   AE6  UPI0_RX_DN<4>  SKX_EXT_B_BGA1  I86

UPI_CPU1_CPU0_P0P0_DN<16>   @BASEBOARD_FAB2_LIB.BASEBOARD_FAB2(SCH_1):UPI_CPU1_CPU0_P0P0_DN<16>
  U2D1   AY3  UPI0_TX_DP<16>  SKX_EXT_B_BGA1  I132
  U5D1   AD5  UPI0_RX_DN<3>  SKX_EXT_B_BGA1  I86

UPI_CPU1_CPU0_P0P0_DN<17>   @BASEBOARD_FAB2_LIB.BASEBOARD_FAB2(SCH_1):UPI_CPU1_CPU0_P0P0_DN<17>
  U2D1   BB3  UPI0_TX_DN<17>  SKX_EXT_B_BGA1  I132
  U5D1   AB7  UPI0_RX_DN<2>  SKX_EXT_B_BGA1  I86

UPI_CPU1_CPU0_P0P0_DN<18>   @BASEBOARD_FAB2_LIB.BASEBOARD_FAB2(SCH_1):UPI_CPU1_CPU0_P0P0_DN<18>
  U2D1   BF3  UPI0_TX_DN<18>  SKX_EXT_B_BGA1  I132
  U5D1   AA8  UPI0_RX_DN<1>  SKX_EXT_B_BGA1  I86

UPI_CPU1_CPU0_P0P0_DN<19>   @BASEBOARD_FAB2_LIB.BASEBOARD_FAB2(SCH_1):UPI_CPU1_CPU0_P0P0_DN<19>
  U2D1   BH3  UPI0_TX_DP<19>  SKX_EXT_B_BGA1  I132
  U5D1   AC10  UPI0_RX_DN<0>  SKX_EXT_B_BGA1  I86

UPI_CPU1_CPU0_P0P0_DP<0>   @BASEBOARD_FAB2_LIB.BASEBOARD_FAB2(SCH_1):UPI_CPU1_CPU0_P0P0_DP<0>
  U2D1    N2  UPI0_TX_DN<0>  SKX_EXT_B_BGA1  I132
  U5D1   BA10  UPI0_RX_DP<19>  SKX_EXT_B_BGA1  I86

UPI_CPU1_CPU0_P0P0_DP<1>   @BASEBOARD_FAB2_LIB.BASEBOARD_FAB2(SCH_1):UPI_CPU1_CPU0_P0P0_DP<1>
  U2D1    P1  UPI0_TX_DN<1>  SKX_EXT_B_BGA1  I132
  U5D1   BC10  UPI0_RX_DP<18>  SKX_EXT_B_BGA1  I86

UPI_CPU1_CPU0_P0P0_DP<2>   @BASEBOARD_FAB2_LIB.BASEBOARD_FAB2(SCH_1):UPI_CPU1_CPU0_P0P0_DP<2>
  U2D1    Y3  UPI0_TX_DP<2>  SKX_EXT_B_BGA1  I132
  U5D1   BB9  UPI0_RX_DP<17>  SKX_EXT_B_BGA1  I86

UPI_CPU1_CPU0_P0P0_DP<3>   @BASEBOARD_FAB2_LIB.BASEBOARD_FAB2(SCH_1):UPI_CPU1_CPU0_P0P0_DP<3>
  U2D1    W2  UPI0_TX_DP<3>  SKX_EXT_B_BGA1  I132
  U5D1   AV9  UPI0_RX_DP<16>  SKX_EXT_B_BGA1  I86

UPI_CPU1_CPU0_P0P0_DP<4>   @BASEBOARD_FAB2_LIB.BASEBOARD_FAB2(SCH_1):UPI_CPU1_CPU0_P0P0_DP<4>
  U2D1   AA2  UPI0_TX_DP<4>  SKX_EXT_B_BGA1  I132
  U5D1   BF7  UPI0_RX_DP<15>  SKX_EXT_B_BGA1  I86

UPI_CPU1_CPU0_P0P0_DP<5>   @BASEBOARD_FAB2_LIB.BASEBOARD_FAB2(SCH_1):UPI_CPU1_CPU0_P0P0_DP<5>
  U2D1   AC2  UPI0_TX_DN<5>  SKX_EXT_B_BGA1  I132
  U5D1   BB7  UPI0_RX_DP<14>  SKX_EXT_B_BGA1  I86

UPI_CPU1_CPU0_P0P0_DP<6>   @BASEBOARD_FAB2_LIB.BASEBOARD_FAB2(SCH_1):UPI_CPU1_CPU0_P0P0_DP<6>
  U2D1   AF3  UPI0_TX_DP<6>  SKX_EXT_B_BGA1  I132
  U5D1   AY7  UPI0_RX_DP<13>  SKX_EXT_B_BGA1  I86

UPI_CPU1_CPU0_P0P0_DP<7>   @BASEBOARD_FAB2_LIB.BASEBOARD_FAB2(SCH_1):UPI_CPU1_CPU0_P0P0_DP<7>
  U2D1   AG2  UPI0_TX_DP<7>  SKX_EXT_B_BGA1  I132
  U5D1   AT9  UPI0_RX_DP<12>  SKX_EXT_B_BGA1  I86

UPI_CPU1_CPU0_P0P0_DP<8>   @BASEBOARD_FAB2_LIB.BASEBOARD_FAB2(SCH_1):UPI_CPU1_CPU0_P0P0_DP<8>
  U2D1   AH3  UPI0_TX_DN<8>  SKX_EXT_B_BGA1  I132
  U5D1   AU8  UPI0_RX_DP<11>  SKX_EXT_B_BGA1  I86

UPI_CPU1_CPU0_P0P0_DP<9>   @BASEBOARD_FAB2_LIB.BASEBOARD_FAB2(SCH_1):UPI_CPU1_CPU0_P0P0_DP<9>
  U2D1   AK1  UPI0_TX_DP<9>  SKX_EXT_B_BGA1  I132
  U5D1   AN8  UPI0_RX_DP<10>  SKX_EXT_B_BGA1  I86

UPI_CPU1_CPU0_P0P0_DP<10>   @BASEBOARD_FAB2_LIB.BASEBOARD_FAB2(SCH_1):UPI_CPU1_CPU0_P0P0_DP<10>
  U2D1   AM3  UPI0_TX_DN<10>  SKX_EXT_B_BGA1  I132
  U5D1   AL8  UPI0_RX_DP<9>  SKX_EXT_B_BGA1  I86

UPI_CPU1_CPU0_P0P0_DP<11>   @BASEBOARD_FAB2_LIB.BASEBOARD_FAB2(SCH_1):UPI_CPU1_CPU0_P0P0_DP<11>
  U2D1   AN4  UPI0_TX_DN<11>  SKX_EXT_B_BGA1  I132
  U5D1   AM7  UPI0_RX_DP<8>  SKX_EXT_B_BGA1  I86

UPI_CPU1_CPU0_P0P0_DP<12>   @BASEBOARD_FAB2_LIB.BASEBOARD_FAB2(SCH_1):UPI_CPU1_CPU0_P0P0_DP<12>
  U2D1   AT1  UPI0_TX_DN<12>  SKX_EXT_B_BGA1  I132
  U5D1   AK5  UPI0_RX_DP<7>  SKX_EXT_B_BGA1  I86

UPI_CPU1_CPU0_P0P0_DP<13>   @BASEBOARD_FAB2_LIB.BASEBOARD_FAB2(SCH_1):UPI_CPU1_CPU0_P0P0_DP<13>
  U2D1   AT3  UPI0_TX_DN<13>  SKX_EXT_B_BGA1  I132
  U5D1   AH7  UPI0_RX_DP<6>  SKX_EXT_B_BGA1  I86

UPI_CPU1_CPU0_P0P0_DP<14>   @BASEBOARD_FAB2_LIB.BASEBOARD_FAB2(SCH_1):UPI_CPU1_CPU0_P0P0_DP<14>
  U2D1   AU4  UPI0_TX_DN<14>  SKX_EXT_B_BGA1  I132
  U5D1   AF7  UPI0_RX_DP<5>  SKX_EXT_B_BGA1  I86

UPI_CPU1_CPU0_P0P0_DP<15>   @BASEBOARD_FAB2_LIB.BASEBOARD_FAB2(SCH_1):UPI_CPU1_CPU0_P0P0_DP<15>
  U2D1   AV5  UPI0_TX_DN<15>  SKX_EXT_B_BGA1  I132
  U5D1   AG6  UPI0_RX_DP<4>  SKX_EXT_B_BGA1  I86

UPI_CPU1_CPU0_P0P0_DP<16>   @BASEBOARD_FAB2_LIB.BASEBOARD_FAB2(SCH_1):UPI_CPU1_CPU0_P0P0_DP<16>
  U2D1   BA4  UPI0_TX_DN<16>  SKX_EXT_B_BGA1  I132
  U5D1   AC6  UPI0_RX_DP<3>  SKX_EXT_B_BGA1  I86

UPI_CPU1_CPU0_P0P0_DP<17>   @BASEBOARD_FAB2_LIB.BASEBOARD_FAB2(SCH_1):UPI_CPU1_CPU0_P0P0_DP<17>
  U2D1   BC2  UPI0_TX_DP<17>  SKX_EXT_B_BGA1  I132
  U5D1   AA6  UPI0_RX_DP<2>  SKX_EXT_B_BGA1  I86

UPI_CPU1_CPU0_P0P0_DP<18>   @BASEBOARD_FAB2_LIB.BASEBOARD_FAB2(SCH_1):UPI_CPU1_CPU0_P0P0_DP<18>
  U2D1   BD3  UPI0_TX_DP<18>  SKX_EXT_B_BGA1  I132
  U5D1   AC8  UPI0_RX_DP<1>  SKX_EXT_B_BGA1  I86

UPI_CPU1_CPU0_P0P0_DP<19>   @BASEBOARD_FAB2_LIB.BASEBOARD_FAB2(SCH_1):UPI_CPU1_CPU0_P0P0_DP<19>
  U2D1   BG4  UPI0_TX_DN<19>  SKX_EXT_B_BGA1  I132
  U5D1   AB9  UPI0_RX_DP<0>  SKX_EXT_B_BGA1  I86

UPI_CPU1_CPU0_P1P1_DN<0>   @BASEBOARD_FAB2_LIB.BASEBOARD_FAB2(SCH_1):UPI_CPU1_CPU0_P1P1_DN<0>
  U2D1    P3  UPI1_TX_DP<0>  SKX_EXT_B_BGA1  I125
  U5D1   AB19  UPI1_RX_DN<19>  SKX_EXT_B_BGA1  I86

UPI_CPU1_CPU0_P1P1_DN<1>   @BASEBOARD_FAB2_LIB.BASEBOARD_FAB2(SCH_1):UPI_CPU1_CPU0_P1P1_DN<1>
  U2D1    K3  UPI1_TX_DP<1>  SKX_EXT_B_BGA1  I125
  U5D1   Y21  UPI1_RX_DN<18>  SKX_EXT_B_BGA1  I86

UPI_CPU1_CPU0_P1P1_DN<2>   @BASEBOARD_FAB2_LIB.BASEBOARD_FAB2(SCH_1):UPI_CPU1_CPU0_P1P1_DN<2>
  U2D1    K5  UPI1_TX_DN<2>  SKX_EXT_B_BGA1  I125
  U5D1   V19  UPI1_RX_DN<17>  SKX_EXT_B_BGA1  I86

UPI_CPU1_CPU0_P1P1_DN<3>   @BASEBOARD_FAB2_LIB.BASEBOARD_FAB2(SCH_1):UPI_CPU1_CPU0_P1P1_DN<3>
  U2D1    J6  UPI1_TX_DN<3>  SKX_EXT_B_BGA1  I125
  U5D1   P21  UPI1_RX_DN<16>  SKX_EXT_B_BGA1  I86

UPI_CPU1_CPU0_P1P1_DN<4>   @BASEBOARD_FAB2_LIB.BASEBOARD_FAB2(SCH_1):UPI_CPU1_CPU0_P1P1_DN<4>
  U2D1    G6  UPI1_TX_DN<4>  SKX_EXT_B_BGA1  I125
  U5D1   U18  UPI1_RX_DN<15>  SKX_EXT_B_BGA1  I86

UPI_CPU1_CPU0_P1P1_DN<5>   @BASEBOARD_FAB2_LIB.BASEBOARD_FAB2(SCH_1):UPI_CPU1_CPU0_P1P1_DN<5>
  U2D1    H7  UPI1_TX_DN<5>  SKX_EXT_B_BGA1  I125
  U5D1   R20  UPI1_RX_DN<14>  SKX_EXT_B_BGA1  I86

UPI_CPU1_CPU0_P1P1_DN<6>   @BASEBOARD_FAB2_LIB.BASEBOARD_FAB2(SCH_1):UPI_CPU1_CPU0_P1P1_DN<6>
  U2D1    J8  UPI1_TX_DP<6>  SKX_EXT_B_BGA1  I125
  U5D1   W18  UPI1_RX_DN<13>  SKX_EXT_B_BGA1  I86

UPI_CPU1_CPU0_P1P1_DN<7>   @BASEBOARD_FAB2_LIB.BASEBOARD_FAB2(SCH_1):UPI_CPU1_CPU0_P1P1_DN<7>
  U2D1    F9  UPI1_TX_DP<7>  SKX_EXT_B_BGA1  I125
  U5D1   U16  UPI1_RX_DN<12>  SKX_EXT_B_BGA1  I86

UPI_CPU1_CPU0_P1P1_DN<8>   @BASEBOARD_FAB2_LIB.BASEBOARD_FAB2(SCH_1):UPI_CPU1_CPU0_P1P1_DN<8>
  U2D1   E10  UPI1_TX_DP<8>  SKX_EXT_B_BGA1  I125
  U5D1   P17  UPI1_RX_DN<11>  SKX_EXT_B_BGA1  I86

UPI_CPU1_CPU0_P1P1_DN<9>   @BASEBOARD_FAB2_LIB.BASEBOARD_FAB2(SCH_1):UPI_CPU1_CPU0_P1P1_DN<9>
  U2D1   G10  UPI1_TX_DN<9>  SKX_EXT_B_BGA1  I125
  U5D1   R16  UPI1_RX_DN<10>  SKX_EXT_B_BGA1  I86

UPI_CPU1_CPU0_P1P1_DN<10>   @BASEBOARD_FAB2_LIB.BASEBOARD_FAB2(SCH_1):UPI_CPU1_CPU0_P1P1_DN<10>
  U2D1   E12  UPI1_TX_DN<10>  SKX_EXT_B_BGA1  I125
  U5D1   R12  UPI1_RX_DN<9>  SKX_EXT_B_BGA1  I86

UPI_CPU1_CPU0_P1P1_DN<11>   @BASEBOARD_FAB2_LIB.BASEBOARD_FAB2(SCH_1):UPI_CPU1_CPU0_P1P1_DN<11>
  U2D1   F13  UPI1_TX_DP<11>  SKX_EXT_B_BGA1  I125
  U5D1   N14  UPI1_RX_DN<8>  SKX_EXT_B_BGA1  I86

UPI_CPU1_CPU0_P1P1_DN<12>   @BASEBOARD_FAB2_LIB.BASEBOARD_FAB2(SCH_1):UPI_CPU1_CPU0_P1P1_DN<12>
  U2D1   D15  UPI1_TX_DN<12>  SKX_EXT_B_BGA1  I125
  U5D1   L12  UPI1_RX_DN<7>  SKX_EXT_B_BGA1  I86

UPI_CPU1_CPU0_P1P1_DN<13>   @BASEBOARD_FAB2_LIB.BASEBOARD_FAB2(SCH_1):UPI_CPU1_CPU0_P1P1_DN<13>
  U2D1   F15  UPI1_TX_DN<13>  SKX_EXT_B_BGA1  I125
  U5D1   U12  UPI1_RX_DN<6>  SKX_EXT_B_BGA1  I86

UPI_CPU1_CPU0_P1P1_DN<14>   @BASEBOARD_FAB2_LIB.BASEBOARD_FAB2(SCH_1):UPI_CPU1_CPU0_P1P1_DN<14>
  U2D1   H17  UPI1_TX_DN<14>  SKX_EXT_B_BGA1  I125
  U5D1   R10  UPI1_RX_DN<5>  SKX_EXT_B_BGA1  I86

UPI_CPU1_CPU0_P1P1_DN<15>   @BASEBOARD_FAB2_LIB.BASEBOARD_FAB2(SCH_1):UPI_CPU1_CPU0_P1P1_DN<15>
  U2D1   K19  UPI1_TX_DN<15>  SKX_EXT_B_BGA1  I125
  U5D1    P9  UPI1_RX_DN<4>  SKX_EXT_B_BGA1  I86

UPI_CPU1_CPU0_P1P1_DN<16>   @BASEBOARD_FAB2_LIB.BASEBOARD_FAB2(SCH_1):UPI_CPU1_CPU0_P1P1_DN<16>
  U2D1   G18  UPI1_TX_DN<16>  SKX_EXT_B_BGA1  I125
  U5D1    T9  UPI1_RX_DN<3>  SKX_EXT_B_BGA1  I86

UPI_CPU1_CPU0_P1P1_DN<17>   @BASEBOARD_FAB2_LIB.BASEBOARD_FAB2(SCH_1):UPI_CPU1_CPU0_P1P1_DN<17>
  U2D1   J20  UPI1_TX_DN<17>  SKX_EXT_B_BGA1  I125
  U5D1    V7  UPI1_RX_DN<2>  SKX_EXT_B_BGA1  I86

UPI_CPU1_CPU0_P1P1_DN<18>   @BASEBOARD_FAB2_LIB.BASEBOARD_FAB2(SCH_1):UPI_CPU1_CPU0_P1P1_DN<18>
  U2D1   G20  UPI1_TX_DP<18>  SKX_EXT_B_BGA1  I125
  U5D1    P7  UPI1_RX_DN<1>  SKX_EXT_B_BGA1  I86

UPI_CPU1_CPU0_P1P1_DN<19>   @BASEBOARD_FAB2_LIB.BASEBOARD_FAB2(SCH_1):UPI_CPU1_CPU0_P1P1_DN<19>
  U2D1   K21  UPI1_TX_DP<19>  SKX_EXT_B_BGA1  I125
  U5D1    T5  UPI1_RX_DN<0>  SKX_EXT_B_BGA1  I86

UPI_CPU1_CPU0_P1P1_DP<0>   @BASEBOARD_FAB2_LIB.BASEBOARD_FAB2(SCH_1):UPI_CPU1_CPU0_P1P1_DP<0>
  U2D1    M3  UPI1_TX_DN<0>  SKX_EXT_B_BGA1  I125
  U5D1   AA20  UPI1_RX_DP<19>  SKX_EXT_B_BGA1  I86

UPI_CPU1_CPU0_P1P1_DP<1>   @BASEBOARD_FAB2_LIB.BASEBOARD_FAB2(SCH_1):UPI_CPU1_CPU0_P1P1_DP<1>
  U2D1    L4  UPI1_TX_DN<1>  SKX_EXT_B_BGA1  I125
  U5D1   W20  UPI1_RX_DP<18>  SKX_EXT_B_BGA1  I86

UPI_CPU1_CPU0_P1P1_DP<2>   @BASEBOARD_FAB2_LIB.BASEBOARD_FAB2(SCH_1):UPI_CPU1_CPU0_P1P1_DP<2>
  U2D1    M5  UPI1_TX_DP<2>  SKX_EXT_B_BGA1  I125
  U5D1   Y19  UPI1_RX_DP<17>  SKX_EXT_B_BGA1  I86

UPI_CPU1_CPU0_P1P1_DP<3>   @BASEBOARD_FAB2_LIB.BASEBOARD_FAB2(SCH_1):UPI_CPU1_CPU0_P1P1_DP<3>
  U2D1    H5  UPI1_TX_DP<3>  SKX_EXT_B_BGA1  I125
  U5D1   T21  UPI1_RX_DP<16>  SKX_EXT_B_BGA1  I86

UPI_CPU1_CPU0_P1P1_DP<4>   @BASEBOARD_FAB2_LIB.BASEBOARD_FAB2(SCH_1):UPI_CPU1_CPU0_P1P1_DP<4>
  U2D1    F7  UPI1_TX_DP<4>  SKX_EXT_B_BGA1  I125
  U5D1   T19  UPI1_RX_DP<15>  SKX_EXT_B_BGA1  I86

UPI_CPU1_CPU0_P1P1_DP<5>   @BASEBOARD_FAB2_LIB.BASEBOARD_FAB2(SCH_1):UPI_CPU1_CPU0_P1P1_DP<5>
  U2D1    K7  UPI1_TX_DP<5>  SKX_EXT_B_BGA1  I125
  U5D1   P19  UPI1_RX_DP<14>  SKX_EXT_B_BGA1  I86

UPI_CPU1_CPU0_P1P1_DP<6>   @BASEBOARD_FAB2_LIB.BASEBOARD_FAB2(SCH_1):UPI_CPU1_CPU0_P1P1_DP<6>
  U2D1    K9  UPI1_TX_DN<6>  SKX_EXT_B_BGA1  I125
  U5D1   V17  UPI1_RX_DP<13>  SKX_EXT_B_BGA1  I86

UPI_CPU1_CPU0_P1P1_DP<7>   @BASEBOARD_FAB2_LIB.BASEBOARD_FAB2(SCH_1):UPI_CPU1_CPU0_P1P1_DP<7>
  U2D1    D9  UPI1_TX_DN<7>  SKX_EXT_B_BGA1  I125
  U5D1   W16  UPI1_RX_DP<12>  SKX_EXT_B_BGA1  I86

UPI_CPU1_CPU0_P1P1_DP<8>   @BASEBOARD_FAB2_LIB.BASEBOARD_FAB2(SCH_1):UPI_CPU1_CPU0_P1P1_DP<8>
  U2D1   F11  UPI1_TX_DN<8>  SKX_EXT_B_BGA1  I125
  U5D1   N16  UPI1_RX_DP<11>  SKX_EXT_B_BGA1  I86

UPI_CPU1_CPU0_P1P1_DP<9>   @BASEBOARD_FAB2_LIB.BASEBOARD_FAB2(SCH_1):UPI_CPU1_CPU0_P1P1_DP<9>
  U2D1    H9  UPI1_TX_DP<9>  SKX_EXT_B_BGA1  I125
  U5D1   T15  UPI1_RX_DP<10>  SKX_EXT_B_BGA1  I86

UPI_CPU1_CPU0_P1P1_DP<10>   @BASEBOARD_FAB2_LIB.BASEBOARD_FAB2(SCH_1):UPI_CPU1_CPU0_P1P1_DP<10>
  U2D1   G12  UPI1_TX_DP<10>  SKX_EXT_B_BGA1  I125
  U5D1   P13  UPI1_RX_DP<9>  SKX_EXT_B_BGA1  I86

UPI_CPU1_CPU0_P1P1_DP<11>   @BASEBOARD_FAB2_LIB.BASEBOARD_FAB2(SCH_1):UPI_CPU1_CPU0_P1P1_DP<11>
  U2D1   G14  UPI1_TX_DN<11>  SKX_EXT_B_BGA1  I125
  U5D1   M13  UPI1_RX_DP<8>  SKX_EXT_B_BGA1  I86

UPI_CPU1_CPU0_P1P1_DP<12>   @BASEBOARD_FAB2_LIB.BASEBOARD_FAB2(SCH_1):UPI_CPU1_CPU0_P1P1_DP<12>
  U2D1   E14  UPI1_TX_DP<12>  SKX_EXT_B_BGA1  I125
  U5D1   N12  UPI1_RX_DP<7>  SKX_EXT_B_BGA1  I86

UPI_CPU1_CPU0_P1P1_DP<13>   @BASEBOARD_FAB2_LIB.BASEBOARD_FAB2(SCH_1):UPI_CPU1_CPU0_P1P1_DP<13>
  U2D1   H15  UPI1_TX_DP<13>  SKX_EXT_B_BGA1  I125
  U5D1   T11  UPI1_RX_DP<6>  SKX_EXT_B_BGA1  I86

UPI_CPU1_CPU0_P1P1_DP<14>   @BASEBOARD_FAB2_LIB.BASEBOARD_FAB2(SCH_1):UPI_CPU1_CPU0_P1P1_DP<14>
  U2D1   G16  UPI1_TX_DP<14>  SKX_EXT_B_BGA1  I125
  U5D1   U10  UPI1_RX_DP<5>  SKX_EXT_B_BGA1  I86

UPI_CPU1_CPU0_P1P1_DP<15>   @BASEBOARD_FAB2_LIB.BASEBOARD_FAB2(SCH_1):UPI_CPU1_CPU0_P1P1_DP<15>
  U2D1   L18  UPI1_TX_DP<15>  SKX_EXT_B_BGA1  I125
  U5D1   N10  UPI1_RX_DP<4>  SKX_EXT_B_BGA1  I86

UPI_CPU1_CPU0_P1P1_DP<16>   @BASEBOARD_FAB2_LIB.BASEBOARD_FAB2(SCH_1):UPI_CPU1_CPU0_P1P1_DP<16>
  U2D1   J18  UPI1_TX_DP<16>  SKX_EXT_B_BGA1  I125
  U5D1    R8  UPI1_RX_DP<3>  SKX_EXT_B_BGA1  I86

UPI_CPU1_CPU0_P1P1_DP<17>   @BASEBOARD_FAB2_LIB.BASEBOARD_FAB2(SCH_1):UPI_CPU1_CPU0_P1P1_DP<17>
  U2D1   H19  UPI1_TX_DP<17>  SKX_EXT_B_BGA1  I125
  U5D1    U8  UPI1_RX_DP<2>  SKX_EXT_B_BGA1  I86

UPI_CPU1_CPU0_P1P1_DP<18>   @BASEBOARD_FAB2_LIB.BASEBOARD_FAB2(SCH_1):UPI_CPU1_CPU0_P1P1_DP<18>
  U2D1   F21  UPI1_TX_DN<18>  SKX_EXT_B_BGA1  I125
  U5D1    T7  UPI1_RX_DP<1>  SKX_EXT_B_BGA1  I86

UPI_CPU1_CPU0_P1P1_DP<19>   @BASEBOARD_FAB2_LIB.BASEBOARD_FAB2(SCH_1):UPI_CPU1_CPU0_P1P1_DP<19>
  U2D1   H21  UPI1_TX_DN<19>  SKX_EXT_B_BGA1  I125
  U5D1    R6  UPI1_RX_DP<0>  SKX_EXT_B_BGA1  I86

USB2_P01_DN     @BASEBOARD_FAB2_LIB.BASEBOARD_FAB2(SCH_1):USB2_P01_DN
  L1M2     1     A1  CHOKE_4PIN  I30
  R1M6     1      A  RES         I31
  U7C1   BY60  USB2N_1  LBG_CORE_QAT_EXT_D  I74

USB2_P01_DP     @BASEBOARD_FAB2_LIB.BASEBOARD_FAB2(SCH_1):USB2_P01_DP
  L1M2     2     A2  CHOKE_4PIN  I30
  R1M5     1      A  RES         I16
  U7C1   BV60  USB2P_1  LBG_CORE_QAT_EXT_D  I74

USB2_P01_ESD_DN   @BASEBOARD_FAB2_LIB.BASEBOARD_FAB2(SCH_1):USB2_P01_ESD_DN
  CR1M2    2    AC1  DIODEAC_DUAL_ARRAY_SM9  I98
  CR1M2    8   OUT1  DIODEAC_DUAL_ARRAY_SM9  I98
  J9B1     2     DN  CONN9_H51826001_PIP2  I69
  L1M2     4     B2  CHOKE_4PIN  I30
  R1M6     2      B  RES         I31

USB2_P01_ESD_DP   @BASEBOARD_FAB2_LIB.BASEBOARD_FAB2(SCH_1):USB2_P01_ESD_DP
  CR1M2    1    AC0  DIODEAC_DUAL_ARRAY_SM9  I98
  CR1M2    9   OUT0  DIODEAC_DUAL_ARRAY_SM9  I98
  J9B1     3     DP  CONN9_H51826001_PIP2  I69
  L1M2     3     B1  CHOKE_4PIN  I30
  R1M5     2      B  RES         I16

USB2_PCH_BMC_P5_DN   @BASEBOARD_FAB2_LIB.BASEBOARD_FAB2(SCH_1):USB2_PCH_BMC_P5_DN
  U7C1   BY58  USB2N_5  LBG_CORE_QAT_EXT_D  I74
  U9F4   AB20  DN_USB2_DN_USB2_HDN  AST1250_BGA  I347

USB2_PCH_BMC_P5_DP   @BASEBOARD_FAB2_LIB.BASEBOARD_FAB2(SCH_1):USB2_PCH_BMC_P5_DP
  U7C1   BV58  USB2P_5  LBG_CORE_QAT_EXT_D  I74
  U9F4   AB21  DP_USB2_DP_USB2_HDP  AST1250_BGA  I347

USB3_P01_C_TXN   @BASEBOARD_FAB2_LIB.BASEBOARD_FAB2(SCH_1):USB3_P01_C_TXN
  C1M2     2      B  CAP_A       I63
  L1M1     1      1  CHOKE_4PIN_SM_B  I62
  R1M2     1      A  RES         I60

USB3_P01_C_TXP   @BASEBOARD_FAB2_LIB.BASEBOARD_FAB2(SCH_1):USB3_P01_C_TXP
  C1M1     2      B  CAP_A       I64
  L1M1     4      4  CHOKE_4PIN_SM_B  I62
  R1M1     1      A  RES         I61

USB3_P01_FB_RXN   @BASEBOARD_FAB2_LIB.BASEBOARD_FAB2(SCH_1):USB3_P01_FB_RXN
  CR1M1    4    AC2  DIODEAC_DUAL_ARRAY_SM9  I52
  CR1M1    7   OUT2  DIODEAC_DUAL_ARRAY_SM9  I52
  J9B1     5  STDA_SSRXN  CONN9_H51826001_PIP2  I69
  L1L1     2      2  CHOKE_4PIN_SM_B  I51
  R1L42    2      B  RES         I58

USB3_P01_FB_RXP   @BASEBOARD_FAB2_LIB.BASEBOARD_FAB2(SCH_1):USB3_P01_FB_RXP
  CR1M1    5    AC3  DIODEAC_DUAL_ARRAY_SM9  I52
  CR1M1    6   OUT3  DIODEAC_DUAL_ARRAY_SM9  I52
  J9B1     6  STDA_SSRXP  CONN9_H51826001_PIP2  I69
  L1L1     3      3  CHOKE_4PIN_SM_B  I51
  R1L40    2      B  RES         I59

USB3_P01_FB_TXN   @BASEBOARD_FAB2_LIB.BASEBOARD_FAB2(SCH_1):USB3_P01_FB_TXN
  CR1M1    1    AC0  DIODEAC_DUAL_ARRAY_SM9  I52
  CR1M1    9   OUT0  DIODEAC_DUAL_ARRAY_SM9  I52
  J9B1     8  STDA_SSTXN  CONN9_H51826001_PIP2  I69
  L1M1     2      2  CHOKE_4PIN_SM_B  I62
  R1M2     2      B  RES         I60

USB3_P01_FB_TXP   @BASEBOARD_FAB2_LIB.BASEBOARD_FAB2(SCH_1):USB3_P01_FB_TXP
  CR1M1    2    AC1  DIODEAC_DUAL_ARRAY_SM9  I52
  CR1M1    8   OUT1  DIODEAC_DUAL_ARRAY_SM9  I52
  J9B1     9  STDA_SSTXP  CONN9_H51826001_PIP2  I69
  L1M1     3      3  CHOKE_4PIN_SM_B  I62
  R1M1     2      B  RES         I61

USB3_P01_RXN    @BASEBOARD_FAB2_LIB.BASEBOARD_FAB2(SCH_1):USB3_P01_RXN
  L1L1     1      1  CHOKE_4PIN_SM_B  I51
  R1L42    1      A  RES         I58
  U7C1   BK71  USB3_1_RXN  LBG_CORE_QAT_EXT_D  I74

USB3_P01_RXP    @BASEBOARD_FAB2_LIB.BASEBOARD_FAB2(SCH_1):USB3_P01_RXP
  L1L1     4      4  CHOKE_4PIN_SM_B  I51
  R1L40    1      A  RES         I59
  U7C1   BK69  USB3_1_RXP  LBG_CORE_QAT_EXT_D  I74

USB3_P01_TXN    @BASEBOARD_FAB2_LIB.BASEBOARD_FAB2(SCH_1):USB3_P01_TXN
  C1M2     1      A  CAP_A       I63
  U7C1   BL52  USB3_1_TXN  LBG_CORE_QAT_EXT_D  I74

USB3_P01_TXP    @BASEBOARD_FAB2_LIB.BASEBOARD_FAB2(SCH_1):USB3_P01_TXP
  C1M1     1      A  CAP_A       I64
  U7C1   BK54  USB3_1_TXP  LBG_CORE_QAT_EXT_D  I74

USB_PCH_BMC_P4_DN   @BASEBOARD_FAB2_LIB.BASEBOARD_FAB2(SCH_1):USB_PCH_BMC_P4_DN
  R1U52    2      B  RES         I557
  U7C1   BY62  USB2N_4  LBG_CORE_QAT_EXT_D  I74
  U9F4    K3  DN_USB11_DN_USB11_HDN2  AST1250_BGA  I347

USB_PCH_BMC_P4_DP   @BASEBOARD_FAB2_LIB.BASEBOARD_FAB2(SCH_1):USB_PCH_BMC_P4_DP
  U7C1   BV62  USB2P_4  LBG_CORE_QAT_EXT_D  I74
  U9F4    K4  DP_USB11_DP_USB11_HDP2  AST1250_BGA  I347

VID_PCH_CORE_PVNN_AUX_VID_0   @BASEBOARD_FAB2_LIB.BASEBOARD_FAB2(SCH_1):VID_PCH_CORE_PVNN_AUX_VID_0
  EU8A1   13    MP0  PXE1110B_QFN  I229
  R2L26    2      B  RES         I236
  U7C1   BL7  GPP_B0_CORE_VID0  LBG_CORE_QAT_EXT_D  I115

VID_PCH_CORE_PVNN_AUX_VID_1   @BASEBOARD_FAB2_LIB.BASEBOARD_FAB2(SCH_1):VID_PCH_CORE_PVNN_AUX_VID_1
  EU8A1   14    MP1  PXE1110B_QFN  I229
  R2L25    2      B  RES         I235
  U7C1   BH9  GPP_B1_CORE_VID1  LBG_CORE_QAT_EXT_D  I115

VR_COMP_PVPP_ABC   @BASEBOARD_FAB2_LIB.BASEBOARD_FAB2(SCH_1):VR_COMP_PVPP_ABC
  C7F13    1      A  CAP         I219
  R7F17    2      B  RES         I218

VR_COMP_PVPP_ABC_3   @BASEBOARD_FAB2_LIB.BASEBOARD_FAB2(SCH_1):VR_COMP_PVPP_ABC_3
  C7F9     2      B  CAP         I199
  C7F12    2      B  CAP         I200
  EU7F1    3   COMP  NCP3232L_SM  I193

VR_COMP_PVPP_DEF   @BASEBOARD_FAB2_LIB.BASEBOARD_FAB2(SCH_1):VR_COMP_PVPP_DEF
  C7B13    1      A  CAP         I302
  R7B18    2      B  RES         I298

VR_COMP_PVPP_DEF_3   @BASEBOARD_FAB2_LIB.BASEBOARD_FAB2(SCH_1):VR_COMP_PVPP_DEF_3
  C7B10    2      B  CAP         I301
  C7B14    2      B  CAP         I306
  EU7B1    3   COMP  NCP3232L_SM  I214

VR_COMP_PVPP_GHJ   @BASEBOARD_FAB2_LIB.BASEBOARD_FAB2(SCH_1):VR_COMP_PVPP_GHJ
  C4G11    1      A  CAP         I267
  R4G10    2      B  RES         I266

VR_COMP_PVPP_GHJ_3   @BASEBOARD_FAB2_LIB.BASEBOARD_FAB2(SCH_1):VR_COMP_PVPP_GHJ_3
  C4G6     2      B  CAP         I273
  C4G10    2      B  CAP         I274
  EU4G1    3   COMP  NCP3232L_SM  I225

VR_COMP_PVPP_KLM   @BASEBOARD_FAB2_LIB.BASEBOARD_FAB2(SCH_1):VR_COMP_PVPP_KLM
  C4B7     1      A  CAP         I218
  R4B9     2      B  RES         I219

VR_COMP_PVPP_KLM_3   @BASEBOARD_FAB2_LIB.BASEBOARD_FAB2(SCH_1):VR_COMP_PVPP_KLM_3
  C4B4     2      B  CAP         I212
  C4B9     2      B  CAP         I211
  EU4A3    3   COMP  NCP3232L_SM  I184

VR_COMP_RC_PVPP_ABC   @BASEBOARD_FAB2_LIB.BASEBOARD_FAB2(SCH_1):VR_COMP_RC_PVPP_ABC
  C7F12    1      A  CAP         I200
  R7F18    1      A  RES         I201

VR_COMP_RC_PVPP_DEF   @BASEBOARD_FAB2_LIB.BASEBOARD_FAB2(SCH_1):VR_COMP_RC_PVPP_DEF
  C7B14    1      A  CAP         I306
  R7B16    1      A  RES         I300

VR_COMP_RC_PVPP_GHJ   @BASEBOARD_FAB2_LIB.BASEBOARD_FAB2(SCH_1):VR_COMP_RC_PVPP_GHJ
  C4G10    1      A  CAP         I274
  R4G13    1      A  RES         I272

VR_COMP_RC_PVPP_KLM   @BASEBOARD_FAB2_LIB.BASEBOARD_FAB2(SCH_1):VR_COMP_RC_PVPP_KLM
  C4B9     1      A  CAP         I211
  R4B8     1      A  RES         I213

VR_FB_PVPP_ABC   @BASEBOARD_FAB2_LIB.BASEBOARD_FAB2(SCH_1):VR_FB_PVPP_ABC
  C7F9     1      A  CAP         I199
  C7F13    2      B  CAP         I219
  EU7F1    2     FB  NCP3232L_SM  I193
  R7F11    1      A  RES         I166
  R7F13    2      B  RES         I167
  R7F18    2      B  RES         I201

VR_FB_PVPP_DEF   @BASEBOARD_FAB2_LIB.BASEBOARD_FAB2(SCH_1):VR_FB_PVPP_DEF
  C7B10    1      A  CAP         I301
  C7B13    2      B  CAP         I302
  EU7B1    2     FB  NCP3232L_SM  I214
  R7B13    1      A  RES         I304
  R7B15    2      B  RES         I303
  R7B16    2      B  RES         I300

VR_FB_PVPP_GHJ   @BASEBOARD_FAB2_LIB.BASEBOARD_FAB2(SCH_1):VR_FB_PVPP_GHJ
  C4G6     1      A  CAP         I273
  C4G11    2      B  CAP         I267
  EU4G1    2     FB  NCP3232L_SM  I225
  R4G7     2      B  RES         I270
  R4G9     1      A  RES         I269
  R4G13    2      B  RES         I272

VR_FB_PVPP_KLM   @BASEBOARD_FAB2_LIB.BASEBOARD_FAB2(SCH_1):VR_FB_PVPP_KLM
  C4B4     1      A  CAP         I212
  C4B7     2      B  CAP         I218
  EU4A3    2     FB  NCP3232L_SM  I184
  R4B4     1      A  RES         I216
  R4B5     2      B  RES         I215
  R4B8     2      B  RES         I213

VR_FET_SW_P12V_PVCCIN_CPU0_R   @BASEBOARD_FAB2_LIB.BASEBOARD_FAB2(SCH_1):VR_FET_SW_P12V_PVCCIN_CPU0_R
  C4C2     1      A  CAP_A       I51
  L4C1     2    INB  INDUCTOR    I46
  R4C6     1      A  RES         I45
  U4C1     3    VCC  ADM4073_SM  I53
  U4C1     4    RSP  ADM4073_SM  I53

VR_FET_SW_P12V_PVCCIN_CPU1_R   @BASEBOARD_FAB2_LIB.BASEBOARD_FAB2(SCH_1):VR_FET_SW_P12V_PVCCIN_CPU1_R
  C1B16    1      A  CAP_A       I30
  L1B2     2    INB  INDUCTOR    I32
  R1B20    1      A  RES         I39
  U1B3     3    VCC  ADM4073_SM  I52
  U1B3     4    RSP  ADM4073_SM  I52

VR_FET_SW_P12V_STBY_P3V3_STBY   @BASEBOARD_FAB2_LIB.BASEBOARD_FAB2(SCH_1):VR_FET_SW_P12V_STBY_P3V3_STBY
  C8E10    1      A  CAP         I137
  C8E11    1      A  CAP         I135
  C8E14    1      A  CAP_0402    I139
  C9F1     1      A  CAP         I134
  EU8E1    2    VIN  CSD87384M_SM  I170
  FB9E1    2      B  FERRITE_SM  I132

VR_FET_SW_P12V_STBY_PVCCIN_CPU0   @BASEBOARD_FAB2_LIB.BASEBOARD_FAB2(SCH_1):VR_FET_SW_P12V_STBY_PVCCIN_CPU0
  C4C9     1      A  CAP_0402    I32
  C4C10    1      A  CAP_A       I31
  C4C12    1      A  CAPP        I67
  C4C18    1      A  CAP_0402    I36
  C4C19    1      A  CAP_A       I35
  C4D2     1      A  CAPP        I48
  C4D10    1      A  CAP_0402    I53
  C4D11    1      A  CAP_A       I52
  C4D30    1      A  CAP_0402    I47
  C4D35    1      A  CAP_A       I46
  C4D48    1      A  CAP_0402    I47
  C4D49    1      A  CAP_A       I46
  C4E8     1      A  CAP         I29
  C4E9     1      A  CAP          I8
  C4E13    1      A  CAP_A       I77
  C4E14    1      A  CAP         I31
  C4E15    1      A  CAP_0402    I79
  C4E16    1      A  CAPP        I50
  C4E19    1      A  CAP_0402    I36
  C4E20    1      A  CAP_A       I35
  C6N2     1      A  CAP         I33
  C6N3     1      A  CAP         I34
  C6N6     1      A  CAP         I35
  C6N8     1      A  CAP         I51
  C6N10    1      A  CAP         I37
  C6N11    1      A  CAP         I42
  C6P7     1      A  CAP         I59
  C6P13    1      A  CAP         I38
  C6P15    1      A  CAP         I58
  C6P17    1      A  CAP         I38
  C6P19    1      A  CAP         I54
  C6P20    1      A  CAP         I57
  C6P22    1      A  CAP         I49
  C6P24    1      A  CAP          I1
  C6R4     1      A  CAP         I48
  C6R6     1      A  CAP          I2
  C6R8     1      A  CAP         I83
  C6R10    1      A  CAP         I81
  C6R11    1      A  CAP         I37
  C6R13    1      A  CAP         I42
  C6R14    1      A  CAP         I80
  EU4C1   25  VIN<0>  IR354XX_SM  I46
  EU4C1   30  VIN<1>  IR354XX_SM  I46
  EU4C2   25  VIN<0>  IR354XX_SM  I71
  EU4C2   30  VIN<1>  IR354XX_SM  I71
  EU4D1   25  VIN<0>  IR354XX_SM  I71
  EU4D1   30  VIN<1>  IR354XX_SM  I71
  EU4D3   25  VIN<0>  IR354XX_SM  I70
  EU4D3   30  VIN<1>  IR354XX_SM  I70
  EU4D6   25  VIN<0>  IR354XX_SM  I64
  EU4D6   30  VIN<1>  IR354XX_SM  I64
  EU4E1   25  VIN<0>  IR354XX_SM  I63
  EU4E1   30  VIN<1>  IR354XX_SM  I63
  EU4E2   25  VIN<0>  IR354XX_SM  I126
  EU4E2   30  VIN<1>  IR354XX_SM  I126
  R4C6     2      B  RES         I45
  R4D27    1      A  RES         I54
  R4D60    1      A  RES         I31
  U4C1     5    RSN  ADM4073_SM  I53

VR_FET_SW_P12V_STBY_PVCCIN_CPU1   @BASEBOARD_FAB2_LIB.BASEBOARD_FAB2(SCH_1):VR_FET_SW_P12V_STBY_PVCCIN_CPU1
  C1C1     1      A  CAPP        I35
  C1C2     1      A  CAPP        I38
  C1C15    1      A  CAP_0402    I28
  C1C17    1      A  CAP_A       I27
  C1C25    1      A  CAP_A       I17
  C1C26    1      A  CAP_0402    I16
  C1D12    1      A  CAP_0402    I52
  C1D13    1      A  CAP_A       I51
  C1D23    1      A  CAP_0402    I45
  C1D28    1      A  CAP_A       I44
  C1D34    1      A  CAP_A       I41
  C1D35    1      A  CAP_0402    I42
  C1E13    1      A  CAP_0402    I34
  C1E14    1      A  CAP_A       I33
  C1E18    1      A  CAPP        I37
  C9N13    1      A  CAP         I35
  C9N19    1      A  CAP         I36
  C9N21    1      A  CAP         I38
  C9N25    1      A  CAP          I8
  C9N26    1      A  CAP          I7
  C9N27    1      A  CAP          I5
  C9P1     1      A  CAP         I59
  C9P2     1      A  CAP         I60
  C9P4     1      A  CAP         I53
  C9P7     1      A  CAP         I54
  C9P9     1      A  CAP         I55
  C9P22    1      A  CAP         I50
  C9P24    1      A  CAP         I58
  C9P25    1      A  CAP         I51
  C9P26    1      A  CAP         I54
  C9R7     1      A  CAP         I43
  C9R10    1      A  CAP         I44
  C9R11    1      A  CAP         I48
  EU1C1   25  VIN<0>  IR354XX_SM  I51
  EU1C1   30  VIN<1>  IR354XX_SM  I51
  EU1C3   25  VIN<0>  IR354XX_SM  I56
  EU1C3   30  VIN<1>  IR354XX_SM  I56
  EU1D1   25  VIN<0>  IR354XX_SM  I71
  EU1D1   30  VIN<1>  IR354XX_SM  I71
  EU1D3   25  VIN<0>  IR354XX_SM  I27
  EU1D3   30  VIN<1>  IR354XX_SM  I27
  EU1D4   25  VIN<0>  IR354XX_SM  I24
  EU1D4   30  VIN<1>  IR354XX_SM  I24
  EU1E2   25  VIN<0>  IR354XX_SM  I20
  EU1E2   30  VIN<1>  IR354XX_SM  I20
  R1B20    2      B  RES         I39
  R1C13    1      A  RES         I49
  U1B3     5    RSN  ADM4073_SM  I52

VR_FET_SW_P12V_STBY_PVCCIO_CPU0   @BASEBOARD_FAB2_LIB.BASEBOARD_FAB2(SCH_1):VR_FET_SW_P12V_STBY_PVCCIO_CPU0
  C3N33    1      A  CAP         I41
  C3N34    1      A  CAP         I43
  C3N36    1      A  CAP         I40
  C7C7     1      A  CAP         I54
  C7C8     1      A  CAP         I51
  C7C11    1      A  CAP_A       I38
  C7C12    1      A  CAP_0402    I39
  EU7C1   25  VIN<0>  IR354XX_SM  I101
  EU7C1   30  VIN<1>  IR354XX_SM  I101
  L7C1     2    INB  INDUCTOR    I56
  R3P12    1      A  RES         I31

VR_FET_SW_P12V_STBY_PVDDQ_ABC   @BASEBOARD_FAB2_LIB.BASEBOARD_FAB2(SCH_1):VR_FET_SW_P12V_STBY_PVDDQ_ABC
  C3U2     1      A  CAP         I45
  C3U3     1      A  CAP         I46
  C3U4     1      A  CAP         I47
  C3U6     1      A  CAP         I84
  C3U7     1      A  CAP         I81
  C3U9     1      A  CAP         I80
  C7G2     1      A  CAPP        I175
  C7G29    1      A  CAP_A       I51
  C7G30    1      A  CAP_0402    I79
  C7G36    1      A  CAP_A       I78
  C7G37    1      A  CAP_0402    I48
  EU7G2   25  VIN<0>  IR354XX_SM  I102
  EU7G2   30  VIN<1>  IR354XX_SM  I102
  EU7G3   25  VIN<0>  IR354XX_SM  I103
  EU7G3   30  VIN<1>  IR354XX_SM  I103
  L7F2     2    INB  INDUCTOR    I124
  R7F34    1      A  RES         I336

VR_FET_SW_P12V_STBY_PVDDQ_DEF   @BASEBOARD_FAB2_LIB.BASEBOARD_FAB2(SCH_1):VR_FET_SW_P12V_STBY_PVDDQ_DEF
  C3L2     1      A  CAP         I45
  C3L4     1      A  CAP         I46
  C3L7     1      A  CAP         I31
  C3L8     1      A  CAP         I26
  C3L9     1      A  CAP         I29
  C3L10    1      A  CAP         I32
  C3L11    1      A  CAP         I24
  C3L12    1      A  CAP         I23
  C3L13    1      A  CAP         I47
  C3L15    1      A  CAP         I84
  C3L16    1      A  CAP         I81
  C3L17    1      A  CAP         I80
  C7A5     1      A  CAP_A       I51
  C7A7     1      A  CAP_0402    I22
  C7A9     1      A  CAP_0402    I33
  C7A11    1      A  CAP_0402    I48
  C7A13    1      A  CAP         I63
  C7A14    1      A  CAP         I65
  C7A19    1      A  CAPP        I175
  C7A20    1      A  CAP_A       I78
  C7A21    1      A  CAP_0402    I79
  C7A39    1      A  CAP_A       I20
  C7A40    1      A  CAP_A       I35
  EU7A1   25  VIN<0>  IR354XX_SM  I106
  EU7A1   30  VIN<1>  IR354XX_SM  I106
  EU7A2   25  VIN<0>  IR354XX_SM  I117
  EU7A2   30  VIN<1>  IR354XX_SM  I117
  EU7A3   25  VIN<0>  IR354XX_SM  I116
  EU7A3   30  VIN<1>  IR354XX_SM  I116
  EU7A4   25  VIN<0>  IR354XX_SM  I107
  EU7A4   30  VIN<1>  IR354XX_SM  I107
  L7A5     2    INB  INDUCTOR    I124
  R3L12    1      A  RES         I53
  R8A4     1      A  RES         I165

VR_FET_SW_P12V_STBY_PVDDQ_GHJ   @BASEBOARD_FAB2_LIB.BASEBOARD_FAB2(SCH_1):VR_FET_SW_P12V_STBY_PVDDQ_GHJ
  C1F27    1      A  CAP_0402    I48
  C1F28    1      A  CAP_A       I78
  C1G2     1      A  CAP         I194
  C1G7     1      A  CAP         I195
  C1G12    1      A  CAP         I193
  C1G13    1      A  CAP_0402    I79
  C1G14    1      A  CAP_A       I51
  C1G15    1      A  CAP         I192
  C9T4     1      A  CAP         I47
  C9T6     1      A  CAP         I81
  C9T9     1      A  CAP         I84
  C9U3     1      A  CAP         I80
  C9U4     1      A  CAP         I46
  C9U6     1      A  CAP         I45
  EU1F1   25  VIN<0>  IR354XX_SM  I111
  EU1F1   30  VIN<1>  IR354XX_SM  I111
  EU1G1   25  VIN<0>  IR354XX_SM  I110
  EU1G1   30  VIN<1>  IR354XX_SM  I110
  L1F1     2    INB  INDUCTOR    I124
  R9U11    1      A  RES         I57

VR_FET_SW_P12V_STBY_PVDDQ_KLM   @BASEBOARD_FAB2_LIB.BASEBOARD_FAB2(SCH_1):VR_FET_SW_P12V_STBY_PVDDQ_KLM
  C1A9     1      A  CAP_0402    I79
  C1A10    1      A  CAP_A       I51
  C1A19    1      A  CAP_0402    I48
  C1A20    1      A  CAP_A       I78
  C1B10    1      A  CAPP        I175
  C9L5     1      A  CAP         I80
  C9L6     1      A  CAP         I47
  C9L10    1      A  CAP         I46
  C9L11    1      A  CAP         I45
  C9L13    1      A  CAP         I81
  C9L14    1      A  CAP         I84
  EU1A1   25  VIN<0>  IR354XX_SM  I102
  EU1A1   30  VIN<1>  IR354XX_SM  I102
  EU1A2   25  VIN<0>  IR354XX_SM  I101
  EU1A2   30  VIN<1>  IR354XX_SM  I101
  L1B1     2    INB  INDUCTOR    I124
  R9M8     1      A  RES         I57

VR_FET_SW_P12V_STBY_PVPP_ABC   @BASEBOARD_FAB2_LIB.BASEBOARD_FAB2(SCH_1):VR_FET_SW_P12V_STBY_PVPP_ABC
  C3T8     1      A  CAP         I210
  C3T10    1      A  CAP_0402    I161
  C3T12    1      A  CAP         I215
  C3T14    1      A  CAP         I211
  C7F5     1      A  CAP         I209
  C7F6     1      A  CAP_A       I205
  C7F7     1      A  CAP         I151
  EU7F1    8  VIN<0>  NCP3232L_SM  I193
  EU7F1    9  VIN<1>  NCP3232L_SM  I193
  EU7F1   10  VIN<2>  NCP3232L_SM  I193
  EU7F1   11  VIN<3>  NCP3232L_SM  I193
  EU7F1   12  VIN<4>  NCP3232L_SM  I193
  EU7F1   13  VIN<5>  NCP3232L_SM  I193
  EU7F1   14  VIN<6>  NCP3232L_SM  I193
  EU7F1   39    VCC  NCP3232L_SM  I193
  EU7F1   42  VIN<7>  NCP3232L_SM  I193
  FB7F1    2      B  FERRITE_SM  I162

VR_FET_SW_P12V_STBY_PVPP_DEF   @BASEBOARD_FAB2_LIB.BASEBOARD_FAB2(SCH_1):VR_FET_SW_P12V_STBY_PVPP_DEF
  C3M8     1      A  CAP         I259
  C3M9     1      A  CAP_0402    I207
  C3M15    1      A  CAP         I260
  C3M16    1      A  CAP         I261
  C7B5     1      A  CAP         I262
  C7B6     1      A  CAP_A       I252
  C7B8     1      A  CAP         I202
  EU7B1    8  VIN<0>  NCP3232L_SM  I214
  EU7B1    9  VIN<1>  NCP3232L_SM  I214
  EU7B1   10  VIN<2>  NCP3232L_SM  I214
  EU7B1   11  VIN<3>  NCP3232L_SM  I214
  EU7B1   12  VIN<4>  NCP3232L_SM  I214
  EU7B1   13  VIN<5>  NCP3232L_SM  I214
  EU7B1   14  VIN<6>  NCP3232L_SM  I214
  EU7B1   39    VCC  NCP3232L_SM  I214
  EU7B1   42  VIN<7>  NCP3232L_SM  I214
  FB7B1    2      B  FERRITE_SM  I200

VR_FET_SW_P12V_STBY_PVPP_GHJ   @BASEBOARD_FAB2_LIB.BASEBOARD_FAB2(SCH_1):VR_FET_SW_P12V_STBY_PVPP_GHJ
  C4G2     1      A  CAP         I253
  C4G4     1      A  CAP_0402    I196
  C4G5     1      A  CAP         I189
  C6U4     1      A  CAP         I248
  C6U5     1      A  CAP_A       I242
  C6U7     1      A  CAP         I254
  C6U8     1      A  CAP         I255
  EU4G1    8  VIN<0>  NCP3232L_SM  I225
  EU4G1    9  VIN<1>  NCP3232L_SM  I225
  EU4G1   10  VIN<2>  NCP3232L_SM  I225
  EU4G1   11  VIN<3>  NCP3232L_SM  I225
  EU4G1   12  VIN<4>  NCP3232L_SM  I225
  EU4G1   13  VIN<5>  NCP3232L_SM  I225
  EU4G1   14  VIN<6>  NCP3232L_SM  I225
  EU4G1   39    VCC  NCP3232L_SM  I225
  EU4G1   42  VIN<7>  NCP3232L_SM  I225
  FB4G1    2      B  FERRITE_SM  I198

VR_FET_SW_P12V_STBY_PVPP_KLM   @BASEBOARD_FAB2_LIB.BASEBOARD_FAB2(SCH_1):VR_FET_SW_P12V_STBY_PVPP_KLM
  C4A19    1      A  CAP         I205
  C4A20    1      A  CAP_A       I199
  C4B1     1      A  CAP         I130
  C6L10    1      A  CAP         I202
  C6L11    1      A  CAP_0402    I152
  C6M3     1      A  CAP         I203
  C6M5     1      A  CAP         I204
  EU4A3    8  VIN<0>  NCP3232L_SM  I184
  EU4A3    9  VIN<1>  NCP3232L_SM  I184
  EU4A3   10  VIN<2>  NCP3232L_SM  I184
  EU4A3   11  VIN<3>  NCP3232L_SM  I184
  EU4A3   12  VIN<4>  NCP3232L_SM  I184
  EU4A3   13  VIN<5>  NCP3232L_SM  I184
  EU4A3   14  VIN<6>  NCP3232L_SM  I184
  EU4A3   39    VCC  NCP3232L_SM  I184
  EU4A3   42  VIN<7>  NCP3232L_SM  I184
  FB4A1    2      B  FERRITE_SM  I154

VR_FET_SW_P5V_STBY_PVIN   @BASEBOARD_FAB2_LIB.BASEBOARD_FAB2(SCH_1):VR_FET_SW_P5V_STBY_PVIN
  C7E11    1      A  CAP         I39
  C7E12    1      A  CAP         I47
  C7E13    1      A  CAP         I45
  EU7E2    4  PVIN<0>  TPS54821_LCC  I83
  EU7E2    5  PVIN<1>  TPS54821_LCC  I83
  FB7E1    2      B  FERRITE_SM  I82
  R7E17    1      A  RES         I37

VR_P1V05_PCH_BIREF1   @BASEBOARD_FAB2_LIB.BASEBOARD_FAB2(SCH_1):VR_P1V05_PCH_BIREF1
  CTI67    1      A  CAP_A       I124
  EU7A2   39  REFIN  IR354XX_SM  I117
  EU8A1   25  BIREF1  PXE1110B_QFN  I229
  R2L7     2      B  RES         I225

VR_P1V05_PCH_STBY_AVSP   @BASEBOARD_FAB2_LIB.BASEBOARD_FAB2(SCH_1):VR_P1V05_PCH_STBY_AVSP
  C2L2     1      A  CAP         I153
  EU8A1   29  BVSEN  PXE1110B_QFN  I229
  R2L8     2      B  RES         I154

VR_P1V05_PCH_STBY_OCSET   @BASEBOARD_FAB2_LIB.BASEBOARD_FAB2(SCH_1):VR_P1V05_PCH_STBY_OCSET
  EU7A2   37  OCSET  IR354XX_SM  I117
  R3L14    1      A  RES         I120

VR_P1V05_PCH_STBY_PH1_BOOT   @BASEBOARD_FAB2_LIB.BASEBOARD_FAB2(SCH_1):VR_P1V05_PCH_STBY_PH1_BOOT
  C7A44    1      A  CAP_0402    I34
  RTI46    1      1  2D2R2F-GP_SMD-RG1  I123

VR_P1V05_PCH_STBY_PH1_BOOT_R   @BASEBOARD_FAB2_LIB.BASEBOARD_FAB2(SCH_1):VR_P1V05_PCH_STBY_PH1_BOOT_R
  EU7A2   33  BOOST  IR354XX_SM  I117
  RTI46    2      2  2D2R2F-GP_SMD-RG1  I123

VR_P1V05_PCH_STBY_PH1_PHASE   @BASEBOARD_FAB2_LIB.BASEBOARD_FAB2(SCH_1):VR_P1V05_PCH_STBY_PH1_PHASE
  C7A44    2      B  CAP_0402    I34
  EU7A2   32  PHASE  IR354XX_SM  I117

VR_P1V05_PCH_STBY_PH1_PHASE_SW   @BASEBOARD_FAB2_LIB.BASEBOARD_FAB2(SCH_1):VR_P1V05_PCH_STBY_PH1_PHASE_SW
  CTI68    1      1  SC2K2P50V3KX-GP_SMD-BCG6  I140
  EU7A2   10     SW  IR354XX_SM  I117
  L7A4     1    INA  INDUCTOR    I45

VR_P1V05_PCH_STBY_PH1_VCIN   @BASEBOARD_FAB2_LIB.BASEBOARD_FAB2(SCH_1):VR_P1V05_PCH_STBY_PH1_VCIN
  C7A10    1      A  CAP_0402    I36
  EU7A2    3    VCC  IR354XX_SM  I117
  R3L4     1      A  RES         I41

VR_P1V05_PCH_STBY_PWM1   @BASEBOARD_FAB2_LIB.BASEBOARD_FAB2(SCH_1):VR_P1V05_PCH_STBY_PWM1
  EU7A2   34    PWM  IR354XX_SM  I117
  EU8A1    3  BPWM1  PXE1110B_QFN  I229

VR_P1V26_BMC_STBY_FB   @BASEBOARD_FAB2_LIB.BASEBOARD_FAB2(SCH_1):VR_P1V26_BMC_STBY_FB
  EU9F1    4  ADJ_NC  RT9059_DFN  I40
  R9F6     2      B  RES         I17
  R9F8     2      B  RES         I14

VR_P1V538_BMC_STBY_FB   @BASEBOARD_FAB2_LIB.BASEBOARD_FAB2(SCH_1):VR_P1V538_BMC_STBY_FB
  EU9F2    4  ADJ_NC  RT9059_DFN  I70
  R9F31    2      B  RES         I14
  R9F32    2      B  RES         I15

VR_P1V8_PCH_STBY_FB   @BASEBOARD_FAB2_LIB.BASEBOARD_FAB2(SCH_1):VR_P1V8_PCH_STBY_FB
  EU8A2    4  ADJ_NC  RT9059_DFN  I86
  R2L19    1      A  RES         I80
  R2L20    2      B  RES         I81

VR_P3V3_STBY_BOOT   @BASEBOARD_FAB2_LIB.BASEBOARD_FAB2(SCH_1):VR_P3V3_STBY_BOOT
  EU8F1    4   BOOT  RT8240_QFN  I125
  R8E35    1      A  RES         I127

VR_P3V3_STBY_BOOT_R   @BASEBOARD_FAB2_LIB.BASEBOARD_FAB2(SCH_1):VR_P3V3_STBY_BOOT_R
  C8E12    2      B  CAP         I129
  R8E35    2      B  RES         I127

VR_P3V3_STBY_EN   @BASEBOARD_FAB2_LIB.BASEBOARD_FAB2(SCH_1):VR_P3V3_STBY_EN
  EU8F1    8     EN  RT8240_QFN  I125
  R8E40    2      B  RES         I177
  R8F2     2      B  RES         I176

VR_P3V3_STBY_LGATE   @BASEBOARD_FAB2_LIB.BASEBOARD_FAB2(SCH_1):VR_P3V3_STBY_LGATE
  EU8E1    4     BG  CSD87384M_SM  I170
  EU8F1    1  LGATE  RT8240_QFN  I125

VR_P3V3_STBY_OCSELECT   @BASEBOARD_FAB2_LIB.BASEBOARD_FAB2(SCH_1):VR_P3V3_STBY_OCSELECT
  EU8F1   10     CS  RT8240_QFN  I125
  R8F9     1      A  RES         I106

VR_P3V3_STBY_PHASE   @BASEBOARD_FAB2_LIB.BASEBOARD_FAB2(SCH_1):VR_P3V3_STBY_PHASE
  C8E12    1      A  CAP         I129
  C8F3     1      A  CAP         I163
  EU8E1    5    VSW  CSD87384M_SM  I170
  EU8F1    2  PHASE  RT8240_QFN  I125
  L8F1     1    INA  INDUCTOR    I173

VR_P3V3_STBY_SNUB   @BASEBOARD_FAB2_LIB.BASEBOARD_FAB2(SCH_1):VR_P3V3_STBY_SNUB
  C8F3     2      B  CAP         I163
  R8F3     1      A  RES         I148

VR_P3V3_STBY_UGATE   @BASEBOARD_FAB2_LIB.BASEBOARD_FAB2(SCH_1):VR_P3V3_STBY_UGATE
  EU8E1    1     TG  CSD87384M_SM  I170
  EU8F1    3  UGATE  RT8240_QFN  I125

VR_P5V_STBY_BOOT   @BASEBOARD_FAB2_LIB.BASEBOARD_FAB2(SCH_1):VR_P5V_STBY_BOOT
  C8E6     1      A  CAP         I12
  EU7E2   13   BOOT  TPS54821_LCC  I83

VR_P5V_STBY_COMP   @BASEBOARD_FAB2_LIB.BASEBOARD_FAB2(SCH_1):VR_P5V_STBY_COMP
  C8E16    1      A  CAP         I53
  EU7E2    8   COMP  TPS54821_LCC  I83
  R8E39    1      A  RES         I54

VR_P5V_STBY_EN   @BASEBOARD_FAB2_LIB.BASEBOARD_FAB2(SCH_1):VR_P5V_STBY_EN
  EU7E2   10     EN  TPS54821_LCC  I83
  R8E33    2      B  RES         I91

VR_P5V_STBY_PHASE   @BASEBOARD_FAB2_LIB.BASEBOARD_FAB2(SCH_1):VR_P5V_STBY_PHASE
  C8E6     2      B  CAP         I12
  EU7E2   11  PH<0>  TPS54821_LCC  I83
  EU7E2   12  PH<1>  TPS54821_LCC  I83
  L8E1     1    INA  INDUCTOR    I90

VR_P5V_STBY_RC_COMP   @BASEBOARD_FAB2_LIB.BASEBOARD_FAB2(SCH_1):VR_P5V_STBY_RC_COMP
  C8F1     1      A  CAP         I57
  R8E39    2      B  RES         I54

VR_P5V_STBY_RT   @BASEBOARD_FAB2_LIB.BASEBOARD_FAB2(SCH_1):VR_P5V_STBY_RT
  EU7E2    1  RT_CLK  TPS54821_LCC  I83
  R7E14    1      A  RES         I18

VR_P5V_STBY_SS   @BASEBOARD_FAB2_LIB.BASEBOARD_FAB2(SCH_1):VR_P5V_STBY_SS
  C8E15    1      A  CAP         I63
  EU7E2    9  SS_TR  TPS54821_LCC  I83

VR_P5V_STBY_VIN   @BASEBOARD_FAB2_LIB.BASEBOARD_FAB2(SCH_1):VR_P5V_STBY_VIN
  C7E14    1      A  CAP_0402    I30
  EU7E2    6    VIN  TPS54821_LCC  I83
  R7E17    2      B  RES         I37

VR_P5V_STBY_VSENSE   @BASEBOARD_FAB2_LIB.BASEBOARD_FAB2(SCH_1):VR_P5V_STBY_VSENSE
  EU7E2    7  VSENSE  TPS54821_LCC  I83
  R7E16    1      A  RES         I51
  R7F1     2      B  RES         I50

VR_P5V_STBY_VSENSE_R   @BASEBOARD_FAB2_LIB.BASEBOARD_FAB2(SCH_1):VR_P5V_STBY_VSENSE_R
  R7F1     1      A  RES         I50
  R8E37    1      A  RES         I78

VR_PVCCIN_CPU0_AIREF1   @BASEBOARD_FAB2_LIB.BASEBOARD_FAB2(SCH_1):VR_PVCCIN_CPU0_AIREF1
  CTI1     1      A  CAP_A       I70
  EU4D4   23  AIREF1  PXE1610B_QFN  I155
  EU4E1   39  REFIN  IR354XX_SM  I63
  R6P43    2      B  RES         I150

VR_PVCCIN_CPU0_AIREF2   @BASEBOARD_FAB2_LIB.BASEBOARD_FAB2(SCH_1):VR_PVCCIN_CPU0_AIREF2
  CTI6     1      A  CAP_A       I81
  EU4D4   25  AIREF2  PXE1610B_QFN  I155
  EU4D6   39  REFIN  IR354XX_SM  I64
  R6P42    2      B  RES         I139

VR_PVCCIN_CPU0_AIREF3   @BASEBOARD_FAB2_LIB.BASEBOARD_FAB2(SCH_1):VR_PVCCIN_CPU0_AIREF3
  CTI39    1      A  CAP_A       I96
  EU4D3   39  REFIN  IR354XX_SM  I70
  EU4D4   27  AIREF3  PXE1610B_QFN  I155
  R6P38    2      B  RES         I147

VR_PVCCIN_CPU0_AIREF4   @BASEBOARD_FAB2_LIB.BASEBOARD_FAB2(SCH_1):VR_PVCCIN_CPU0_AIREF4
  CTI40    1      A  CAP_A       I93
  EU4D1   39  REFIN  IR354XX_SM  I71
  EU4D4   29  AIREF4  PXE1610B_QFN  I155
  R6P34    2      B  RES         I148

VR_PVCCIN_CPU0_AIREF5   @BASEBOARD_FAB2_LIB.BASEBOARD_FAB2(SCH_1):VR_PVCCIN_CPU0_AIREF5
  CTI36    1      A  CAP_A       I85
  EU4C2   39  REFIN  IR354XX_SM  I71
  EU4D4   31  AIREF5  PXE1610B_QFN  I155
  R6P30    2      B  RES         I149

VR_PVCCIN_CPU0_AVINSEN   @BASEBOARD_FAB2_LIB.BASEBOARD_FAB2(SCH_1):VR_PVCCIN_CPU0_AVINSEN
  C4D20    1      A  CAP         I60
  EU4D4   45  VINSEN  PXE1610B_QFN  I155
  R4D27    2      B  RES         I54
  R4D32    1      A  RES         I55

VR_PVCCIN_CPU0_PH1_BOOT   @BASEBOARD_FAB2_LIB.BASEBOARD_FAB2(SCH_1):VR_PVCCIN_CPU0_PH1_BOOT
  C4E17    1      A  CAP_0402    I22
  RTI1     1      1  2D2R2F-GP_SMD-RG1  I69

VR_PVCCIN_CPU0_PH1_BOOT_R   @BASEBOARD_FAB2_LIB.BASEBOARD_FAB2(SCH_1):VR_PVCCIN_CPU0_PH1_BOOT_R
  EU4E1   33  BOOST  IR354XX_SM  I63
  RTI1     2      2  2D2R2F-GP_SMD-RG1  I69

VR_PVCCIN_CPU0_PH1_OCSET   @BASEBOARD_FAB2_LIB.BASEBOARD_FAB2(SCH_1):VR_PVCCIN_CPU0_PH1_OCSET
  EU4E1   37  OCSET  IR354XX_SM  I63
  R4E22    1      A  RES         I65

VR_PVCCIN_CPU0_PH1_PHASE   @BASEBOARD_FAB2_LIB.BASEBOARD_FAB2(SCH_1):VR_PVCCIN_CPU0_PH1_PHASE
  C4E17    2      B  CAP_0402    I22
  EU4E1   32  PHASE  IR354XX_SM  I63

VR_PVCCIN_CPU0_PH1_VCIN   @BASEBOARD_FAB2_LIB.BASEBOARD_FAB2(SCH_1):VR_PVCCIN_CPU0_PH1_VCIN
  C4E10    1      A  CAP_0402    I34
  EU4E1    3    VCC  IR354XX_SM  I63
  R6R2     1      A  RES         I33

VR_PVCCIN_CPU0_PH2_BOOT   @BASEBOARD_FAB2_LIB.BASEBOARD_FAB2(SCH_1):VR_PVCCIN_CPU0_PH2_BOOT
  C4D50    1      A  CAP_0402    I32
  RTI3     1      1  2D2R2F-GP_SMD-RG1  I79

VR_PVCCIN_CPU0_PH2_BOOT_R   @BASEBOARD_FAB2_LIB.BASEBOARD_FAB2(SCH_1):VR_PVCCIN_CPU0_PH2_BOOT_R
  EU4D6   33  BOOST  IR354XX_SM  I64
  RTI3     2      2  2D2R2F-GP_SMD-RG1  I79

VR_PVCCIN_CPU0_PH2_OCSET   @BASEBOARD_FAB2_LIB.BASEBOARD_FAB2(SCH_1):VR_PVCCIN_CPU0_PH2_OCSET
  EU4D6   37  OCSET  IR354XX_SM  I64
  R4E19    1      A  RES         I67

VR_PVCCIN_CPU0_PH2_PHASE   @BASEBOARD_FAB2_LIB.BASEBOARD_FAB2(SCH_1):VR_PVCCIN_CPU0_PH2_PHASE
  C4D50    2      B  CAP_0402    I32
  EU4D6   32  PHASE  IR354XX_SM  I64

VR_PVCCIN_CPU0_PH2_VCIN   @BASEBOARD_FAB2_LIB.BASEBOARD_FAB2(SCH_1):VR_PVCCIN_CPU0_PH2_VCIN
  C4E26    1      A  CAP_0402    I45
  EU4D6    3    VCC  IR354XX_SM  I64
  R6R6     1      A  RES         I39

VR_PVCCIN_CPU0_PH3_BOOT   @BASEBOARD_FAB2_LIB.BASEBOARD_FAB2(SCH_1):VR_PVCCIN_CPU0_PH3_BOOT
  C4D28    1      A  CAP_0402    I42
  RTI25    1      1  2D2R2F-GP_SMD-RG1  I98

VR_PVCCIN_CPU0_PH3_BOOT_R   @BASEBOARD_FAB2_LIB.BASEBOARD_FAB2(SCH_1):VR_PVCCIN_CPU0_PH3_BOOT_R
  EU4D3   33  BOOST  IR354XX_SM  I70
  RTI25    2      2  2D2R2F-GP_SMD-RG1  I98

VR_PVCCIN_CPU0_PH3_OCSET   @BASEBOARD_FAB2_LIB.BASEBOARD_FAB2(SCH_1):VR_PVCCIN_CPU0_PH3_OCSET
  EU4D3   37  OCSET  IR354XX_SM  I70
  R4D72    1      A  RES         I89

VR_PVCCIN_CPU0_PH3_PHASE   @BASEBOARD_FAB2_LIB.BASEBOARD_FAB2(SCH_1):VR_PVCCIN_CPU0_PH3_PHASE
  C4D28    2      B  CAP_0402    I42
  EU4D3   32  PHASE  IR354XX_SM  I70

VR_PVCCIN_CPU0_PH3_VCIN   @BASEBOARD_FAB2_LIB.BASEBOARD_FAB2(SCH_1):VR_PVCCIN_CPU0_PH3_VCIN
  C4D16    1      A  CAP_0402    I45
  EU4D3    3    VCC  IR354XX_SM  I70
  R6P19    1      A  RES         I38

VR_PVCCIN_CPU0_PH4_BOOT   @BASEBOARD_FAB2_LIB.BASEBOARD_FAB2(SCH_1):VR_PVCCIN_CPU0_PH4_BOOT
  C4D9     1      A  CAP_0402     I3
  RTI28    1      1  2D2R2F-GP_SMD-RG1  I95

VR_PVCCIN_CPU0_PH4_BOOT_R   @BASEBOARD_FAB2_LIB.BASEBOARD_FAB2(SCH_1):VR_PVCCIN_CPU0_PH4_BOOT_R
  EU4D1   33  BOOST  IR354XX_SM  I71
  RTI28    2      2  2D2R2F-GP_SMD-RG1  I95

VR_PVCCIN_CPU0_PH4_OCSET   @BASEBOARD_FAB2_LIB.BASEBOARD_FAB2(SCH_1):VR_PVCCIN_CPU0_PH4_OCSET
  EU4D1   37  OCSET  IR354XX_SM  I71
  R4D71    1      A  RES         I91

VR_PVCCIN_CPU0_PH4_PHASE   @BASEBOARD_FAB2_LIB.BASEBOARD_FAB2(SCH_1):VR_PVCCIN_CPU0_PH4_PHASE
  C4D9     2      B  CAP_0402     I3
  EU4D1   32  PHASE  IR354XX_SM  I71

VR_PVCCIN_CPU0_PH4_VCIN   @BASEBOARD_FAB2_LIB.BASEBOARD_FAB2(SCH_1):VR_PVCCIN_CPU0_PH4_VCIN
  C4D7     1      A  CAP_0402    I51
  EU4D1    3    VCC  IR354XX_SM  I71
  R6P10    1      A  RES         I50

VR_PVCCIN_CPU0_PH5_BOOT   @BASEBOARD_FAB2_LIB.BASEBOARD_FAB2(SCH_1):VR_PVCCIN_CPU0_PH5_BOOT
  C4C17    1      A  CAP_0402    I22
  RTI23    1      1  2D2R2F-GP_SMD-RG1  I87

VR_PVCCIN_CPU0_PH5_BOOT_R   @BASEBOARD_FAB2_LIB.BASEBOARD_FAB2(SCH_1):VR_PVCCIN_CPU0_PH5_BOOT_R
  EU4C2   33  BOOST  IR354XX_SM  I71
  RTI23    2      2  2D2R2F-GP_SMD-RG1  I87

VR_PVCCIN_CPU0_PH5_OCSET   @BASEBOARD_FAB2_LIB.BASEBOARD_FAB2(SCH_1):VR_PVCCIN_CPU0_PH5_OCSET
  EU4C2   37  OCSET  IR354XX_SM  I71
  R4D68    1      A  RES         I83

VR_PVCCIN_CPU0_PH5_PHASE   @BASEBOARD_FAB2_LIB.BASEBOARD_FAB2(SCH_1):VR_PVCCIN_CPU0_PH5_PHASE
  C4C17    2      B  CAP_0402    I22
  EU4C2   32  PHASE  IR354XX_SM  I71

VR_PVCCIN_CPU0_PH5_VCIN   @BASEBOARD_FAB2_LIB.BASEBOARD_FAB2(SCH_1):VR_PVCCIN_CPU0_PH5_VCIN
  C4D46    1      A  CAP_0402    I34
  EU4C2    3    VCC  IR354XX_SM  I71
  R6P47    1      A  RES         I33

VR_PVCCIN_CPU0_PHASE1   @BASEBOARD_FAB2_LIB.BASEBOARD_FAB2(SCH_1):VR_PVCCIN_CPU0_PHASE1
  CTI3     1      1  SC2K2P50V3KX-GP_SMD-BCG6  I76
  EU4E1   10     SW  IR354XX_SM  I63
  L4E1     1    INA  INDUCTOR     I5

VR_PVCCIN_CPU0_PHASE2   @BASEBOARD_FAB2_LIB.BASEBOARD_FAB2(SCH_1):VR_PVCCIN_CPU0_PHASE2
  CTI5     1      1  SC2K2P50V3KX-GP_SMD-BCG6  I82
  EU4D6   10     SW  IR354XX_SM  I64
  L4D3     1    INA  INDUCTOR    I29

VR_PVCCIN_CPU0_PHASE3   @BASEBOARD_FAB2_LIB.BASEBOARD_FAB2(SCH_1):VR_PVCCIN_CPU0_PHASE3
  CTI38    1      1  SC2K2P50V3KX-GP_SMD-BCG6  I101
  EU4D3   10     SW  IR354XX_SM  I70
  L4D2     1    INA  INDUCTOR    I15

VR_PVCCIN_CPU0_PHASE4   @BASEBOARD_FAB2_LIB.BASEBOARD_FAB2(SCH_1):VR_PVCCIN_CPU0_PHASE4
  CTI41    1      1  SC2K2P50V3KX-GP_SMD-BCG6  I106
  EU4D1   10     SW  IR354XX_SM  I71
  L4D1     1    INA  INDUCTOR    I24

VR_PVCCIN_CPU0_PHASE5   @BASEBOARD_FAB2_LIB.BASEBOARD_FAB2(SCH_1):VR_PVCCIN_CPU0_PHASE5
  CTI35    1      1  SC2K2P50V3KX-GP_SMD-BCG6  I90
  EU4C2   10     SW  IR354XX_SM  I71
  L4C3     1    INA  INDUCTOR     I5

VR_PVCCIN_CPU0_PWM1   @BASEBOARD_FAB2_LIB.BASEBOARD_FAB2(SCH_1):VR_PVCCIN_CPU0_PWM1
  EU4D4    7  APWM1  PXE1610B_QFN  I155
  EU4E1   34    PWM  IR354XX_SM  I63

VR_PVCCIN_CPU0_PWM2   @BASEBOARD_FAB2_LIB.BASEBOARD_FAB2(SCH_1):VR_PVCCIN_CPU0_PWM2
  EU4D4    6  APWM2  PXE1610B_QFN  I155
  EU4D6   34    PWM  IR354XX_SM  I64

VR_PVCCIN_CPU0_PWM3   @BASEBOARD_FAB2_LIB.BASEBOARD_FAB2(SCH_1):VR_PVCCIN_CPU0_PWM3
  EU4D3   34    PWM  IR354XX_SM  I70
  EU4D4    5  APWM3  PXE1610B_QFN  I155

VR_PVCCIN_CPU0_PWM4   @BASEBOARD_FAB2_LIB.BASEBOARD_FAB2(SCH_1):VR_PVCCIN_CPU0_PWM4
  EU4D1   34    PWM  IR354XX_SM  I71
  EU4D4    4  APWM4  PXE1610B_QFN  I155

VR_PVCCIN_CPU0_PWM5   @BASEBOARD_FAB2_LIB.BASEBOARD_FAB2(SCH_1):VR_PVCCIN_CPU0_PWM5
  EU4C2   34    PWM  IR354XX_SM  I71
  EU4D4    3  APWM5  PXE1610B_QFN  I155

VR_PVCCIN_CPU0_VD12   @BASEBOARD_FAB2_LIB.BASEBOARD_FAB2(SCH_1):VR_PVCCIN_CPU0_VD12
  C4D25    1      A  CAP_A       I30
  C4D26    1      A  CAP_A       I32
  EU4D4   48   VD12  PXE1610B_QFN  I155
  R6P29    1      A  RES         I154
  R6P30    1      A  RES         I149
  R6P34    1      A  RES         I148
  R6P38    1      A  RES         I147
  R6P42    1      A  RES         I139
  R6P43    1      A  RES         I150

VR_PVCCIN_CPU0_VDD   @BASEBOARD_FAB2_LIB.BASEBOARD_FAB2(SCH_1):VR_PVCCIN_CPU0_VDD
  C4D15    1      A  CAP_A       I37
  C4D19    1      A  CAP_A       I39
  EU4D4   47    VDD  PXE1610B_QFN  I155
  R4D26    2      B  RES         I40

VR_PVCCIN_CPU0_VREN   @BASEBOARD_FAB2_LIB.BASEBOARD_FAB2(SCH_1):VR_PVCCIN_CPU0_VREN
  EU4D4   12  AVREN  PXE1610B_QFN  I155
  R6P16    2      B  RES         I132
  R6P18    2      B  RES         I131

VR_PVCCIN_CPU0_XADDR1   @BASEBOARD_FAB2_LIB.BASEBOARD_FAB2(SCH_1):VR_PVCCIN_CPU0_XADDR1
  EU4D4   44  XADDR1  PXE1610B_QFN  I155
  R6P28    1      A  RES         I121

VR_PVCCIN_CPU0_XADDR2   @BASEBOARD_FAB2_LIB.BASEBOARD_FAB2(SCH_1):VR_PVCCIN_CPU0_XADDR2
  EU4D4   41  XADDR2  PXE1610B_QFN  I155
  R6P27    1      A  RES         I120

VR_PVCCIN_CPU1_AIREF1   @BASEBOARD_FAB2_LIB.BASEBOARD_FAB2(SCH_1):VR_PVCCIN_CPU1_AIREF1
  CTI24    1      A  CAP_A       I71
  EU1C2   23  AIREF1  PXE1610B_QFN  I130
  EU1E2   39  REFIN  IR354XX_SM  I20
  R9N15    2      B  RES         I122

VR_PVCCIN_CPU1_AIREF2   @BASEBOARD_FAB2_LIB.BASEBOARD_FAB2(SCH_1):VR_PVCCIN_CPU1_AIREF2
  CTI25    1      A  CAP_A       I81
  EU1C2   25  AIREF2  PXE1610B_QFN  I130
  EU1D4   39  REFIN  IR354XX_SM  I24
  R9N17    2      B  RES         I123

VR_PVCCIN_CPU1_AIREF3   @BASEBOARD_FAB2_LIB.BASEBOARD_FAB2(SCH_1):VR_PVCCIN_CPU1_AIREF3
  CTI16    1      A  CAP_A       I80
  EU1C2   27  AIREF3  PXE1610B_QFN  I130
  EU1D3   39  REFIN  IR354XX_SM  I27
  R9N12    2      B  RES         I124

VR_PVCCIN_CPU1_AIREF4   @BASEBOARD_FAB2_LIB.BASEBOARD_FAB2(SCH_1):VR_PVCCIN_CPU1_AIREF4
  CTI21    1      A  CAP_A       I87
  EU1C2   29  AIREF4  PXE1610B_QFN  I130
  EU1D1   39  REFIN  IR354XX_SM  I71
  R9N10    2      B  RES         I125

VR_PVCCIN_CPU1_AIREF5   @BASEBOARD_FAB2_LIB.BASEBOARD_FAB2(SCH_1):VR_PVCCIN_CPU1_AIREF5
  CTI13    1      A  CAP_A       I62
  EU1C2   31  AIREF5  PXE1610B_QFN  I130
  EU1C3   39  REFIN  IR354XX_SM  I56
  R9N9     2      B  RES         I126

VR_PVCCIN_CPU1_AVINSEN   @BASEBOARD_FAB2_LIB.BASEBOARD_FAB2(SCH_1):VR_PVCCIN_CPU1_AVINSEN
  C1C8     1      A  CAP         I73
  EU1C2   45  VINSEN  PXE1610B_QFN  I130
  R1C13    2      B  RES         I49
  R1C16    1      A  RES         I56

VR_PVCCIN_CPU1_PH1_BOOT   @BASEBOARD_FAB2_LIB.BASEBOARD_FAB2(SCH_1):VR_PVCCIN_CPU1_PH1_BOOT
  C1E11    1      A  CAP_0402    I30
  RTI15    1      1  2D2R2F-GP_SMD-RG1  I73

VR_PVCCIN_CPU1_PH1_BOOT_R   @BASEBOARD_FAB2_LIB.BASEBOARD_FAB2(SCH_1):VR_PVCCIN_CPU1_PH1_BOOT_R
  EU1E2   33  BOOST  IR354XX_SM  I20
  RTI15    2      2  2D2R2F-GP_SMD-RG1  I73

VR_PVCCIN_CPU1_PH1_OCSET   @BASEBOARD_FAB2_LIB.BASEBOARD_FAB2(SCH_1):VR_PVCCIN_CPU1_PH1_OCSET
  EU1E2   37  OCSET  IR354XX_SM  I20
  R1E14    1      A  RES         I68

VR_PVCCIN_CPU1_PH1_PHASE   @BASEBOARD_FAB2_LIB.BASEBOARD_FAB2(SCH_1):VR_PVCCIN_CPU1_PH1_PHASE
  C1E11    2      B  CAP_0402    I30
  EU1E2   32  PHASE  IR354XX_SM  I20

VR_PVCCIN_CPU1_PH1_VCIN   @BASEBOARD_FAB2_LIB.BASEBOARD_FAB2(SCH_1):VR_PVCCIN_CPU1_PH1_VCIN
  C1E8     1      A  CAP_0402    I32
  EU1E2    3    VCC  IR354XX_SM  I20
  R9R2     1      A  RES         I26

VR_PVCCIN_CPU1_PH2_BOOT   @BASEBOARD_FAB2_LIB.BASEBOARD_FAB2(SCH_1):VR_PVCCIN_CPU1_PH2_BOOT
  C1D36    1      A  CAP_0402    I38
  RTI17    1      1  2D2R2F-GP_SMD-RG1  I79

VR_PVCCIN_CPU1_PH2_BOOT_R   @BASEBOARD_FAB2_LIB.BASEBOARD_FAB2(SCH_1):VR_PVCCIN_CPU1_PH2_BOOT_R
  EU1D4   33  BOOST  IR354XX_SM  I24
  RTI17    2      2  2D2R2F-GP_SMD-RG1  I79

VR_PVCCIN_CPU1_PH2_OCSET   @BASEBOARD_FAB2_LIB.BASEBOARD_FAB2(SCH_1):VR_PVCCIN_CPU1_PH2_OCSET
  EU1D4   37  OCSET  IR354XX_SM  I24
  R1E13    1      A  RES         I67

VR_PVCCIN_CPU1_PH2_PHASE   @BASEBOARD_FAB2_LIB.BASEBOARD_FAB2(SCH_1):VR_PVCCIN_CPU1_PH2_PHASE
  C1D36    2      B  CAP_0402    I38
  EU1D4   32  PHASE  IR354XX_SM  I24

VR_PVCCIN_CPU1_PH2_VCIN   @BASEBOARD_FAB2_LIB.BASEBOARD_FAB2(SCH_1):VR_PVCCIN_CPU1_PH2_VCIN
  C1E24    1      A  CAP_0402    I40
  EU1D4    3    VCC  IR354XX_SM  I24
  R9R11    1      A  RES         I39

VR_PVCCIN_CPU1_PH3_BOOT   @BASEBOARD_FAB2_LIB.BASEBOARD_FAB2(SCH_1):VR_PVCCIN_CPU1_PH3_BOOT
  C1D20    1      A  CAP_0402    I40
  RTI11    1      1  2D2R2F-GP_SMD-RG1  I95

VR_PVCCIN_CPU1_PH3_BOOT_R   @BASEBOARD_FAB2_LIB.BASEBOARD_FAB2(SCH_1):VR_PVCCIN_CPU1_PH3_BOOT_R
  EU1D3   33  BOOST  IR354XX_SM  I27
  RTI11    2      2  2D2R2F-GP_SMD-RG1  I95

VR_PVCCIN_CPU1_PH3_OCSET   @BASEBOARD_FAB2_LIB.BASEBOARD_FAB2(SCH_1):VR_PVCCIN_CPU1_PH3_OCSET
  EU1D3   37  OCSET  IR354XX_SM  I27
  R1D55    1      A  RES         I76

VR_PVCCIN_CPU1_PH3_PHASE   @BASEBOARD_FAB2_LIB.BASEBOARD_FAB2(SCH_1):VR_PVCCIN_CPU1_PH3_PHASE
  C1D20    2      B  CAP_0402    I40
  EU1D3   32  PHASE  IR354XX_SM  I27

VR_PVCCIN_CPU1_PH3_VCIN   @BASEBOARD_FAB2_LIB.BASEBOARD_FAB2(SCH_1):VR_PVCCIN_CPU1_PH3_VCIN
  C1D17    1      A  CAP_0402    I43
  EU1D3    3    VCC  IR354XX_SM  I27
  R9P22    1      A  RES         I36

VR_PVCCIN_CPU1_PH4_BOOT   @BASEBOARD_FAB2_LIB.BASEBOARD_FAB2(SCH_1):VR_PVCCIN_CPU1_PH4_BOOT
  C1D10    1      A  CAP_0402    I48
  RTI14    1      1  2D2R2F-GP_SMD-RG1  I89

VR_PVCCIN_CPU1_PH4_BOOT_R   @BASEBOARD_FAB2_LIB.BASEBOARD_FAB2(SCH_1):VR_PVCCIN_CPU1_PH4_BOOT_R
  EU1D1   33  BOOST  IR354XX_SM  I71
  RTI14    2      2  2D2R2F-GP_SMD-RG1  I89

VR_PVCCIN_CPU1_PH4_OCSET   @BASEBOARD_FAB2_LIB.BASEBOARD_FAB2(SCH_1):VR_PVCCIN_CPU1_PH4_OCSET
  EU1D1   37  OCSET  IR354XX_SM  I71
  R1D54    1      A  RES         I75

VR_PVCCIN_CPU1_PH4_PHASE   @BASEBOARD_FAB2_LIB.BASEBOARD_FAB2(SCH_1):VR_PVCCIN_CPU1_PH4_PHASE
  C1D10    2      B  CAP_0402    I48
  EU1D1   32  PHASE  IR354XX_SM  I71

VR_PVCCIN_CPU1_PH4_VCIN   @BASEBOARD_FAB2_LIB.BASEBOARD_FAB2(SCH_1):VR_PVCCIN_CPU1_PH4_VCIN
  C1D7     1      A  CAP_0402    I50
  EU1D1    3    VCC  IR354XX_SM  I71
  R9P8     1      A  RES         I49

VR_PVCCIN_CPU1_PH5_BOOT   @BASEBOARD_FAB2_LIB.BASEBOARD_FAB2(SCH_1):VR_PVCCIN_CPU1_PH5_BOOT
  C1C24    1      A  CAP_0402    I20
  RTI9     1      1  2D2R2F-GP_SMD-RG1  I61

VR_PVCCIN_CPU1_PH5_BOOT_R   @BASEBOARD_FAB2_LIB.BASEBOARD_FAB2(SCH_1):VR_PVCCIN_CPU1_PH5_BOOT_R
  EU1C3   33  BOOST  IR354XX_SM  I56
  RTI9     2      2  2D2R2F-GP_SMD-RG1  I61

VR_PVCCIN_CPU1_PH5_OCSET   @BASEBOARD_FAB2_LIB.BASEBOARD_FAB2(SCH_1):VR_PVCCIN_CPU1_PH5_OCSET
  EU1C3   37  OCSET  IR354XX_SM  I56
  R1D52    1      A  RES         I59

VR_PVCCIN_CPU1_PH5_PHASE   @BASEBOARD_FAB2_LIB.BASEBOARD_FAB2(SCH_1):VR_PVCCIN_CPU1_PH5_PHASE
  C1C24    2      B  CAP_0402    I20
  EU1C3   32  PHASE  IR354XX_SM  I56

VR_PVCCIN_CPU1_PH5_VCIN   @BASEBOARD_FAB2_LIB.BASEBOARD_FAB2(SCH_1):VR_PVCCIN_CPU1_PH5_VCIN
  C1D32    1      A  CAP_0402    I18
  EU1C3    3    VCC  IR354XX_SM  I56
  R9P32    1      A  RES         I24

VR_PVCCIN_CPU1_PHASE1   @BASEBOARD_FAB2_LIB.BASEBOARD_FAB2(SCH_1):VR_PVCCIN_CPU1_PHASE1
  CTI23    1      1  SC2K2P50V3KX-GP_SMD-BCG6  I77
  EU1E2   10     SW  IR354XX_SM  I20
  L1E1     1    INA  INDUCTOR    I10

VR_PVCCIN_CPU1_PHASE2   @BASEBOARD_FAB2_LIB.BASEBOARD_FAB2(SCH_1):VR_PVCCIN_CPU1_PHASE2
  CTI27    1      1  SC2K2P50V3KX-GP_SMD-BCG6  I84
  EU1D4   10     SW  IR354XX_SM  I24
  L1D3     1    INA  INDUCTOR    I16

VR_PVCCIN_CPU1_PHASE3   @BASEBOARD_FAB2_LIB.BASEBOARD_FAB2(SCH_1):VR_PVCCIN_CPU1_PHASE3
  CTI18    1      1  SC2K2P50V3KX-GP_SMD-BCG6  I84
  EU1D3   10     SW  IR354XX_SM  I27
  L1D2     1    INA  INDUCTOR    I11

VR_PVCCIN_CPU1_PHASE4   @BASEBOARD_FAB2_LIB.BASEBOARD_FAB2(SCH_1):VR_PVCCIN_CPU1_PHASE4
  CTI20    1      1  SC2K2P50V3KX-GP_SMD-BCG6  I92
  EU1D1   10     SW  IR354XX_SM  I71
  L1D1     1    INA  INDUCTOR    I20

VR_PVCCIN_CPU1_PHASE5   @BASEBOARD_FAB2_LIB.BASEBOARD_FAB2(SCH_1):VR_PVCCIN_CPU1_PHASE5
  CTI14    1      1  SC2K2P50V3KX-GP_SMD-BCG6  I64
  EU1C3   10     SW  IR354XX_SM  I56
  L1C2     1    INA  INDUCTOR    I40

VR_PVCCIN_CPU1_PWM1   @BASEBOARD_FAB2_LIB.BASEBOARD_FAB2(SCH_1):VR_PVCCIN_CPU1_PWM1
  EU1C2    7  APWM1  PXE1610B_QFN  I130
  EU1E2   34    PWM  IR354XX_SM  I20

VR_PVCCIN_CPU1_PWM2   @BASEBOARD_FAB2_LIB.BASEBOARD_FAB2(SCH_1):VR_PVCCIN_CPU1_PWM2
  EU1C2    6  APWM2  PXE1610B_QFN  I130
  EU1D4   34    PWM  IR354XX_SM  I24

VR_PVCCIN_CPU1_PWM3   @BASEBOARD_FAB2_LIB.BASEBOARD_FAB2(SCH_1):VR_PVCCIN_CPU1_PWM3
  EU1C2    5  APWM3  PXE1610B_QFN  I130
  EU1D3   34    PWM  IR354XX_SM  I27

VR_PVCCIN_CPU1_PWM4   @BASEBOARD_FAB2_LIB.BASEBOARD_FAB2(SCH_1):VR_PVCCIN_CPU1_PWM4
  EU1C2    4  APWM4  PXE1610B_QFN  I130
  EU1D1   34    PWM  IR354XX_SM  I71

VR_PVCCIN_CPU1_PWM5   @BASEBOARD_FAB2_LIB.BASEBOARD_FAB2(SCH_1):VR_PVCCIN_CPU1_PWM5
  EU1C2    3  APWM5  PXE1610B_QFN  I130
  EU1C3   34    PWM  IR354XX_SM  I56

VR_PVCCIN_CPU1_VD12   @BASEBOARD_FAB2_LIB.BASEBOARD_FAB2(SCH_1):VR_PVCCIN_CPU1_VD12
  C1C13    1      A  CAP_A       I29
  C1C14    1      A  CAP_A       I31
  EU1C2   48   VD12  PXE1610B_QFN  I130
  R9N5     1      A  RES         I128
  R9N9     1      A  RES         I126
  R9N10    1      A  RES         I125
  R9N12    1      A  RES         I124
  R9N15    1      A  RES         I122
  R9N17    1      A  RES         I123

VR_PVCCIN_CPU1_VDD   @BASEBOARD_FAB2_LIB.BASEBOARD_FAB2(SCH_1):VR_PVCCIN_CPU1_VDD
  C1C7     1      A  CAP_A       I41
  C1C9     1      A  CAP_A       I42
  EU1C2   47    VDD  PXE1610B_QFN  I130
  R1C14    2      B  RES         I46

VR_PVCCIN_CPU1_VREN   @BASEBOARD_FAB2_LIB.BASEBOARD_FAB2(SCH_1):VR_PVCCIN_CPU1_VREN
  EU1C2   12  AVREN  PXE1610B_QFN  I130
  R9N14    2      B  RES         I120
  R9N16    2      B  RES         I119

VR_PVCCIN_CPU1_XADDR1   @BASEBOARD_FAB2_LIB.BASEBOARD_FAB2(SCH_1):VR_PVCCIN_CPU1_XADDR1
  EU1C2   44  XADDR1  PXE1610B_QFN  I130
  R9N8     1      A  RES         I112

VR_PVCCIN_CPU1_XADDR2   @BASEBOARD_FAB2_LIB.BASEBOARD_FAB2(SCH_1):VR_PVCCIN_CPU1_XADDR2
  EU1C2   41  XADDR2  PXE1610B_QFN  I130
  R9N7     1      A  RES         I111

VR_PVCCIOMCP_CPU0_XADDR1   @BASEBOARD_FAB2_LIB.BASEBOARD_FAB2(SCH_1):VR_PVCCIOMCP_CPU0_XADDR1
  J6B1   E10  IOE10  SCONN120_H61426002_SM  I56
  R3N29    1      A  RES         I156

VR_PVCCIOMCP_CPU1_XADDR1   @BASEBOARD_FAB2_LIB.BASEBOARD_FAB2(SCH_1):VR_PVCCIOMCP_CPU1_XADDR1
  J4B2   E10  IOE10  SCONN120_H61426002_SM  I46
  R4C12    1      A  RES         I169

VR_PVCCIO_CPU0_AIREF1   @BASEBOARD_FAB2_LIB.BASEBOARD_FAB2(SCH_1):VR_PVCCIO_CPU0_AIREF1
  CTI70    1      A  CAP_A       I106
  EU3P1   21  AIREF1  PXE1110B_QFN  I93
  EU7C1   39  REFIN  IR354XX_SM  I101
  R3P57    2      B  RES         I91

VR_PVCCIO_CPU0_AVSP   @BASEBOARD_FAB2_LIB.BASEBOARD_FAB2(SCH_1):VR_PVCCIO_CPU0_AVSP
  C3N39    1      A  CAP         I83
  EU3P1   19  AVSEN  PXE1110B_QFN  I93
  R3N19    2      B  RES         I81

VR_PVCCIO_CPU0_EN   @BASEBOARD_FAB2_LIB.BASEBOARD_FAB2(SCH_1):VR_PVCCIO_CPU0_EN
  EU3P1   10  AVREN  PXE1110B_QFN  I93
  R3P21    2      B  RES         I88
  R3P26    2      B  RES         I87

VR_PVCCIO_CPU0_OCSET   @BASEBOARD_FAB2_LIB.BASEBOARD_FAB2(SCH_1):VR_PVCCIO_CPU0_OCSET
  EU7C1   37  OCSET  IR354XX_SM  I101
  R7C25    1      A  RES         I103

VR_PVCCIO_CPU0_PH1_BOOT   @BASEBOARD_FAB2_LIB.BASEBOARD_FAB2(SCH_1):VR_PVCCIO_CPU0_PH1_BOOT
  C7C14    1      A  CAP_0402    I37
  RTI47    1      1  2D2R2F-GP_SMD-RG1  I108

VR_PVCCIO_CPU0_PH1_BOOT_R   @BASEBOARD_FAB2_LIB.BASEBOARD_FAB2(SCH_1):VR_PVCCIO_CPU0_PH1_BOOT_R
  EU7C1   33  BOOST  IR354XX_SM  I101
  RTI47    2      2  2D2R2F-GP_SMD-RG1  I108

VR_PVCCIO_CPU0_PH1_PHASE   @BASEBOARD_FAB2_LIB.BASEBOARD_FAB2(SCH_1):VR_PVCCIO_CPU0_PH1_PHASE
  C7C14    2      B  CAP_0402    I37
  EU7C1   32  PHASE  IR354XX_SM  I101

VR_PVCCIO_CPU0_PH1_SW   @BASEBOARD_FAB2_LIB.BASEBOARD_FAB2(SCH_1):VR_PVCCIO_CPU0_PH1_SW
  CTI72    1      1  SC2K2P50V3KX-GP_SMD-BCG6  I111
  EU7C1   10     SW  IR354XX_SM  I101
  L7C2     1    INA  INDUCTOR    I25

VR_PVCCIO_CPU0_PH1_VCIN   @BASEBOARD_FAB2_LIB.BASEBOARD_FAB2(SCH_1):VR_PVCCIO_CPU0_PH1_VCIN
  C7C17    1      A  CAP_0402    I36
  EU7C1    3    VCC  IR354XX_SM  I101
  R3N7     1      A  RES         I32

VR_PVCCIO_CPU0_PWM1   @BASEBOARD_FAB2_LIB.BASEBOARD_FAB2(SCH_1):VR_PVCCIO_CPU0_PWM1
  EU3P1    5  APWM1  PXE1110B_QFN  I93
  EU7C1   34    PWM  IR354XX_SM  I101

VR_PVCCIO_CPU0_VD12   @BASEBOARD_FAB2_LIB.BASEBOARD_FAB2(SCH_1):VR_PVCCIO_CPU0_VD12
  C3P4     1      A  CAP_A       I11
  C3P5     1      A  CAP_A       I13
  EU3P1   40   VD12  PXE1110B_QFN  I93
  R3P57    1      A  RES         I91

VR_PVCCIO_CPU0_VDD   @BASEBOARD_FAB2_LIB.BASEBOARD_FAB2(SCH_1):VR_PVCCIO_CPU0_VDD
  C3P3     1      A  CAP_A       I20
  C3P7     1      A  CAP_A       I22
  EU3P1   39    VDD  PXE1110B_QFN  I93
  R3P22    2      B  RES         I24

VR_PVCCIO_CPU0_VINSEN   @BASEBOARD_FAB2_LIB.BASEBOARD_FAB2(SCH_1):VR_PVCCIO_CPU0_VINSEN
  C3P2     1      A  CAP         I33
  EU3P1   37  VINSEN  PXE1110B_QFN  I93
  R3P12    2      B  RES         I31
  R3P16    1      A  RES         I32

VR_PVCCIO_CPU0_XADDR1   @BASEBOARD_FAB2_LIB.BASEBOARD_FAB2(SCH_1):VR_PVCCIO_CPU0_XADDR1
  EU3P1   36  XADDR1  PXE1110B_QFN  I93
  R3N31    1      A  RES         I52

VR_PVCCIO_CPU0_XADDR2   @BASEBOARD_FAB2_LIB.BASEBOARD_FAB2(SCH_1):VR_PVCCIO_CPU0_XADDR2
  EU3P1   33  XADDR2  PXE1110B_QFN  I93
  R3N22    1      A  RES         I65

VR_PVCCIO_CPU1_AIREF1   @BASEBOARD_FAB2_LIB.BASEBOARD_FAB2(SCH_1):VR_PVCCIO_CPU1_AIREF1
  CTI63    1      A  CAP_A       I137
  EU4D5   21  AIREF1  PXE1110B_QFN  I96
  EU4E2   39  REFIN  IR354XX_SM  I126
  R4D45    2      B  RES         I94

VR_PVCCIO_CPU1_AVSP   @BASEBOARD_FAB2_LIB.BASEBOARD_FAB2(SCH_1):VR_PVCCIO_CPU1_AVSP
  C4D44    1      A  CAP         I83
  EU4D5   19  AVSEN  PXE1110B_QFN  I96
  R4E7     2      B  RES         I84

VR_PVCCIO_CPU1_EN   @BASEBOARD_FAB2_LIB.BASEBOARD_FAB2(SCH_1):VR_PVCCIO_CPU1_EN
  EU4D5   10  AVREN  PXE1110B_QFN  I96
  R6P40    2      B  RES         I91
  R6P41    2      B  RES         I90

VR_PVCCIO_CPU1_OCSET   @BASEBOARD_FAB2_LIB.BASEBOARD_FAB2(SCH_1):VR_PVCCIO_CPU1_OCSET
  EU4E2   37  OCSET  IR354XX_SM  I126
  R4E21    1      A  RES         I127

VR_PVCCIO_CPU1_PH1_BOOT   @BASEBOARD_FAB2_LIB.BASEBOARD_FAB2(SCH_1):VR_PVCCIO_CPU1_PH1_BOOT
  C4E18    1      A  CAP_0402    I78
  RTI41    1      1  2D2R2F-GP_SMD-RG1  I138

VR_PVCCIO_CPU1_PH1_BOOT_R   @BASEBOARD_FAB2_LIB.BASEBOARD_FAB2(SCH_1):VR_PVCCIO_CPU1_PH1_BOOT_R
  EU4E2   33  BOOST  IR354XX_SM  I126
  RTI41    2      2  2D2R2F-GP_SMD-RG1  I138

VR_PVCCIO_CPU1_PH1_PHASE   @BASEBOARD_FAB2_LIB.BASEBOARD_FAB2(SCH_1):VR_PVCCIO_CPU1_PH1_PHASE
  C4E18    2      B  CAP_0402    I78
  EU4E2   32  PHASE  IR354XX_SM  I126

VR_PVCCIO_CPU1_PH1_SW   @BASEBOARD_FAB2_LIB.BASEBOARD_FAB2(SCH_1):VR_PVCCIO_CPU1_PH1_SW
  CTI62    1      1  SC2K2P50V3KX-GP_SMD-BCG6  I131
  EU4E2   10     SW  IR354XX_SM  I126
  L4E2     1    INA  INDUCTOR    I67

VR_PVCCIO_CPU1_PH1_VCIN   @BASEBOARD_FAB2_LIB.BASEBOARD_FAB2(SCH_1):VR_PVCCIO_CPU1_PH1_VCIN
  C4E22    1      A  CAP_0402    I76
  EU4E2    3    VCC  IR354XX_SM  I126
  R6R5     1      A  RES         I71

VR_PVCCIO_CPU1_PWM1   @BASEBOARD_FAB2_LIB.BASEBOARD_FAB2(SCH_1):VR_PVCCIO_CPU1_PWM1
  EU4D5    5  APWM1  PXE1110B_QFN  I96
  EU4E2   34    PWM  IR354XX_SM  I126

VR_PVCCIO_CPU1_VD12   @BASEBOARD_FAB2_LIB.BASEBOARD_FAB2(SCH_1):VR_PVCCIO_CPU1_VD12
  C4D31    1      A  CAP_A        I9
  C4D32    1      A  CAP_A       I11
  EU4D5   40   VD12  PXE1110B_QFN  I96
  R4D45    1      A  RES         I94

VR_PVCCIO_CPU1_VDD   @BASEBOARD_FAB2_LIB.BASEBOARD_FAB2(SCH_1):VR_PVCCIO_CPU1_VDD
  C4D36    1      A  CAP_A       I17
  C4D38    1      A  CAP_A       I35
  EU4D5   39    VDD  PXE1110B_QFN  I96
  R4D47    2      B  RES         I25

VR_PVCCIO_CPU1_VINSEN   @BASEBOARD_FAB2_LIB.BASEBOARD_FAB2(SCH_1):VR_PVCCIO_CPU1_VINSEN
  C4D40    1      A  CAP         I33
  EU4D5   37  VINSEN  PXE1110B_QFN  I96
  R4D57    1      A  RES         I32
  R4D60    2      B  RES         I31

VR_PVCCIO_CPU1_XADDR1   @BASEBOARD_FAB2_LIB.BASEBOARD_FAB2(SCH_1):VR_PVCCIO_CPU1_XADDR1
  EU4D5   36  XADDR1  PXE1110B_QFN  I96
  R4D64    1      A  RES         I42

VR_PVCCIO_CPU1_XADDR2   @BASEBOARD_FAB2_LIB.BASEBOARD_FAB2(SCH_1):VR_PVCCIO_CPU1_XADDR2
  EU4D5   33  XADDR2  PXE1110B_QFN  I96
  R4E2     1      A  RES         I65

VR_PVCCMCP_CPU0_XADDR2   @BASEBOARD_FAB2_LIB.BASEBOARD_FAB2(SCH_1):VR_PVCCMCP_CPU0_XADDR2
  J6B1   F10  IOF10  SCONN120_H61426002_SM  I56
  R7C24    1      A  RES         I155

VR_PVCCMCP_CPU1_XADDR2   @BASEBOARD_FAB2_LIB.BASEBOARD_FAB2(SCH_1):VR_PVCCMCP_CPU1_XADDR2
  J4B2   F10  IOF10  SCONN120_H61426002_SM  I46
  R4C11    1      A  RES         I170

VR_PVDDQ_ABC_AIINSEN   @BASEBOARD_FAB2_LIB.BASEBOARD_FAB2(SCH_1):VR_PVDDQ_ABC_AIINSEN
  C3U10    1      A  CAP_A       I360
  EU7G1   38  IINSEN  PXM1310B_QFN  I358
  R4F1     2      B  RES         I110

VR_PVDDQ_ABC_AIINSEN_R   @BASEBOARD_FAB2_LIB.BASEBOARD_FAB2(SCH_1):VR_PVDDQ_ABC_AIINSEN_R
  R4F1     1      A  RES         I110
  U4F1     3    OUT  MAX9634_SOT  I97

VR_PVDDQ_ABC_AIREF1   @BASEBOARD_FAB2_LIB.BASEBOARD_FAB2(SCH_1):VR_PVDDQ_ABC_AIREF1
  CTI51    1      A  CAP_A       I108
  EU7G1   21  AIREF1  PXM1310B_QFN  I358
  EU7G2   39  REFIN  IR354XX_SM  I102
  R3U10    2      B  RES         I341

VR_PVDDQ_ABC_AIREF2   @BASEBOARD_FAB2_LIB.BASEBOARD_FAB2(SCH_1):VR_PVDDQ_ABC_AIREF2
  CTI52    1      A  CAP_A       I111
  EU7G1   23  AIREF2  PXM1310B_QFN  I358
  EU7G3   39  REFIN  IR354XX_SM  I103
  R3U3     2      B  RES         I332

VR_PVDDQ_ABC_AVSP   @BASEBOARD_FAB2_LIB.BASEBOARD_FAB2(SCH_1):VR_PVDDQ_ABC_AVSP
  C7G4     1      A  CAP         I342
  EU7G1   19  AVSEN  PXM1310B_QFN  I358
  R7G9     2      B  RES         I344

VR_PVDDQ_ABC_PH1_BOOT   @BASEBOARD_FAB2_LIB.BASEBOARD_FAB2(SCH_1):VR_PVDDQ_ABC_PH1_BOOT
  C7G31    1      A  CAP_0402    I44
  RTI33    1      1  2D2R2F-GP_SMD-RG1  I110

VR_PVDDQ_ABC_PH1_BOOT_R   @BASEBOARD_FAB2_LIB.BASEBOARD_FAB2(SCH_1):VR_PVDDQ_ABC_PH1_BOOT_R
  EU7G2   33  BOOST  IR354XX_SM  I102
  RTI33    2      2  2D2R2F-GP_SMD-RG1  I110

VR_PVDDQ_ABC_PH1_OCSET   @BASEBOARD_FAB2_LIB.BASEBOARD_FAB2(SCH_1):VR_PVDDQ_ABC_PH1_OCSET
  EU7G2   37  OCSET  IR354XX_SM  I102
  R7G25    1      A  RES         I104

VR_PVDDQ_ABC_PH1_PHASE   @BASEBOARD_FAB2_LIB.BASEBOARD_FAB2(SCH_1):VR_PVDDQ_ABC_PH1_PHASE
  C7G31    2      B  CAP_0402    I44
  EU7G2   32  PHASE  IR354XX_SM  I102

VR_PVDDQ_ABC_PH1_SW   @BASEBOARD_FAB2_LIB.BASEBOARD_FAB2(SCH_1):VR_PVDDQ_ABC_PH1_SW
  CTI50    1      1  SC2K2P50V3KX-GP_SMD-BCG6  I124
  EU7G2   10     SW  IR354XX_SM  I102
  L7G1     1    INA  INDUCTOR    I125

VR_PVDDQ_ABC_PH1_VCIN   @BASEBOARD_FAB2_LIB.BASEBOARD_FAB2(SCH_1):VR_PVDDQ_ABC_PH1_VCIN
  C7G33    1      A  CAP_0402    I50
  EU7G2    3    VCC  IR354XX_SM  I102
  R3U6     1      A  RES         I52

VR_PVDDQ_ABC_PH2_BOOT   @BASEBOARD_FAB2_LIB.BASEBOARD_FAB2(SCH_1):VR_PVDDQ_ABC_PH2_BOOT
  C7G38    1      A  CAP_0402    I75
  RTI36    1      1  2D2R2F-GP_SMD-RG1  I113

VR_PVDDQ_ABC_PH2_BOOT_R   @BASEBOARD_FAB2_LIB.BASEBOARD_FAB2(SCH_1):VR_PVDDQ_ABC_PH2_BOOT_R
  EU7G3   33  BOOST  IR354XX_SM  I103
  RTI36    2      2  2D2R2F-GP_SMD-RG1  I113

VR_PVDDQ_ABC_PH2_OCSET   @BASEBOARD_FAB2_LIB.BASEBOARD_FAB2(SCH_1):VR_PVDDQ_ABC_PH2_OCSET
  EU7G3   37  OCSET  IR354XX_SM  I103
  R7G30    1      A  RES         I106

VR_PVDDQ_ABC_PH2_PHASE   @BASEBOARD_FAB2_LIB.BASEBOARD_FAB2(SCH_1):VR_PVDDQ_ABC_PH2_PHASE
  C7G38    2      B  CAP_0402    I75
  EU7G3   32  PHASE  IR354XX_SM  I103

VR_PVDDQ_ABC_PH2_SW   @BASEBOARD_FAB2_LIB.BASEBOARD_FAB2(SCH_1):VR_PVDDQ_ABC_PH2_SW
  CTI53    1      1  SC2K2P50V3KX-GP_SMD-BCG6  I119
  EU7G3   10     SW  IR354XX_SM  I103
  L7G2     1    INA  INDUCTOR    I65

VR_PVDDQ_ABC_PH2_VCIN   @BASEBOARD_FAB2_LIB.BASEBOARD_FAB2(SCH_1):VR_PVDDQ_ABC_PH2_VCIN
  C7G40    1      A  CAP_0402    I77
  EU7G3    3    VCC  IR354XX_SM  I103
  R3U9     1      A  RES         I76

VR_PVDDQ_ABC_PWM1   @BASEBOARD_FAB2_LIB.BASEBOARD_FAB2(SCH_1):VR_PVDDQ_ABC_PWM1
  EU7G1    5  APWM1  PXM1310B_QFN  I358
  EU7G2   34    PWM  IR354XX_SM  I102

VR_PVDDQ_ABC_PWM2   @BASEBOARD_FAB2_LIB.BASEBOARD_FAB2(SCH_1):VR_PVDDQ_ABC_PWM2
  EU7G1    4  APWM2  PXM1310B_QFN  I358
  EU7G3   34    PWM  IR354XX_SM  I103

VR_PVDDQ_ABC_VD12   @BASEBOARD_FAB2_LIB.BASEBOARD_FAB2(SCH_1):VR_PVDDQ_ABC_VD12
  C7F15    1      A  CAP_A       I327
  C7F16    1      A  CAP_A       I325
  EU7G1   40   VD12  PXM1310B_QFN  I358
  R3U3     1      A  RES         I332
  R3U10    1      A  RES         I341

VR_PVDDQ_ABC_VDD   @BASEBOARD_FAB2_LIB.BASEBOARD_FAB2(SCH_1):VR_PVDDQ_ABC_VDD
  C7F17    1      A  CAP_A       I311
  C7F18    1      A  CAP_A       I309
  EU7G1   39    VDD  PXM1310B_QFN  I358
  R3T13    2      B  RES         I313

VR_PVDDQ_ABC_VINSEN   @BASEBOARD_FAB2_LIB.BASEBOARD_FAB2(SCH_1):VR_PVDDQ_ABC_VINSEN
  C7G1     1      A  CAP         I339
  EU7G1   37  VINSEN  PXM1310B_QFN  I358
  R7F34    2      B  RES         I336
  R7G3     1      A  RES         I337

VR_PVDDQ_ABC_VREN   @BASEBOARD_FAB2_LIB.BASEBOARD_FAB2(SCH_1):VR_PVDDQ_ABC_VREN
  EU7G1   10  AVREN  PXM1310B_QFN  I358
  R7F20    2      B  RES         I315
  R7F21    2      B  RES         I343

VR_PVDDQ_ABC_XADDR1   @BASEBOARD_FAB2_LIB.BASEBOARD_FAB2(SCH_1):VR_PVDDQ_ABC_XADDR1
  EU7G1   36  XADDR1  PXM1310B_QFN  I358
  R7G8     1      A  RES         I321

VR_PVDDQ_ABC_XADDR2   @BASEBOARD_FAB2_LIB.BASEBOARD_FAB2(SCH_1):VR_PVDDQ_ABC_XADDR2
  EU7G1   33  XADDR2  PXM1310B_QFN  I358
  R7G10    1      A  RES         I317

VR_PVDDQ_DEF_AIINSEN   @BASEBOARD_FAB2_LIB.BASEBOARD_FAB2(SCH_1):VR_PVDDQ_DEF_AIINSEN
  C3L31    1      A  CAP_A       I77
  EU7A5   38  IINSEN  PXM1310B_QFN  I75
  R4B11    2      B  RES         I113

VR_PVDDQ_DEF_AIINSEN_R   @BASEBOARD_FAB2_LIB.BASEBOARD_FAB2(SCH_1):VR_PVDDQ_DEF_AIINSEN_R
  R4B11    1      A  RES         I113
  U4B1     3    OUT  MAX9634_SOT  I120

VR_PVDDQ_DEF_AIREF1   @BASEBOARD_FAB2_LIB.BASEBOARD_FAB2(SCH_1):VR_PVDDQ_DEF_AIREF1
  CTI45    1      A  CAP_A       I116
  EU7A1   39  REFIN  IR354XX_SM  I106
  EU7A5   21  AIREF1  PXM1310B_QFN  I75
  R3L9     2      B  RES         I57

VR_PVDDQ_DEF_AIREF2   @BASEBOARD_FAB2_LIB.BASEBOARD_FAB2(SCH_1):VR_PVDDQ_DEF_AIREF2
  CTI46    1      A  CAP_A       I113
  EU7A4   39  REFIN  IR354XX_SM  I107
  EU7A5   23  AIREF2  PXM1310B_QFN  I75
  R3L10    2      B  RES         I50

VR_PVDDQ_DEF_AVSP   @BASEBOARD_FAB2_LIB.BASEBOARD_FAB2(SCH_1):VR_PVDDQ_DEF_AVSP
  C7A28    1      A  CAP         I61
  EU7A5   19  AVSEN  PXM1310B_QFN  I75
  R7A7     2      B  RES         I60

VR_PVDDQ_DEF_PH1_BOOT   @BASEBOARD_FAB2_LIB.BASEBOARD_FAB2(SCH_1):VR_PVDDQ_DEF_PH1_BOOT
  C7A12    1      A  CAP_0402    I44
  RTI30    1      1  2D2R2F-GP_SMD-RG1  I118

VR_PVDDQ_DEF_PH1_BOOT_R   @BASEBOARD_FAB2_LIB.BASEBOARD_FAB2(SCH_1):VR_PVDDQ_DEF_PH1_BOOT_R
  EU7A1   33  BOOST  IR354XX_SM  I106
  RTI30    2      2  2D2R2F-GP_SMD-RG1  I118

VR_PVDDQ_DEF_PH1_OCSET   @BASEBOARD_FAB2_LIB.BASEBOARD_FAB2(SCH_1):VR_PVDDQ_DEF_PH1_OCSET
  EU7A1   37  OCSET  IR354XX_SM  I106
  R7A20    1      A  RES         I108

VR_PVDDQ_DEF_PH1_PHASE   @BASEBOARD_FAB2_LIB.BASEBOARD_FAB2(SCH_1):VR_PVDDQ_DEF_PH1_PHASE
  C7A12    2      B  CAP_0402    I44
  EU7A1   32  PHASE  IR354XX_SM  I106

VR_PVDDQ_DEF_PH1_SW   @BASEBOARD_FAB2_LIB.BASEBOARD_FAB2(SCH_1):VR_PVDDQ_DEF_PH1_SW
  CTI44    1      1  SC2K2P50V3KX-GP_SMD-BCG6  I127
  EU7A1   10     SW  IR354XX_SM  I106
  L7A1     1    INA  INDUCTOR    I55

VR_PVDDQ_DEF_PH1_VCIN   @BASEBOARD_FAB2_LIB.BASEBOARD_FAB2(SCH_1):VR_PVDDQ_DEF_PH1_VCIN
  C7A16    1      A  CAP_0402    I50
  EU7A1    3    VCC  IR354XX_SM  I106
  R3L6     1      A  RES         I52

VR_PVDDQ_DEF_PH2_BOOT   @BASEBOARD_FAB2_LIB.BASEBOARD_FAB2(SCH_1):VR_PVDDQ_DEF_PH2_BOOT
  C7A22    1      A  CAP_0402    I75
  RTI31    1      1  2D2R2F-GP_SMD-RG1  I115

VR_PVDDQ_DEF_PH2_BOOT_R   @BASEBOARD_FAB2_LIB.BASEBOARD_FAB2(SCH_1):VR_PVDDQ_DEF_PH2_BOOT_R
  EU7A4   33  BOOST  IR354XX_SM  I107
  RTI31    2      2  2D2R2F-GP_SMD-RG1  I115

VR_PVDDQ_DEF_PH2_OCSET   @BASEBOARD_FAB2_LIB.BASEBOARD_FAB2(SCH_1):VR_PVDDQ_DEF_PH2_OCSET
  EU7A4   37  OCSET  IR354XX_SM  I107
  R7A21    1      A  RES         I110

VR_PVDDQ_DEF_PH2_PHASE   @BASEBOARD_FAB2_LIB.BASEBOARD_FAB2(SCH_1):VR_PVDDQ_DEF_PH2_PHASE
  C7A22    2      B  CAP_0402    I75
  EU7A4   32  PHASE  IR354XX_SM  I107

VR_PVDDQ_DEF_PH2_SW   @BASEBOARD_FAB2_LIB.BASEBOARD_FAB2(SCH_1):VR_PVDDQ_DEF_PH2_SW
  CTI47    1      1  SC2K2P50V3KX-GP_SMD-BCG6  I121
  EU7A4   10     SW  IR354XX_SM  I107
  L7A3     1    INA  INDUCTOR    I65

VR_PVDDQ_DEF_PH2_VCIN   @BASEBOARD_FAB2_LIB.BASEBOARD_FAB2(SCH_1):VR_PVDDQ_DEF_PH2_VCIN
  C7A24    1      A  CAP_0402    I77
  EU7A4    3    VCC  IR354XX_SM  I107
  R3L8     1      A  RES         I76

VR_PVDDQ_DEF_PWM1   @BASEBOARD_FAB2_LIB.BASEBOARD_FAB2(SCH_1):VR_PVDDQ_DEF_PWM1
  EU7A1   34    PWM  IR354XX_SM  I106
  EU7A5    5  APWM1  PXM1310B_QFN  I75

VR_PVDDQ_DEF_PWM2   @BASEBOARD_FAB2_LIB.BASEBOARD_FAB2(SCH_1):VR_PVDDQ_DEF_PWM2
  EU7A4   34    PWM  IR354XX_SM  I107
  EU7A5    4  APWM2  PXM1310B_QFN  I75

VR_PVDDQ_DEF_VD12   @BASEBOARD_FAB2_LIB.BASEBOARD_FAB2(SCH_1):VR_PVDDQ_DEF_VD12
  C7B1     1      A  CAP_A       I22
  C7B2     1      A  CAP_A       I23
  EU7A5   40   VD12  PXM1310B_QFN  I75
  R3L9     1      A  RES         I57
  R3L10    1      A  RES         I50

VR_PVDDQ_DEF_VDD   @BASEBOARD_FAB2_LIB.BASEBOARD_FAB2(SCH_1):VR_PVDDQ_DEF_VDD
  C7A37    1      A  CAP_A       I29
  C7A38    1      A  CAP_A       I31
  EU7A5   39    VDD  PXM1310B_QFN  I75
  R3M1     2      B  RES         I34

VR_PVDDQ_DEF_VINSEN   @BASEBOARD_FAB2_LIB.BASEBOARD_FAB2(SCH_1):VR_PVDDQ_DEF_VINSEN
  C7A35    1      A  CAP         I55
  EU7A5   37  VINSEN  PXM1310B_QFN  I75
  R3L12    2      B  RES         I53
  R7A16    1      A  RES         I54

VR_PVDDQ_DEF_VREN   @BASEBOARD_FAB2_LIB.BASEBOARD_FAB2(SCH_1):VR_PVDDQ_DEF_VREN
  EU7A5   10  AVREN  PXM1310B_QFN  I75
  R3M5     2      B  RES         I35
  R3M6     2      B  RES         I59

VR_PVDDQ_DEF_XADDR1   @BASEBOARD_FAB2_LIB.BASEBOARD_FAB2(SCH_1):VR_PVDDQ_DEF_XADDR1
  EU7A5   36  XADDR1  PXM1310B_QFN  I75
  R7A10    1      A  RES         I40

VR_PVDDQ_DEF_XADDR2   @BASEBOARD_FAB2_LIB.BASEBOARD_FAB2(SCH_1):VR_PVDDQ_DEF_XADDR2
  EU7A5   33  XADDR2  PXM1310B_QFN  I75
  R7A8     1      A  RES         I37

VR_PVDDQ_GHJ_AIINSEN   @BASEBOARD_FAB2_LIB.BASEBOARD_FAB2(SCH_1):VR_PVDDQ_GHJ_AIINSEN
  C9U12    1      A  CAP_A       I92
  EU1G2   38  IINSEN  PXM1310B_QFN  I90
  R9T4     2      B  RES         I126

VR_PVDDQ_GHJ_AIINSEN_R   @BASEBOARD_FAB2_LIB.BASEBOARD_FAB2(SCH_1):VR_PVDDQ_GHJ_AIINSEN_R
  R9T4     1      A  RES         I126
  U1F1     3    OUT  MAX9634_SOT  I133

VR_PVDDQ_GHJ_AIREF1   @BASEBOARD_FAB2_LIB.BASEBOARD_FAB2(SCH_1):VR_PVDDQ_GHJ_AIREF1
  CTI30    1      A  CAP_A       I117
  EU1G1   39  REFIN  IR354XX_SM  I110
  EU1G2   21  AIREF1  PXM1310B_QFN  I90
  R1G28    2      B  RES         I87

VR_PVDDQ_GHJ_AIREF2   @BASEBOARD_FAB2_LIB.BASEBOARD_FAB2(SCH_1):VR_PVDDQ_GHJ_AIREF2
  CTI31    1      A  CAP_A       I124
  EU1F1   39  REFIN  IR354XX_SM  I111
  EU1G2   23  AIREF2  PXM1310B_QFN  I90
  R1G27    2      B  RES         I88

VR_PVDDQ_GHJ_AVSP   @BASEBOARD_FAB2_LIB.BASEBOARD_FAB2(SCH_1):VR_PVDDQ_GHJ_AVSP
  C1G16    1      A  CAP         I39
  EU1G2   19  AVSEN  PXM1310B_QFN  I90
  R1G5     2      B  RES         I32

VR_PVDDQ_GHJ_PH1_BOOT   @BASEBOARD_FAB2_LIB.BASEBOARD_FAB2(SCH_1):VR_PVDDQ_GHJ_PH1_BOOT
  C1G11    1      A  CAP_0402    I44
  RTI19    1      1  2D2R2F-GP_SMD-RG1  I116

VR_PVDDQ_GHJ_PH1_BOOT_R   @BASEBOARD_FAB2_LIB.BASEBOARD_FAB2(SCH_1):VR_PVDDQ_GHJ_PH1_BOOT_R
  EU1G1   33  BOOST  IR354XX_SM  I110
  RTI19    2      2  2D2R2F-GP_SMD-RG1  I116

VR_PVDDQ_GHJ_PH1_OCSET   @BASEBOARD_FAB2_LIB.BASEBOARD_FAB2(SCH_1):VR_PVDDQ_GHJ_PH1_OCSET
  EU1G1   37  OCSET  IR354XX_SM  I110
  R1G26    1      A  RES         I112

VR_PVDDQ_GHJ_PH1_PHASE   @BASEBOARD_FAB2_LIB.BASEBOARD_FAB2(SCH_1):VR_PVDDQ_GHJ_PH1_PHASE
  C1G11    2      B  CAP_0402    I44
  EU1G1   32  PHASE  IR354XX_SM  I110

VR_PVDDQ_GHJ_PH1_SW   @BASEBOARD_FAB2_LIB.BASEBOARD_FAB2(SCH_1):VR_PVDDQ_GHJ_PH1_SW
  CTI29    1      1  SC2K2P50V3KX-GP_SMD-BCG6  I121
  EU1G1   10     SW  IR354XX_SM  I110
  L1G1     1    INA  INDUCTOR    I55

VR_PVDDQ_GHJ_PH1_VCIN   @BASEBOARD_FAB2_LIB.BASEBOARD_FAB2(SCH_1):VR_PVDDQ_GHJ_PH1_VCIN
  C1G6     1      A  CAP_0402    I50
  EU1G1    3    VCC  IR354XX_SM  I110
  R9U1     1      A  RES         I52

VR_PVDDQ_GHJ_PH2_BOOT   @BASEBOARD_FAB2_LIB.BASEBOARD_FAB2(SCH_1):VR_PVDDQ_GHJ_PH2_BOOT
  C1F26    1      A  CAP_0402    I75
  RTI21    1      1  2D2R2F-GP_SMD-RG1  I126

VR_PVDDQ_GHJ_PH2_BOOT_R   @BASEBOARD_FAB2_LIB.BASEBOARD_FAB2(SCH_1):VR_PVDDQ_GHJ_PH2_BOOT_R
  EU1F1   33  BOOST  IR354XX_SM  I111
  RTI21    2      2  2D2R2F-GP_SMD-RG1  I126

VR_PVDDQ_GHJ_PH2_OCSET   @BASEBOARD_FAB2_LIB.BASEBOARD_FAB2(SCH_1):VR_PVDDQ_GHJ_PH2_OCSET
  EU1F1   37  OCSET  IR354XX_SM  I111
  R1G25    1      A  RES         I114

VR_PVDDQ_GHJ_PH2_PHASE   @BASEBOARD_FAB2_LIB.BASEBOARD_FAB2(SCH_1):VR_PVDDQ_GHJ_PH2_PHASE
  C1F26    2      B  CAP_0402    I75
  EU1F1   32  PHASE  IR354XX_SM  I111

VR_PVDDQ_GHJ_PH2_SW   @BASEBOARD_FAB2_LIB.BASEBOARD_FAB2(SCH_1):VR_PVDDQ_GHJ_PH2_SW
  CTI33    1      1  SC2K2P50V3KX-GP_SMD-BCG6  I127
  EU1F1   10     SW  IR354XX_SM  I111
  L1F2     1    INA  INDUCTOR    I65

VR_PVDDQ_GHJ_PH2_VCIN   @BASEBOARD_FAB2_LIB.BASEBOARD_FAB2(SCH_1):VR_PVDDQ_GHJ_PH2_VCIN
  C1G28    1      A  CAP_0402    I77
  EU1F1    3    VCC  IR354XX_SM  I111
  R9U12    1      A  RES         I76

VR_PVDDQ_GHJ_PWM1   @BASEBOARD_FAB2_LIB.BASEBOARD_FAB2(SCH_1):VR_PVDDQ_GHJ_PWM1
  EU1G1   34    PWM  IR354XX_SM  I110
  EU1G2    5  APWM1  PXM1310B_QFN  I90

VR_PVDDQ_GHJ_PWM2   @BASEBOARD_FAB2_LIB.BASEBOARD_FAB2(SCH_1):VR_PVDDQ_GHJ_PWM2
  EU1F1   34    PWM  IR354XX_SM  I111
  EU1G2    4  APWM2  PXM1310B_QFN  I90

VR_PVDDQ_GHJ_VD12   @BASEBOARD_FAB2_LIB.BASEBOARD_FAB2(SCH_1):VR_PVDDQ_GHJ_VD12
  C1G22    1      A  CAP_A       I44
  C1G23    1      A  CAP_A       I41
  EU1G2   40   VD12  PXM1310B_QFN  I90
  R1G27    1      A  RES         I88
  R1G28    1      A  RES         I87

VR_PVDDQ_GHJ_VDD   @BASEBOARD_FAB2_LIB.BASEBOARD_FAB2(SCH_1):VR_PVDDQ_GHJ_VDD
  C1G25    1      A  CAP_A       I27
  C1G27    1      A  CAP_A       I25
  EU1G2   39    VDD  PXM1310B_QFN  I90
  R9U10    2      B  RES         I30

VR_PVDDQ_GHJ_VINSEN   @BASEBOARD_FAB2_LIB.BASEBOARD_FAB2(SCH_1):VR_PVDDQ_GHJ_VINSEN
  C1G26    1      A  CAP         I59
  EU1G2   37  VINSEN  PXM1310B_QFN  I90
  R1G24    1      A  RES         I58
  R9U11    2      B  RES         I57

VR_PVDDQ_GHJ_VREN   @BASEBOARD_FAB2_LIB.BASEBOARD_FAB2(SCH_1):VR_PVDDQ_GHJ_VREN
  EU1G2   10  AVREN  PXM1310B_QFN  I90
  R9U7     2      B  RES         I84
  R9U8     2      B  RES         I85

VR_PVDDQ_GHJ_XADDR1   @BASEBOARD_FAB2_LIB.BASEBOARD_FAB2(SCH_1):VR_PVDDQ_GHJ_XADDR1
  EU1G2   36  XADDR1  PXM1310B_QFN  I90
  R1G23    1      A  RES         I77

VR_PVDDQ_GHJ_XADDR2   @BASEBOARD_FAB2_LIB.BASEBOARD_FAB2(SCH_1):VR_PVDDQ_GHJ_XADDR2
  EU1G2   33  XADDR2  PXM1310B_QFN  I90
  R1G22    1      A  RES         I78

VR_PVDDQ_KLM_AIINSEN   @BASEBOARD_FAB2_LIB.BASEBOARD_FAB2(SCH_1):VR_PVDDQ_KLM_AIINSEN
  C9M11    1      A  CAP_A       I92
  EU1B1   38  IINSEN  PXM1310B_QFN  I90
  R1B14    2      B  RES         I137

VR_PVDDQ_KLM_AIINSEN_R   @BASEBOARD_FAB2_LIB.BASEBOARD_FAB2(SCH_1):VR_PVDDQ_KLM_AIINSEN_R
  R1B14    1      A  RES         I137
  U1B1     3    OUT  MAX9634_SOT  I144

VR_PVDDQ_KLM_AIREF1   @BASEBOARD_FAB2_LIB.BASEBOARD_FAB2(SCH_1):VR_PVDDQ_KLM_AIREF1
  CTI7     1      A  CAP_A       I109
  EU1A2   39  REFIN  IR354XX_SM  I101
  EU1B1   21  AIREF1  PXM1310B_QFN  I90
  R9M11    2      B  RES         I87

VR_PVDDQ_KLM_AIREF2   @BASEBOARD_FAB2_LIB.BASEBOARD_FAB2(SCH_1):VR_PVDDQ_KLM_AIREF2
  CTI12    1      A  CAP_A       I122
  EU1A1   39  REFIN  IR354XX_SM  I102
  EU1B1   23  AIREF2  PXM1310B_QFN  I90
  R9M10    2      B  RES         I88

VR_PVDDQ_KLM_AVSP   @BASEBOARD_FAB2_LIB.BASEBOARD_FAB2(SCH_1):VR_PVDDQ_KLM_AVSP
  C1B12    1      A  CAP         I39
  EU1B1   19  AVSEN  PXM1310B_QFN  I90
  R1B16    2      B  RES         I32

VR_PVDDQ_KLM_PH1_BOOT   @BASEBOARD_FAB2_LIB.BASEBOARD_FAB2(SCH_1):VR_PVDDQ_KLM_PH1_BOOT
  C1A18    1      A  CAP_0402    I44
  RTI5     1      1  2D2R2F-GP_SMD-RG1  I108

VR_PVDDQ_KLM_PH1_BOOT_R   @BASEBOARD_FAB2_LIB.BASEBOARD_FAB2(SCH_1):VR_PVDDQ_KLM_PH1_BOOT_R
  EU1A2   33  BOOST  IR354XX_SM  I101
  RTI5     2      2  2D2R2F-GP_SMD-RG1  I108

VR_PVDDQ_KLM_PH1_OCSET   @BASEBOARD_FAB2_LIB.BASEBOARD_FAB2(SCH_1):VR_PVDDQ_KLM_PH1_OCSET
  EU1A2   37  OCSET  IR354XX_SM  I101
  R1A3     1      A  RES         I103

VR_PVDDQ_KLM_PH1_PHASE   @BASEBOARD_FAB2_LIB.BASEBOARD_FAB2(SCH_1):VR_PVDDQ_KLM_PH1_PHASE
  C1A18    2      B  CAP_0402    I44
  EU1A2   32  PHASE  IR354XX_SM  I101

VR_PVDDQ_KLM_PH1_SW   @BASEBOARD_FAB2_LIB.BASEBOARD_FAB2(SCH_1):VR_PVDDQ_KLM_PH1_SW
  CTI9     1      1  SC2K2P50V3KX-GP_SMD-BCG6  I111
  EU1A2   10     SW  IR354XX_SM  I101
  L1A2     1    INA  INDUCTOR    I55

VR_PVDDQ_KLM_PH1_VCIN   @BASEBOARD_FAB2_LIB.BASEBOARD_FAB2(SCH_1):VR_PVDDQ_KLM_PH1_VCIN
  C1B20    1      A  CAP_0402    I50
  EU1A2    3    VCC  IR354XX_SM  I101
  R9L9     1      A  RES         I52

VR_PVDDQ_KLM_PH2_BOOT   @BASEBOARD_FAB2_LIB.BASEBOARD_FAB2(SCH_1):VR_PVDDQ_KLM_PH2_BOOT
  C1A8     1      A  CAP_0402    I75
  RTI8     1      1  2D2R2F-GP_SMD-RG1  I121

VR_PVDDQ_KLM_PH2_BOOT_R   @BASEBOARD_FAB2_LIB.BASEBOARD_FAB2(SCH_1):VR_PVDDQ_KLM_PH2_BOOT_R
  EU1A1   33  BOOST  IR354XX_SM  I102
  RTI8     2      2  2D2R2F-GP_SMD-RG1  I121

VR_PVDDQ_KLM_PH2_OCSET   @BASEBOARD_FAB2_LIB.BASEBOARD_FAB2(SCH_1):VR_PVDDQ_KLM_PH2_OCSET
  EU1A1   37  OCSET  IR354XX_SM  I102
  R1A2     1      A  RES         I105

VR_PVDDQ_KLM_PH2_PHASE   @BASEBOARD_FAB2_LIB.BASEBOARD_FAB2(SCH_1):VR_PVDDQ_KLM_PH2_PHASE
  C1A8     2      B  CAP_0402    I75
  EU1A1   32  PHASE  IR354XX_SM  I102

VR_PVDDQ_KLM_PH2_SW   @BASEBOARD_FAB2_LIB.BASEBOARD_FAB2(SCH_1):VR_PVDDQ_KLM_PH2_SW
  CTI11    1      1  SC2K2P50V3KX-GP_SMD-BCG6  I116
  EU1A1   10     SW  IR354XX_SM  I102
  L1A1     1    INA  INDUCTOR    I65

VR_PVDDQ_KLM_PH2_VCIN   @BASEBOARD_FAB2_LIB.BASEBOARD_FAB2(SCH_1):VR_PVDDQ_KLM_PH2_VCIN
  C1A6     1      A  CAP_0402    I77
  EU1A1    3    VCC  IR354XX_SM  I102
  R9L4     1      A  RES         I76

VR_PVDDQ_KLM_PWM1   @BASEBOARD_FAB2_LIB.BASEBOARD_FAB2(SCH_1):VR_PVDDQ_KLM_PWM1
  EU1A2   34    PWM  IR354XX_SM  I101
  EU1B1    5  APWM1  PXM1310B_QFN  I90

VR_PVDDQ_KLM_PWM2   @BASEBOARD_FAB2_LIB.BASEBOARD_FAB2(SCH_1):VR_PVDDQ_KLM_PWM2
  EU1A1   34    PWM  IR354XX_SM  I102
  EU1B1    4  APWM2  PXM1310B_QFN  I90

VR_PVDDQ_KLM_VD12   @BASEBOARD_FAB2_LIB.BASEBOARD_FAB2(SCH_1):VR_PVDDQ_KLM_VD12
  C1B2     1      A  CAP_A       I44
  C1B3     1      A  CAP_A       I41
  EU1B1   40   VD12  PXM1310B_QFN  I90
  R9M10    1      A  RES         I88
  R9M11    1      A  RES         I87

VR_PVDDQ_KLM_VDD   @BASEBOARD_FAB2_LIB.BASEBOARD_FAB2(SCH_1):VR_PVDDQ_KLM_VDD
  C1B5     1      A  CAP_A       I27
  C1B6     1      A  CAP_A       I25
  EU1B1   39    VDD  PXM1310B_QFN  I90
  R9M3     2      B  RES         I30

VR_PVDDQ_KLM_VINSEN   @BASEBOARD_FAB2_LIB.BASEBOARD_FAB2(SCH_1):VR_PVDDQ_KLM_VINSEN
  C1B8     1      A  CAP         I59
  EU1B1   37  VINSEN  PXM1310B_QFN  I90
  R1B9     1      A  RES         I58
  R9M8     2      B  RES         I57

VR_PVDDQ_KLM_VREN   @BASEBOARD_FAB2_LIB.BASEBOARD_FAB2(SCH_1):VR_PVDDQ_KLM_VREN
  EU1B1   10  AVREN  PXM1310B_QFN  I90
  R9M5     2      B  RES         I85
  R9M9     2      B  RES         I84

VR_PVDDQ_KLM_XADDR1   @BASEBOARD_FAB2_LIB.BASEBOARD_FAB2(SCH_1):VR_PVDDQ_KLM_XADDR1
  EU1B1   36  XADDR1  PXM1310B_QFN  I90
  R1B12    1      A  RES         I78

VR_PVDDQ_KLM_XADDR2   @BASEBOARD_FAB2_LIB.BASEBOARD_FAB2(SCH_1):VR_PVDDQ_KLM_XADDR2
  EU1B1   33  XADDR2  PXM1310B_QFN  I90
  R1B15    1      A  RES         I77

VR_PVNN_P1V05_PCH_VD12   @BASEBOARD_FAB2_LIB.BASEBOARD_FAB2(SCH_1):VR_PVNN_P1V05_PCH_VD12
  C8A7     1      A  CAP_A       I143
  C8A8     1      A  CAP_A       I145
  EU8A1   40   VD12  PXE1110B_QFN  I229
  R2L1     1      A  RES         I224
  R2L7     1      A  RES         I225

VR_PVNN_PCH_AIREF1   @BASEBOARD_FAB2_LIB.BASEBOARD_FAB2(SCH_1):VR_PVNN_PCH_AIREF1
  CTI66    1      A  CAP_A       I127
  EU7A3   39  REFIN  IR354XX_SM  I116
  EU8A1   21  AIREF1  PXE1110B_QFN  I229
  R2L1     2      B  RES         I224

VR_PVNN_PCH_AVSP   @BASEBOARD_FAB2_LIB.BASEBOARD_FAB2(SCH_1):VR_PVNN_PCH_AVSP
  C8A2     1      A  CAP         I209
  EU8A1   19  AVSEN  PXE1110B_QFN  I229
  R8A1     2      B  RES         I210

VR_PVNN_PCH_PH1_BOOT   @BASEBOARD_FAB2_LIB.BASEBOARD_FAB2(SCH_1):VR_PVNN_PCH_PH1_BOOT
  C7A43    1      A  CAP_0402    I21
  RTI44    1      1  2D2R2F-GP_SMD-RG1  I128

VR_PVNN_PCH_PH1_BOOT_R   @BASEBOARD_FAB2_LIB.BASEBOARD_FAB2(SCH_1):VR_PVNN_PCH_PH1_BOOT_R
  EU7A3   33  BOOST  IR354XX_SM  I116
  RTI44    2      2  2D2R2F-GP_SMD-RG1  I128

VR_PVNN_PCH_PH1_PHASE   @BASEBOARD_FAB2_LIB.BASEBOARD_FAB2(SCH_1):VR_PVNN_PCH_PH1_PHASE
  C7A43    2      B  CAP_0402    I21
  EU7A3   32  PHASE  IR354XX_SM  I116

VR_PVNN_PCH_PH1_PHASE_SW   @BASEBOARD_FAB2_LIB.BASEBOARD_FAB2(SCH_1):VR_PVNN_PCH_PH1_PHASE_SW
  CTI65    1      1  SC2K2P50V3KX-GP_SMD-BCG6  I131
  EU7A3   10     SW  IR354XX_SM  I116
  L7A2     1    INA  INDUCTOR    I10

VR_PVNN_PCH_PH1_VCIN   @BASEBOARD_FAB2_LIB.BASEBOARD_FAB2(SCH_1):VR_PVNN_PCH_PH1_VCIN
  C7A6     1      A  CAP_0402    I19
  EU7A3    3    VCC  IR354XX_SM  I116
  R3L1     1      A  RES         I14

VR_PVNN_PCH_PWM1   @BASEBOARD_FAB2_LIB.BASEBOARD_FAB2(SCH_1):VR_PVNN_PCH_PWM1
  EU7A3   34    PWM  IR354XX_SM  I116
  EU8A1    5  APWM1  PXE1110B_QFN  I229

VR_PVNN_PCH_STBY_OCSET   @BASEBOARD_FAB2_LIB.BASEBOARD_FAB2(SCH_1):VR_PVNN_PCH_STBY_OCSET
  EU7A3   37  OCSET  IR354XX_SM  I116
  R3L15    1      A  RES         I118

VR_PVNN_PCH_VDD   @BASEBOARD_FAB2_LIB.BASEBOARD_FAB2(SCH_1):VR_PVNN_PCH_VDD
  C2L8     1      A  CAP_A       I151
  C2L11    1      A  CAP_A       I169
  EU8A1   39    VDD  PXE1110B_QFN  I229
  R2L14    2      B  RES         I159

VR_PVNN_PCH_VINSEN   @BASEBOARD_FAB2_LIB.BASEBOARD_FAB2(SCH_1):VR_PVNN_PCH_VINSEN
  C8A3     1      A  CAP         I167
  EU8A1   37  VINSEN  PXE1110B_QFN  I229
  R2L10    1      A  RES         I166
  R8A4     2      B  RES         I165

VR_PVNN_PCH_VREN   @BASEBOARD_FAB2_LIB.BASEBOARD_FAB2(SCH_1):VR_PVNN_PCH_VREN
  EU8A1   10  AVREN  PXE1110B_QFN  I229
  R2L17    2      B  RES         I221
  R8A7     2      B  RES         I222

VR_PVNN_PCH_XADDR1   @BASEBOARD_FAB2_LIB.BASEBOARD_FAB2(SCH_1):VR_PVNN_PCH_XADDR1
  EU8A1   36  XADDR1  PXE1110B_QFN  I229
  R2L9     1      A  RES         I176

VR_PVNN_PCH_XADDR2   @BASEBOARD_FAB2_LIB.BASEBOARD_FAB2(SCH_1):VR_PVNN_PCH_XADDR2
  EU8A1   33  XADDR2  PXE1110B_QFN  I229
  R8A2     1      A  RES         I217

VR_PVPP_ABC_BOOT   @BASEBOARD_FAB2_LIB.BASEBOARD_FAB2(SCH_1):VR_PVPP_ABC_BOOT
  EU7F1   36    BST  NCP3232L_SM  I193
  R7F8     1      A  RES         I154

VR_PVPP_ABC_BOOT_R   @BASEBOARD_FAB2_LIB.BASEBOARD_FAB2(SCH_1):VR_PVPP_ABC_BOOT_R
  C7F4     2      B  CAP         I159
  R7F8     2      B  RES         I154

VR_PVPP_ABC_ISET   @BASEBOARD_FAB2_LIB.BASEBOARD_FAB2(SCH_1):VR_PVPP_ABC_ISET
  EU7F1    4   ISET  NCP3232L_SM  I193
  R7F15    1      A  RES         I134

VR_PVPP_ABC_PHASE   @BASEBOARD_FAB2_LIB.BASEBOARD_FAB2(SCH_1):VR_PVPP_ABC_PHASE
  C7F3     1      A  CAP         I175
  C7F4     1      A  CAP         I159
  EU7F1   15  VSWH<0>  NCP3232L_SM  I193
  EU7F1   29  VSWH<1>  NCP3232L_SM  I193
  EU7F1   30  VSWH<2>  NCP3232L_SM  I193
  EU7F1   31  VSWH<3>  NCP3232L_SM  I193
  EU7F1   32  VSWH<4>  NCP3232L_SM  I193
  EU7F1   33  VSWH<5>  NCP3232L_SM  I193
  EU7F1   34  VSWH<6>  NCP3232L_SM  I193
  EU7F1   35    VSW  NCP3232L_SM  I193
  EU7F1   43  VSWH<7>  NCP3232L_SM  I193
  L7F1     1    INA  INDUCTOR    I178

VR_PVPP_ABC_SNUB   @BASEBOARD_FAB2_LIB.BASEBOARD_FAB2(SCH_1):VR_PVPP_ABC_SNUB
  C7F3     2      B  CAP         I175
  R7F7     1      A  RES         I174

VR_PVPP_ABC_SS   @BASEBOARD_FAB2_LIB.BASEBOARD_FAB2(SCH_1):VR_PVPP_ABC_SS
  C7F10    1      A  CAP_0402    I194
  EU7F1    1     SS  NCP3232L_SM  I193

VR_PVPP_DEF_BOOT   @BASEBOARD_FAB2_LIB.BASEBOARD_FAB2(SCH_1):VR_PVPP_DEF_BOOT
  EU7B1   36    BST  NCP3232L_SM  I214
  R7B19    1      A  RES         I240

VR_PVPP_DEF_BOOT_R   @BASEBOARD_FAB2_LIB.BASEBOARD_FAB2(SCH_1):VR_PVPP_DEF_BOOT_R
  C7B30    2      B  CAP         I241
  R7B19    2      B  RES         I240

VR_PVPP_DEF_ISET   @BASEBOARD_FAB2_LIB.BASEBOARD_FAB2(SCH_1):VR_PVPP_DEF_ISET
  EU7B1    4   ISET  NCP3232L_SM  I214
  R7B14    1      A  RES         I193

VR_PVPP_DEF_PHASE   @BASEBOARD_FAB2_LIB.BASEBOARD_FAB2(SCH_1):VR_PVPP_DEF_PHASE
  C7A34    1      A  CAP         I220
  C7B30    1      A  CAP         I241
  EU7B1   15  VSWH<0>  NCP3232L_SM  I214
  EU7B1   29  VSWH<1>  NCP3232L_SM  I214
  EU7B1   30  VSWH<2>  NCP3232L_SM  I214
  EU7B1   31  VSWH<3>  NCP3232L_SM  I214
  EU7B1   32  VSWH<4>  NCP3232L_SM  I214
  EU7B1   33  VSWH<5>  NCP3232L_SM  I214
  EU7B1   34  VSWH<6>  NCP3232L_SM  I214
  EU7B1   35    VSW  NCP3232L_SM  I214
  EU7B1   43  VSWH<7>  NCP3232L_SM  I214
  L7B1     1    INA  INDUCTOR    I239

VR_PVPP_DEF_SNUB   @BASEBOARD_FAB2_LIB.BASEBOARD_FAB2(SCH_1):VR_PVPP_DEF_SNUB
  C7A34    2      B  CAP         I220
  R7A15    1      A  RES         I218

VR_PVPP_DEF_SS   @BASEBOARD_FAB2_LIB.BASEBOARD_FAB2(SCH_1):VR_PVPP_DEF_SS
  C7B11    1      A  CAP_0402    I197
  EU7B1    1     SS  NCP3232L_SM  I214

VR_PVPP_GHJ_BOOT   @BASEBOARD_FAB2_LIB.BASEBOARD_FAB2(SCH_1):VR_PVPP_GHJ_BOOT
  EU4G1   36    BST  NCP3232L_SM  I225
  R4G24    1      A  RES         I199

VR_PVPP_GHJ_BOOT_R   @BASEBOARD_FAB2_LIB.BASEBOARD_FAB2(SCH_1):VR_PVPP_GHJ_BOOT_R
  C4G26    2      B  CAP         I224
  R4G24    2      B  RES         I199

VR_PVPP_GHJ_ISET   @BASEBOARD_FAB2_LIB.BASEBOARD_FAB2(SCH_1):VR_PVPP_GHJ_ISET
  EU4G1    4   ISET  NCP3232L_SM  I225
  R4G11    1      A  RES         I184

VR_PVPP_GHJ_PHASE   @BASEBOARD_FAB2_LIB.BASEBOARD_FAB2(SCH_1):VR_PVPP_GHJ_PHASE
  C4F12    1      A  CAP         I209
  C4G26    1      A  CAP         I224
  EU4G1   15  VSWH<0>  NCP3232L_SM  I225
  EU4G1   29  VSWH<1>  NCP3232L_SM  I225
  EU4G1   30  VSWH<2>  NCP3232L_SM  I225
  EU4G1   31  VSWH<3>  NCP3232L_SM  I225
  EU4G1   32  VSWH<4>  NCP3232L_SM  I225
  EU4G1   33  VSWH<5>  NCP3232L_SM  I225
  EU4G1   34  VSWH<6>  NCP3232L_SM  I225
  EU4G1   35    VSW  NCP3232L_SM  I225
  EU4G1   43  VSWH<7>  NCP3232L_SM  I225
  L4G1     1    INA  INDUCTOR    I277

VR_PVPP_GHJ_SNUB   @BASEBOARD_FAB2_LIB.BASEBOARD_FAB2(SCH_1):VR_PVPP_GHJ_SNUB
  C4F12    2      B  CAP         I209
  R4F6     1      A  RES         I208

VR_PVPP_GHJ_SS   @BASEBOARD_FAB2_LIB.BASEBOARD_FAB2(SCH_1):VR_PVPP_GHJ_SS
  C4G8     1      A  CAP_0402    I194
  EU4G1    1     SS  NCP3232L_SM  I225

VR_PVPP_KLM_BOOT   @BASEBOARD_FAB2_LIB.BASEBOARD_FAB2(SCH_1):VR_PVPP_KLM_BOOT
  EU4A3   36    BST  NCP3232L_SM  I184
  R4B13    1      A  RES         I155

VR_PVPP_KLM_BOOT_R   @BASEBOARD_FAB2_LIB.BASEBOARD_FAB2(SCH_1):VR_PVPP_KLM_BOOT_R
  C4B15    2      B  CAP         I182
  R4B13    2      B  RES         I155

VR_PVPP_KLM_ISET   @BASEBOARD_FAB2_LIB.BASEBOARD_FAB2(SCH_1):VR_PVPP_KLM_ISET
  EU4A3    4   ISET  NCP3232L_SM  I184
  R4B6     1      A  RES         I140

VR_PVPP_KLM_PHASE   @BASEBOARD_FAB2_LIB.BASEBOARD_FAB2(SCH_1):VR_PVPP_KLM_PHASE
  C4A16    1      A  CAP         I163
  C4B15    1      A  CAP         I182
  EU4A3   15  VSWH<0>  NCP3232L_SM  I184
  EU4A3   29  VSWH<1>  NCP3232L_SM  I184
  EU4A3   30  VSWH<2>  NCP3232L_SM  I184
  EU4A3   31  VSWH<3>  NCP3232L_SM  I184
  EU4A3   32  VSWH<4>  NCP3232L_SM  I184
  EU4A3   33  VSWH<5>  NCP3232L_SM  I184
  EU4A3   34  VSWH<6>  NCP3232L_SM  I184
  EU4A3   35    VSW  NCP3232L_SM  I184
  EU4A3   43  VSWH<7>  NCP3232L_SM  I184
  L4A1     1    INA  INDUCTOR    I164

VR_PVPP_KLM_SNUB   @BASEBOARD_FAB2_LIB.BASEBOARD_FAB2(SCH_1):VR_PVPP_KLM_SNUB
  C4A16    2      B  CAP         I163
  R4A7     1      A  RES         I162

VR_PVPP_KLM_SS   @BASEBOARD_FAB2_LIB.BASEBOARD_FAB2(SCH_1):VR_PVPP_KLM_SS
  C4B6     1      A  CAP_0402    I146
  EU4A3    1     SS  NCP3232L_SM  I184

VR_PVSA_CPU0_BIREF1   @BASEBOARD_FAB2_LIB.BASEBOARD_FAB2(SCH_1):VR_PVSA_CPU0_BIREF1
  CTI60    1      A  CAP_A       I69
  EU4C1   39  REFIN  IR354XX_SM  I46
  EU4D4   37  BIREF1  PXE1610B_QFN  I155
  R6P29    2      B  RES         I154

VR_PVSA_CPU0_BOOT   @BASEBOARD_FAB2_LIB.BASEBOARD_FAB2(SCH_1):VR_PVSA_CPU0_BOOT
  C4C8     1      A  CAP_0402    I25
  RTI40    1      1  2D2R2F-GP_SMD-RG1  I71

VR_PVSA_CPU0_BOOT_R   @BASEBOARD_FAB2_LIB.BASEBOARD_FAB2(SCH_1):VR_PVSA_CPU0_BOOT_R
  EU4C1   33  BOOST  IR354XX_SM  I46
  RTI40    2      2  2D2R2F-GP_SMD-RG1  I71

VR_PVSA_CPU0_OCSET   @BASEBOARD_FAB2_LIB.BASEBOARD_FAB2(SCH_1):VR_PVSA_CPU0_OCSET
  EU4C1   37  OCSET  IR354XX_SM  I46
  R4C13    1      A  RES         I62

VR_PVSA_CPU0_PHASE   @BASEBOARD_FAB2_LIB.BASEBOARD_FAB2(SCH_1):VR_PVSA_CPU0_PHASE
  C4C8     2      B  CAP_0402    I25
  EU4C1   32  PHASE  IR354XX_SM  I46

VR_PVSA_CPU0_PHASE_SW   @BASEBOARD_FAB2_LIB.BASEBOARD_FAB2(SCH_1):VR_PVSA_CPU0_PHASE_SW
  CTI59    1      1  SC2K2P50V3KX-GP_SMD-BCG6  I64
  EU4C1   10     SW  IR354XX_SM  I46
  L4C2     1    INA  INDUCTOR     I7

VR_PVSA_CPU0_PWM   @BASEBOARD_FAB2_LIB.BASEBOARD_FAB2(SCH_1):VR_PVSA_CPU0_PWM
  EU4C1   34    PWM  IR354XX_SM  I46
  EU4D4    1  BPWM1  PXE1610B_QFN  I155

VR_PVSA_CPU0_VCIN   @BASEBOARD_FAB2_LIB.BASEBOARD_FAB2(SCH_1):VR_PVSA_CPU0_VCIN
  C4C6     1      A  CAP_0402    I20
  EU4C1    3    VCC  IR354XX_SM  I46
  R6N3     1      A  RES         I19

VR_PVSA_CPU1_BIREF1   @BASEBOARD_FAB2_LIB.BASEBOARD_FAB2(SCH_1):VR_PVSA_CPU1_BIREF1
  CTI57    1      A  CAP_A       I55
  EU1C1   39  REFIN  IR354XX_SM  I51
  EU1C2   37  BIREF1  PXE1610B_QFN  I130
  R9N5     2      B  RES         I128

VR_PVSA_CPU1_BOOT   @BASEBOARD_FAB2_LIB.BASEBOARD_FAB2(SCH_1):VR_PVSA_CPU1_BOOT
  C1C12    1      A  CAP_0402    I24
  RTI37    1      1  2D2R2F-GP_SMD-RG1  I56

VR_PVSA_CPU1_BOOT_R   @BASEBOARD_FAB2_LIB.BASEBOARD_FAB2(SCH_1):VR_PVSA_CPU1_BOOT_R
  EU1C1   33  BOOST  IR354XX_SM  I51
  RTI37    2      2  2D2R2F-GP_SMD-RG1  I56

VR_PVSA_CPU1_OCSET   @BASEBOARD_FAB2_LIB.BASEBOARD_FAB2(SCH_1):VR_PVSA_CPU1_OCSET
  EU1C1   37  OCSET  IR354XX_SM  I51
  R1C37    1      A  RES         I52

VR_PVSA_CPU1_PHASE   @BASEBOARD_FAB2_LIB.BASEBOARD_FAB2(SCH_1):VR_PVSA_CPU1_PHASE
  C1C12    2      B  CAP_0402    I24
  EU1C1   32  PHASE  IR354XX_SM  I51

VR_PVSA_CPU1_PHASE_SW   @BASEBOARD_FAB2_LIB.BASEBOARD_FAB2(SCH_1):VR_PVSA_CPU1_PHASE_SW
  CTI56    1      1  SC2K2P50V3KX-GP_SMD-BCG6  I57
  EU1C1   10     SW  IR354XX_SM  I51
  L1C1     1    INA  INDUCTOR    I10

VR_PVSA_CPU1_PWM   @BASEBOARD_FAB2_LIB.BASEBOARD_FAB2(SCH_1):VR_PVSA_CPU1_PWM
  EU1C1   34    PWM  IR354XX_SM  I51
  EU1C2    1  BPWM1  PXE1610B_QFN  I130

VR_PVSA_CPU1_VCIN   @BASEBOARD_FAB2_LIB.BASEBOARD_FAB2(SCH_1):VR_PVSA_CPU1_VCIN
  C1C5     1      A  CAP_0402    I26
  EU1C1    3    VCC  IR354XX_SM  I51
  R9N3     1      A  RES         I20

VR_PVTT_ABC_BIAS   @BASEBOARD_FAB2_LIB.BASEBOARD_FAB2(SCH_1):VR_PVTT_ABC_BIAS
  C4G15    1      A  CAP_0402    I24
  EU4G3    2   BIAS  MIC5166_DFN   I1
  R6U4     2      B  RES         I28

VR_PVTT_ABC_SNS   @BASEBOARD_FAB2_LIB.BASEBOARD_FAB2(SCH_1):VR_PVTT_ABC_SNS
  EU4G3    6    SNS  MIC5166_DFN   I1
  SH5U1    1      A  SHUNT       I56

VR_PVTT_ABC_VREF   @BASEBOARD_FAB2_LIB.BASEBOARD_FAB2(SCH_1):VR_PVTT_ABC_VREF
  C4G16    1      A  CAP_0402    I34
  EU4G3    1   VREF  MIC5166_DFN   I1

VR_PVTT_DEF_BIAS   @BASEBOARD_FAB2_LIB.BASEBOARD_FAB2(SCH_1):VR_PVTT_DEF_BIAS
  C4A10    1      A  CAP_0402    I28
  EU4A1    2   BIAS  MIC5166_DFN  I31
  R6L11    2      B  RES         I30

VR_PVTT_DEF_SNS   @BASEBOARD_FAB2_LIB.BASEBOARD_FAB2(SCH_1):VR_PVTT_DEF_SNS
  EU4A1    6    SNS  MIC5166_DFN  I31
  SH5L1    1      A  SHUNT       I53

VR_PVTT_DEF_VREF   @BASEBOARD_FAB2_LIB.BASEBOARD_FAB2(SCH_1):VR_PVTT_DEF_VREF
  C4A9     1      A  CAP_0402    I21
  EU4A1    1   VREF  MIC5166_DFN  I31

VR_PVTT_GHJ_BIAS   @BASEBOARD_FAB2_LIB.BASEBOARD_FAB2(SCH_1):VR_PVTT_GHJ_BIAS
  C4G18    1      A  CAP_0402    I27
  EU4G2    2   BIAS  MIC5166_DFN  I24
  R6U7     2      B  RES         I32

VR_PVTT_GHJ_SNS   @BASEBOARD_FAB2_LIB.BASEBOARD_FAB2(SCH_1):VR_PVTT_GHJ_SNS
  EU4G2    6    SNS  MIC5166_DFN  I24
  SH8U1    1      A  SHUNT       I53

VR_PVTT_GHJ_VREF   @BASEBOARD_FAB2_LIB.BASEBOARD_FAB2(SCH_1):VR_PVTT_GHJ_VREF
  C4G21    1      A  CAP_0402    I21
  EU4G2    1   VREF  MIC5166_DFN  I24

VR_PVTT_KLM_BIAS   @BASEBOARD_FAB2_LIB.BASEBOARD_FAB2(SCH_1):VR_PVTT_KLM_BIAS
  C4A8     1      A  CAP_0402    I28
  EU4A2    2   BIAS  MIC5166_DFN  I31
  R6L8     2      B  RES         I30

VR_PVTT_KLM_SNS   @BASEBOARD_FAB2_LIB.BASEBOARD_FAB2(SCH_1):VR_PVTT_KLM_SNS
  EU4A2    6    SNS  MIC5166_DFN  I31
  SH8L1    1      A  SHUNT       I53

VR_PVTT_KLM_VREF   @BASEBOARD_FAB2_LIB.BASEBOARD_FAB2(SCH_1):VR_PVTT_KLM_VREF
  C4A14    1      A  CAP_0402    I21
  EU4A2    1   VREF  MIC5166_DFN  I31

VR_VB_PVPP_ABC   @BASEBOARD_FAB2_LIB.BASEBOARD_FAB2(SCH_1):VR_VB_PVPP_ABC
  C3T11    1      A  CAP         I202
  EU7F1   38     VB  NCP3232L_SM  I193

VR_VB_PVPP_DEF   @BASEBOARD_FAB2_LIB.BASEBOARD_FAB2(SCH_1):VR_VB_PVPP_DEF
  C3M10    1      A  CAP         I253
  EU7B1   38     VB  NCP3232L_SM  I214

VR_VB_PVPP_GHJ   @BASEBOARD_FAB2_LIB.BASEBOARD_FAB2(SCH_1):VR_VB_PVPP_GHJ
  C6U6     1      A  CAP         I187
  EU4G1   38     VB  NCP3232L_SM  I225

VR_VB_PVPP_KLM   @BASEBOARD_FAB2_LIB.BASEBOARD_FAB2(SCH_1):VR_VB_PVPP_KLM
  C6L12    1      A  CAP         I144
  EU4A3   38     VB  NCP3232L_SM  I184

VR_VRRDY_PVCCIN_CPU0   @BASEBOARD_FAB2_LIB.BASEBOARD_FAB2(SCH_1):VR_VRRDY_PVCCIN_CPU0
  C4D42    1      A  CAP         I125
  EU4D4   11  AVRRDY  PXE1610B_QFN  I155
  R4D58    2      B  RES         I25
  R4D63    1      A  RES         I124

VR_VRRDY_PVCCIN_CPU1   @BASEBOARD_FAB2_LIB.BASEBOARD_FAB2(SCH_1):VR_VRRDY_PVCCIN_CPU1
  C1C23    1      A  CAP         I114
  EU1C2   11  AVRRDY  PXE1610B_QFN  I130
  R1C28    2      B  RES         I35
  R1C30    1      A  RES         I113

VSENSE_P12V_ADM1085   @BASEBOARD_FAB2_LIB.BASEBOARD_FAB2(SCH_1):VSENSE_P12V_ADM1085
  R3P48    2      B  RES         I74
  R3P51    1      A  RES         I75
  U7D3     3    VIN  ADM1085_SMT  I70

VSENSE_P1V05_PCH_STBY_AVSN   @BASEBOARD_FAB2_LIB.BASEBOARD_FAB2(SCH_1):VSENSE_P1V05_PCH_STBY_AVSN
  C2L2     2      B  CAP         I153
  EU8A1   30  BVREF  PXE1110B_QFN  I229
  R8B12    1      A  RES         I59
  R8B15    2      B  RES         I57

VSENSE_P1V05_PCH_STBY_AVSP   @BASEBOARD_FAB2_LIB.BASEBOARD_FAB2(SCH_1):VSENSE_P1V05_PCH_STBY_AVSP
  R2L8     1      A  RES         I154
  R8B14    1      A  RES         I56
  R8B15    1      A  RES         I57

VSENSE_P1V8MCP_CPU0_SKT_VRTN   @BASEBOARD_FAB2_LIB.BASEBOARD_FAB2(SCH_1):VSENSE_P1V8MCP_CPU0_SKT_VRTN
  J6E1    D2   IOD2  SCONN120_H61426002_SM  I55
  U5D1   AL20  RSVD<215>  SKX_EXT_B_BGA1  I204

VSENSE_P1V8MCP_CPU0_SKT_VSEN   @BASEBOARD_FAB2_LIB.BASEBOARD_FAB2(SCH_1):VSENSE_P1V8MCP_CPU0_SKT_VSEN
  J6E1    D1   IOD1  SCONN120_H61426002_SM  I55
  U5D1   AK21  RSVD<221>  SKX_EXT_B_BGA1  I204

VSENSE_P1V8MCP_CPU1_SKT_VRTN   @BASEBOARD_FAB2_LIB.BASEBOARD_FAB2(SCH_1):VSENSE_P1V8MCP_CPU1_SKT_VRTN
  J4E1    D2   IOD2  SCONN120_H61426002_SM  I45
  U2D1   AL20  RSVD<215>  SKX_EXT_B_BGA1  I169

VSENSE_P1V8MCP_CPU1_SKT_VSEN   @BASEBOARD_FAB2_LIB.BASEBOARD_FAB2(SCH_1):VSENSE_P1V8MCP_CPU1_SKT_VSEN
  J4E1    D1   IOD1  SCONN120_H61426002_SM  I45
  U2D1   AK21  RSVD<221>  SKX_EXT_B_BGA1  I169

VSENSE_P3V3_STBY   @BASEBOARD_FAB2_LIB.BASEBOARD_FAB2(SCH_1):VSENSE_P3V3_STBY
  R8E25    2      B  RES         I144
  R8E31    1      A  RES         I143

VSENSE_PMAX_CPU0   @BASEBOARD_FAB2_LIB.BASEBOARD_FAB2(SCH_1):VSENSE_PMAX_CPU0
  R5D5     1      A  RES         I303
  R5D6     2      B  RES         I312
  U5D1   AD41  VSENSEPMAX  SKX_EXT_B_BGA1  I311

VSENSE_PMAX_CPU1   @BASEBOARD_FAB2_LIB.BASEBOARD_FAB2(SCH_1):VSENSE_PMAX_CPU1
  R3D27    1      A  RES         I43
  R3D32    2      B  RES         I53
  U2D1   AD41  VSENSEPMAX  SKX_EXT_B_BGA1  I51

VSENSE_PVCCIN_CPU0_AVSP   @BASEBOARD_FAB2_LIB.BASEBOARD_FAB2(SCH_1):VSENSE_PVCCIN_CPU0_AVSP
  C4D45    1      A  CAP         I70
  EU4D4   21  AVSEN  PXE1610B_QFN  I155
  R4E8     2      B  RES         I109

VSENSE_PVCCIN_CPU0_N   @BASEBOARD_FAB2_LIB.BASEBOARD_FAB2(SCH_1):VSENSE_PVCCIN_CPU0_N
  C4D45    2      B  CAP         I70
  EU4D4   22  AVREF  PXE1610B_QFN  I155
  R4E15    2      B  RES         I63
  R4E17    1      A  RES         I62
  R4E18    1      A  RES         I64

VSENSE_PVCCIN_CPU0_P   @BASEBOARD_FAB2_LIB.BASEBOARD_FAB2(SCH_1):VSENSE_PVCCIN_CPU0_P
  R4E8     1      A  RES         I109
  R4E14    1      A  RES         I60
  R4E15    1      A  RES         I63
  R4E16    1      A  RES         I61

VSENSE_PVCCIN_CPU0_SKT_VRTN   @BASEBOARD_FAB2_LIB.BASEBOARD_FAB2(SCH_1):VSENSE_PVCCIN_CPU0_SKT_VRTN
  R4E17    2      B  RES         I62
  U5D1   AY85  VSS_VCCIN_SENSE  SKX_EXT_B_BGA1  I311

VSENSE_PVCCIN_CPU0_SKT_VSEN   @BASEBOARD_FAB2_LIB.BASEBOARD_FAB2(SCH_1):VSENSE_PVCCIN_CPU0_SKT_VSEN
  R4E16    2      B  RES         I61
  U5D1   BA86  VCCIN_SENSE  SKX_EXT_B_BGA1  I311

VSENSE_PVCCIN_CPU1_AVSP   @BASEBOARD_FAB2_LIB.BASEBOARD_FAB2(SCH_1):VSENSE_PVCCIN_CPU1_AVSP
  C1D1     1      A  CAP         I78
  EU1C2   21  AVSEN  PXE1610B_QFN  I130
  R1D4     2      B  RES         I79

VSENSE_PVCCIN_CPU1_N   @BASEBOARD_FAB2_LIB.BASEBOARD_FAB2(SCH_1):VSENSE_PVCCIN_CPU1_N
  C1D1     2      B  CAP         I78
  EU1C2   22  AVREF  PXE1610B_QFN  I130
  R1E5     2      B  RES          I3
  R1E7     1      A  RES         I10
  R1E8     1      A  RES          I9

VSENSE_PVCCIN_CPU1_P   @BASEBOARD_FAB2_LIB.BASEBOARD_FAB2(SCH_1):VSENSE_PVCCIN_CPU1_P
  R1D4     1      A  RES         I79
  R1E4     1      A  RES         I15
  R1E5     1      A  RES          I3
  R1E6     1      A  RES         I11

VSENSE_PVCCIN_CPU1_SKT_VRTN   @BASEBOARD_FAB2_LIB.BASEBOARD_FAB2(SCH_1):VSENSE_PVCCIN_CPU1_SKT_VRTN
  R1E7     2      B  RES         I10
  U2D1   AY85  VSS_VCCIN_SENSE  SKX_EXT_B_BGA1  I51

VSENSE_PVCCIN_CPU1_SKT_VSEN   @BASEBOARD_FAB2_LIB.BASEBOARD_FAB2(SCH_1):VSENSE_PVCCIN_CPU1_SKT_VSEN
  R1E6     2      B  RES         I11
  U2D1   BA86  VCCIN_SENSE  SKX_EXT_B_BGA1  I51

VSENSE_PVCCIOMCP_CPU0_SKT_VRTN   @BASEBOARD_FAB2_LIB.BASEBOARD_FAB2(SCH_1):VSENSE_PVCCIOMCP_CPU0_SKT_VRTN
  J6B1    F8   IOF8  SCONN120_H61426002_SM  I56
  U5D1   BU16  CD_VCCP_SENSE<0>  SKX_EXT_B_BGA1  I127

VSENSE_PVCCIOMCP_CPU0_SKT_VSEN   @BASEBOARD_FAB2_LIB.BASEBOARD_FAB2(SCH_1):VSENSE_PVCCIOMCP_CPU0_SKT_VSEN
  J6B1    E8   IOE8  SCONN120_H61426002_SM  I56
  U5D1   BT17  CD_VCCP_SENSE<1>  SKX_EXT_B_BGA1  I127

VSENSE_PVCCIOMCP_CPU1_SKT_VRTN   @BASEBOARD_FAB2_LIB.BASEBOARD_FAB2(SCH_1):VSENSE_PVCCIOMCP_CPU1_SKT_VRTN
  J4B2    F8   IOF8  SCONN120_H61426002_SM  I46
  U2D1   BU16  CD_VCCP_SENSE<0>  SKX_EXT_B_BGA1  I107

VSENSE_PVCCIOMCP_CPU1_SKT_VSEN   @BASEBOARD_FAB2_LIB.BASEBOARD_FAB2(SCH_1):VSENSE_PVCCIOMCP_CPU1_SKT_VSEN
  J4B2    E8   IOE8  SCONN120_H61426002_SM  I46
  U2D1   BT17  CD_VCCP_SENSE<1>  SKX_EXT_B_BGA1  I107

VSENSE_PVCCIO_CPU0_AVSN   @BASEBOARD_FAB2_LIB.BASEBOARD_FAB2(SCH_1):VSENSE_PVCCIO_CPU0_AVSN
  C3N39    2      B  CAP         I83
  EU3P1   20  AVREF  PXE1110B_QFN  I93
  R3N20    1      A  RES         I68
  SH3P2    2      B  SHUNT       I105

VSENSE_PVCCIO_CPU0_AVSP   @BASEBOARD_FAB2_LIB.BASEBOARD_FAB2(SCH_1):VSENSE_PVCCIO_CPU0_AVSP
  R3N19    1      A  RES         I81
  R3N21    1      A  RES         I74
  SH3P1    2      B  SHUNT       I104

VSENSE_PVCCIO_CPU0_SKT_VRTN   @BASEBOARD_FAB2_LIB.BASEBOARD_FAB2(SCH_1):VSENSE_PVCCIO_CPU0_SKT_VRTN
  C3P1     2      B  CAP_A       I60
  SH3P2    1      A  SHUNT       I105
  U5D1   BF5  VSS_VCCIO_SENSE  SKX_EXT_B_BGA1  I127

VSENSE_PVCCIO_CPU0_SKT_VSEN   @BASEBOARD_FAB2_LIB.BASEBOARD_FAB2(SCH_1):VSENSE_PVCCIO_CPU0_SKT_VSEN
  C3P1     1      A  CAP_A       I60
  SH3P1    1      A  SHUNT       I104
  U5D1   BH5  VCCIO_SENSE  SKX_EXT_B_BGA1  I127

VSENSE_PVCCIO_CPU1_AVSN   @BASEBOARD_FAB2_LIB.BASEBOARD_FAB2(SCH_1):VSENSE_PVCCIO_CPU1_AVSN
  C4D44    2      B  CAP         I83
  EU4D5   20  AVREF  PXE1110B_QFN  I96
  R3D28    1      A  RES         I101
  SH3D1    2      B  SHUNT       I130

VSENSE_PVCCIO_CPU1_AVSP   @BASEBOARD_FAB2_LIB.BASEBOARD_FAB2(SCH_1):VSENSE_PVCCIO_CPU1_AVSP
  R3E1     1      A  RES         I105
  R4E7     1      A  RES         I84
  SH3D2    2      B  SHUNT       I129

VSENSE_PVCCIO_CPU1_SKT_VRTN   @BASEBOARD_FAB2_LIB.BASEBOARD_FAB2(SCH_1):VSENSE_PVCCIO_CPU1_SKT_VRTN
  C3D27    2      B  CAP_A       I96
  SH3D1    1      A  SHUNT       I130
  U2D1   BF5  VSS_VCCIO_SENSE  SKX_EXT_B_BGA1  I107

VSENSE_PVCCIO_CPU1_SKT_VSEN   @BASEBOARD_FAB2_LIB.BASEBOARD_FAB2(SCH_1):VSENSE_PVCCIO_CPU1_SKT_VSEN
  C3D27    1      A  CAP_A       I96
  SH3D2    1      A  SHUNT       I129
  U2D1   BH5  VCCIO_SENSE  SKX_EXT_B_BGA1  I107

VSENSE_PVCCMCP_CPU0_SKT_VRTN   @BASEBOARD_FAB2_LIB.BASEBOARD_FAB2(SCH_1):VSENSE_PVCCMCP_CPU0_SKT_VRTN
  J6E1    B4   IOB4  SCONN120_H61426002_SM  I55
  U5D1   BL16  CD_VSS_VCC_CORE_SENSE  SKX_EXT_B_BGA1  I127

VSENSE_PVCCMCP_CPU0_SKT_VSEN   @BASEBOARD_FAB2_LIB.BASEBOARD_FAB2(SCH_1):VSENSE_PVCCMCP_CPU0_SKT_VSEN
  J6E1    A4   IOA4  SCONN120_H61426002_SM  I55
  U5D1   BN16  CD_VCC_CORE_SENSE  SKX_EXT_B_BGA1  I127

VSENSE_PVCCMCP_CPU1_SKT_VRTN   @BASEBOARD_FAB2_LIB.BASEBOARD_FAB2(SCH_1):VSENSE_PVCCMCP_CPU1_SKT_VRTN
  J4E1    B4   IOB4  SCONN120_H61426002_SM  I45
  U2D1   BL16  CD_VSS_VCC_CORE_SENSE  SKX_EXT_B_BGA1  I107

VSENSE_PVCCMCP_CPU1_SKT_VSEN   @BASEBOARD_FAB2_LIB.BASEBOARD_FAB2(SCH_1):VSENSE_PVCCMCP_CPU1_SKT_VSEN
  J4E1    A4   IOA4  SCONN120_H61426002_SM  I45
  U2D1   BN16  CD_VCC_CORE_SENSE  SKX_EXT_B_BGA1  I107

VSENSE_PVDDQ_ABC_N   @BASEBOARD_FAB2_LIB.BASEBOARD_FAB2(SCH_1):VSENSE_PVDDQ_ABC_N
  C7G4     2      B  CAP         I342
  EU7G1   20  AVREF  PXM1310B_QFN  I358
  R4U6     2      B  RES         I74
  SH4U1    1      A  SHUNT       I259

VSENSE_PVDDQ_ABC_P   @BASEBOARD_FAB2_LIB.BASEBOARD_FAB2(SCH_1):VSENSE_PVDDQ_ABC_P
  R4U6     1      A  RES         I74
  R7G9     1      A  RES         I344
  SH4U2    1      A  SHUNT       I260

VSENSE_PVDDQ_ABC_VTT   @BASEBOARD_FAB2_LIB.BASEBOARD_FAB2(SCH_1):VSENSE_PVDDQ_ABC_VTT
  C6U12    1      A  CAP         I49
  EU4G3    4   VDDQ  MIC5166_DFN   I1
  R6U5     2      B  RES         I32

VSENSE_PVDDQ_DEF_N   @BASEBOARD_FAB2_LIB.BASEBOARD_FAB2(SCH_1):VSENSE_PVDDQ_DEF_N
  C7A28    2      B  CAP         I61
  EU7A5   20  AVREF  PXM1310B_QFN  I75
  R4L2     2      B  RES         I74
  SH4L1    1      A  SHUNT       I240

VSENSE_PVDDQ_DEF_P   @BASEBOARD_FAB2_LIB.BASEBOARD_FAB2(SCH_1):VSENSE_PVDDQ_DEF_P
  R4L2     1      A  RES         I74
  R7A7     1      A  RES         I60
  SH4L2    1      A  SHUNT       I239

VSENSE_PVDDQ_DEF_VTT   @BASEBOARD_FAB2_LIB.BASEBOARD_FAB2(SCH_1):VSENSE_PVDDQ_DEF_VTT
  C4A11    1      A  CAP         I46
  EU4A1    4   VDDQ  MIC5166_DFN  I31
  R6L10    2      B  RES         I34

VSENSE_PVDDQ_GHJ_N   @BASEBOARD_FAB2_LIB.BASEBOARD_FAB2(SCH_1):VSENSE_PVDDQ_GHJ_N
  C1G16    2      B  CAP         I39
  EU1G2   20  AVREF  PXM1310B_QFN  I90
  R7U2     2      B  RES         I74
  SH7U2    1      A  SHUNT       I244

VSENSE_PVDDQ_GHJ_P   @BASEBOARD_FAB2_LIB.BASEBOARD_FAB2(SCH_1):VSENSE_PVDDQ_GHJ_P
  R1G5     1      A  RES         I32
  R7U2     1      A  RES         I74
  SH7U1    1      A  SHUNT       I243

VSENSE_PVDDQ_GHJ_VTT   @BASEBOARD_FAB2_LIB.BASEBOARD_FAB2(SCH_1):VSENSE_PVDDQ_GHJ_VTT
  C6U11    1      A  CAP         I46
  EU4G2    4   VDDQ  MIC5166_DFN  I24
  R6U6     2      B  RES         I39

VSENSE_PVDDQ_KLM_N   @BASEBOARD_FAB2_LIB.BASEBOARD_FAB2(SCH_1):VSENSE_PVDDQ_KLM_N
  C1B12    2      B  CAP         I39
  EU1B1   20  AVREF  PXM1310B_QFN  I90
  R7L2     2      B  RES         I74
  SH7L1    1      A  SHUNT       I246

VSENSE_PVDDQ_KLM_P   @BASEBOARD_FAB2_LIB.BASEBOARD_FAB2(SCH_1):VSENSE_PVDDQ_KLM_P
  R1B16    1      A  RES         I32
  R7L2     1      A  RES         I74
  SH7L2    1      A  SHUNT       I245

VSENSE_PVDDQ_KLM_VTT   @BASEBOARD_FAB2_LIB.BASEBOARD_FAB2(SCH_1):VSENSE_PVDDQ_KLM_VTT
  C4A7     1      A  CAP         I46
  EU4A2    4   VDDQ  MIC5166_DFN  I31
  R6L6     2      B  RES         I34

VSENSE_PVNN_PCH_STBY_AVSN   @BASEBOARD_FAB2_LIB.BASEBOARD_FAB2(SCH_1):VSENSE_PVNN_PCH_STBY_AVSN
  C8A2     2      B  CAP         I209
  EU8A1   20  AVREF  PXE1110B_QFN  I229
  R7A18    2      B  RES         I92

VSENSE_PVNN_PCH_STBY_AVSP   @BASEBOARD_FAB2_LIB.BASEBOARD_FAB2(SCH_1):VSENSE_PVNN_PCH_STBY_AVSP
  R7A13    1      A  RES         I90
  R7A14    2      B  RES         I94
  R7A19    2      B  RES         I93
  R8A1     1      A  RES         I210

VSENSE_PVNN_PCH_STBY_FPK   @BASEBOARD_FAB2_LIB.BASEBOARD_FAB2(SCH_1):VSENSE_PVNN_PCH_STBY_FPK
  R7A14    1      A  RES         I94
  U7C1   AK36  VCCPRIM_AVID_SENSE  LBG_CORE_QAT_EXT_D  I21

VSENSE_PVNN_PCH_STBY_QAT   @BASEBOARD_FAB2_LIB.BASEBOARD_FAB2(SCH_1):VSENSE_PVNN_PCH_STBY_QAT
  R7A19    1      A  RES         I93
  U7C1   V37  VCCPRIM_AVID_QAT_SENSE  LBG_CORE_QAT_EXT_D  I21

VSENSE_PVPP_ABC   @BASEBOARD_FAB2_LIB.BASEBOARD_FAB2(SCH_1):VSENSE_PVPP_ABC
  R7F12    2      B  RES         I168
  R7F13    1      A  RES         I167
  R7F17    1      A  RES         I218

VSENSE_PVPP_DEF   @BASEBOARD_FAB2_LIB.BASEBOARD_FAB2(SCH_1):VSENSE_PVPP_DEF
  R7B11    2      B  RES         I299
  R7B15    1      A  RES         I303
  R7B18    1      A  RES         I298

VSENSE_PVPP_GHJ   @BASEBOARD_FAB2_LIB.BASEBOARD_FAB2(SCH_1):VSENSE_PVPP_GHJ
  R4G7     1      A  RES         I270
  R4G8     2      B  RES         I271
  R4G10    1      A  RES         I266

VSENSE_PVPP_KLM   @BASEBOARD_FAB2_LIB.BASEBOARD_FAB2(SCH_1):VSENSE_PVPP_KLM
  R4B3     2      B  RES         I214
  R4B5     1      A  RES         I215
  R4B9     1      A  RES         I219

VSENSE_PVSA_CPU0_BVSP   @BASEBOARD_FAB2_LIB.BASEBOARD_FAB2(SCH_1):VSENSE_PVSA_CPU0_BVSP
  C4D29    1      A  CAP         I64
  EU4D4   35  BVSEN  PXE1610B_QFN  I155
  R4D39    2      B  RES         I110

VSENSE_PVSA_CPU0_N   @BASEBOARD_FAB2_LIB.BASEBOARD_FAB2(SCH_1):VSENSE_PVSA_CPU0_N
  C4D29    2      B  CAP         I64
  EU4D4   36  BVREF  PXE1610B_QFN  I155
  R4C1     1      A  RES         I29
  R4C2     1      A  RES         I30
  R4C3     2      B  RES         I37

VSENSE_PVSA_CPU0_P   @BASEBOARD_FAB2_LIB.BASEBOARD_FAB2(SCH_1):VSENSE_PVSA_CPU0_P
  R4C3     1      A  RES         I37
  R4C4     1      A  RES         I26
  R4C5     1      A  RES         I24
  R4D39    1      A  RES         I110

VSENSE_PVSA_CPU0_SKT_VRTN   @BASEBOARD_FAB2_LIB.BASEBOARD_FAB2(SCH_1):VSENSE_PVSA_CPU0_SKT_VRTN
  R4C2     2      B  RES         I30
  U5D1   CG76  VSS_VCCSA_SENSE  SKX_EXT_B_BGA1  I127

VSENSE_PVSA_CPU0_SKT_VSEN   @BASEBOARD_FAB2_LIB.BASEBOARD_FAB2(SCH_1):VSENSE_PVSA_CPU0_SKT_VSEN
  R4C4     2      B  RES         I26
  U5D1   CE76  VCCSA_SENSE  SKX_EXT_B_BGA1  I127

VSENSE_PVSA_CPU1_BVSP   @BASEBOARD_FAB2_LIB.BASEBOARD_FAB2(SCH_1):VSENSE_PVSA_CPU1_BVSP
  C1C16    1      A  CAP         I68
  EU1C2   35  BVSEN  PXE1610B_QFN  I130
  R1C21    2      B  RES         I77

VSENSE_PVSA_CPU1_N   @BASEBOARD_FAB2_LIB.BASEBOARD_FAB2(SCH_1):VSENSE_PVSA_CPU1_N
  C1C16    2      B  CAP         I68
  EU1C2   36  BVREF  PXE1610B_QFN  I130
  R1C4     1      A  RES         I33
  R1C5     1      A  RES         I32
  R1C6     2      B  RES         I34

VSENSE_PVSA_CPU1_P   @BASEBOARD_FAB2_LIB.BASEBOARD_FAB2(SCH_1):VSENSE_PVSA_CPU1_P
  R1C6     1      A  RES         I34
  R1C7     1      A  RES         I31
  R1C12    1      A  RES         I29
  R1C21    1      A  RES         I77

VSENSE_PVSA_CPU1_SKT_VRTN   @BASEBOARD_FAB2_LIB.BASEBOARD_FAB2(SCH_1):VSENSE_PVSA_CPU1_SKT_VRTN
  R1C5     2      B  RES         I32
  U2D1   CG76  VSS_VCCSA_SENSE  SKX_EXT_B_BGA1  I107

VSENSE_PVSA_CPU1_SKT_VSEN   @BASEBOARD_FAB2_LIB.BASEBOARD_FAB2(SCH_1):VSENSE_PVSA_CPU1_SKT_VSEN
  R1C7     2      B  RES         I31
  U2D1   CE76  VCCSA_SENSE  SKX_EXT_B_BGA1  I107

VSENSE_RGND_P3V3_STBY   @BASEBOARD_FAB2_LIB.BASEBOARD_FAB2(SCH_1):VSENSE_RGND_P3V3_STBY
  EU8F1    7   RGND  RT8240_QFN  I125
  R8E38    1      A  RES         I140

VSENSE_VCCINR2PMAX_CPU0   @BASEBOARD_FAB2_LIB.BASEBOARD_FAB2(SCH_1):VSENSE_VCCINR2PMAX_CPU0
  R5P1     2      B  RES         I309
  U5D1   AV85  VCCINPMAX<1>  SKX_EXT_B_BGA1  I311
  U5D1   AW86  VCCINPMAX<0>  SKX_EXT_B_BGA1  I311

VSENSE_VCCINR2PMAX_CPU1   @BASEBOARD_FAB2_LIB.BASEBOARD_FAB2(SCH_1):VSENSE_VCCINR2PMAX_CPU1
  RT8P1    2      B  RES         I49
  U2D1   AV85  VCCINPMAX<1>  SKX_EXT_B_BGA1  I51
  U2D1   AW86  VCCINPMAX<0>  SKX_EXT_B_BGA1  I51

VSENSE_VOUT_P3V3_STBY   @BASEBOARD_FAB2_LIB.BASEBOARD_FAB2(SCH_1):VSENSE_VOUT_P3V3_STBY
  EU8F1    6   VOUT  RT8240_QFN  I125
  R8E31    2      B  RES         I143
  R8E34    1      A  RES         I142

XDP_CPU0_TDO    @BASEBOARD_FAB2_LIB.BASEBOARD_FAB2(SCH_1):XDP_CPU0_TDO
  R4P23    2      B  RES         I58
  U1M4     2      A  74CBTLV1G125  I127
  U1M7     1     B1  NC7SB3157   I40
  U5D1   AE14    TDO  SKX_EXT_B_BGA1  I259

XDP_CPU1_TDI    @BASEBOARD_FAB2_LIB.BASEBOARD_FAB2(SCH_1):XDP_CPU1_TDI
  R6T6     2      B  RES         I56
  U1M4     4      B  74CBTLV1G125  I127
  U2D1   AC14    TDI  SKX_EXT_B_BGA1  I172

XDP_CPU1_TDO    @BASEBOARD_FAB2_LIB.BASEBOARD_FAB2(SCH_1):XDP_CPU1_TDO
  R6T7     2      B  RES         I55
  U1M7     3     B0  NC7SB3157   I40
  U2D1   AE14    TDO  SKX_EXT_B_BGA1  I172

XDP_CPU_GTL_TCK_R2   @BASEBOARD_FAB2_LIB.BASEBOARD_FAB2(SCH_1):XDP_CPU_GTL_TCK_R2
  Q9A1     1   E<0>  NPN_DUAL    I93
  R9A2     2      B  RES         I83

XDP_CPU_MBP0_N   @BASEBOARD_FAB2_LIB.BASEBOARD_FAB2(SCH_1):XDP_CPU_MBP0_N
  R4P12    2      B  RES         I57
  R7P30    2      B  RES         I50
  U2D1   AJ10  BPM_N<0>  SKX_EXT_B_BGA1  I172
  U5D1   AJ10  BPM_N<0>  SKX_EXT_B_BGA1  I259

XDP_CPU_MBP1_N   @BASEBOARD_FAB2_LIB.BASEBOARD_FAB2(SCH_1):XDP_CPU_MBP1_N
  R4P15    2      B  RES         I53
  R6P46    2      B  RES         I49
  U2D1   AH11  BPM_N<1>  SKX_EXT_B_BGA1  I172
  U5D1   AH11  BPM_N<1>  SKX_EXT_B_BGA1  I259

XDP_CPU_OBSFN_B0_MBP6_N   @BASEBOARD_FAB2_LIB.BASEBOARD_FAB2(SCH_1):XDP_CPU_OBSFN_B0_MBP6_N
  R6T8     2      B  RES         I121
  U1L5     6   B<0>  TTL3126_QFNLF  I109
  U2D1   AE12  BPM_N<6>  SKX_EXT_B_BGA1  I172
  U5D1   AE12  BPM_N<6>  SKX_EXT_B_BGA1  I259

XDP_CPU_OBSFN_B1_MBP7_N   @BASEBOARD_FAB2_LIB.BASEBOARD_FAB2(SCH_1):XDP_CPU_OBSFN_B1_MBP7_N
  R6T9     2      B  RES         I120
  U1L5     3   B<0>  TTL3126_QFNLF  I109
  U2D1   AC12  BPM_N<7>  SKX_EXT_B_BGA1  I172
  U5D1   AC12  BPM_N<7>  SKX_EXT_B_BGA1  I259

XDP_CPU_PRDY_N   @BASEBOARD_FAB2_LIB.BASEBOARD_FAB2(SCH_1):XDP_CPU_PRDY_N
  R1M3     2      B  RES         I51
  U1L5     8   B<0>  TTL3126_QFNLF  I109
  U2D1   AG16  PRDY_N  SKX_EXT_B_BGA1  I172
  U5D1   AG16  PRDY_N  SKX_EXT_B_BGA1  I259

XDP_CPU_PREQ_N   @BASEBOARD_FAB2_LIB.BASEBOARD_FAB2(SCH_1):XDP_CPU_PREQ_N
  R1M4     2      B  RES         I54
  U1L5    11   B<0>  TTL3126_QFNLF  I109
  U2D1   AR12  PREQ_N  SKX_EXT_B_BGA1  I172
  U5D1   AR12  PREQ_N  SKX_EXT_B_BGA1  I259

XDP_CPU_PWR_DEBUG_N   @BASEBOARD_FAB2_LIB.BASEBOARD_FAB2(SCH_1):XDP_CPU_PWR_DEBUG_N
  C9A4     1      A  CAP_A       I59
  J9A3    45   IO45  SCONN60_C21100002  I26
  R1L17    1      A  RES         I56
  U2D1   AP17  PWR_DEBUG_N  SKX_EXT_B_BGA1  I169
  U5D1   AP17  PWR_DEBUG_N  SKX_EXT_B_BGA1  I204
  U7D1     4      B  74CBTLV1G125  I142

XDP_CPU_TCK0    @BASEBOARD_FAB2_LIB.BASEBOARD_FAB2(SCH_1):XDP_CPU_TCK0
  J9A3    57   IO57  SCONN60_C21100002  I26
  Q9A1     4   E<0>  NPN_DUAL    I94
  R7P29    1      A  RES         I61
  R9A3     2      B  RES         I74
  U2D1   AA14    TCK  SKX_EXT_B_BGA1  I172
  U5D1   AA14    TCK  SKX_EXT_B_BGA1  I259

XDP_CPU_TCK_BUF   @BASEBOARD_FAB2_LIB.BASEBOARD_FAB2(SCH_1):XDP_CPU_TCK_BUF
  Q9A1     2   B<0>  NPN_DUAL    I93
  Q9A1     5   B<0>  NPN_DUAL    I94
  Q9A1     6   C<0>  NPN_DUAL    I93
  R9A1     2      B  RES         I95

XDP_CPU_TDI     @BASEBOARD_FAB2_LIB.BASEBOARD_FAB2(SCH_1):XDP_CPU_TDI
  R4P24    2      B  RES         I59
  U1L1    11   B<0>  TTL3126_QFNLF  I108
  U5D1   AC14    TDI  SKX_EXT_B_BGA1  I259

XDP_CPU_TDO     @BASEBOARD_FAB2_LIB.BASEBOARD_FAB2(SCH_1):XDP_CPU_TDO
  U1L1     8   B<0>  TTL3126_QFNLF  I108
  U1M7     4      A  NC7SB3157   I40

XDP_CPU_TMS     @BASEBOARD_FAB2_LIB.BASEBOARD_FAB2(SCH_1):XDP_CPU_TMS
  R1L15    2      B  RES         I60
  U1L1     6   B<0>  TTL3126_QFNLF  I108
  U2D1   W14    TMS  SKX_EXT_B_BGA1  I172
  U5D1   W14    TMS  SKX_EXT_B_BGA1  I259

XDP_CPU_TRST_N   @BASEBOARD_FAB2_LIB.BASEBOARD_FAB2(SCH_1):XDP_CPU_TRST_N
  R6T5     1      A  RES         I62
  U1L1     3   B<0>  TTL3126_QFNLF  I108
  U2D1   Y13  TRST_N  SKX_EXT_B_BGA1  I172
  U5D1   Y13  TRST_N  SKX_EXT_B_BGA1  I259

XDP_DEBUG_CONSENT_N   @BASEBOARD_FAB2_LIB.BASEBOARD_FAB2(SCH_1):XDP_DEBUG_CONSENT_N
  J9A3     1    IO1  SCONN60_C21100002  I26
  R2P2     2      B  RES         I37

XDP_ITP_PMODE   @BASEBOARD_FAB2_LIB.BASEBOARD_FAB2(SCH_1):XDP_ITP_PMODE
  J9A3    46   IO46  SCONN60_C21100002  I26
  R9A17    1      A  RES         I57
  U7C1   AR54  ITP_PMODE  LBG_CORE_QAT_EXT_D  I73

XDP_OBSFN_B0_MBP6_N   @BASEBOARD_FAB2_LIB.BASEBOARD_FAB2(SCH_1):XDP_OBSFN_B0_MBP6_N
  J9A3    22   IO22  SCONN60_C21100002  I26
  U1L5     5   A<0>  TTL3126_QFNLF  I109

XDP_OBSFN_B1_MBP7_N   @BASEBOARD_FAB2_LIB.BASEBOARD_FAB2(SCH_1):XDP_OBSFN_B1_MBP7_N
  J9A3    24   IO24  SCONN60_C21100002  I26
  U1L5     2   A<0>  TTL3126_QFNLF  I109

XDP_PCH_CPU_TCK0   @BASEBOARD_FAB2_LIB.BASEBOARD_FAB2(SCH_1):XDP_PCH_CPU_TCK0
  R3M10    1      A  RES         I85
  R9A2     1      A  RES         I83
  R9A3     1      A  RES         I74
  U7C1   AF54  JTAGX  LBG_CORE_QAT_EXT_D  I73

XDP_PCH_PWR_DEBUG_N   @BASEBOARD_FAB2_LIB.BASEBOARD_FAB2(SCH_1):XDP_PCH_PWR_DEBUG_N
  R7C23    2      B  RES         I144
  U7C1   G15   GPD0  LBG_CORE_QAT_EXT_D  I73
  U7D1     2      A  74CBTLV1G125  I142

XDP_PCH_TCK1    @BASEBOARD_FAB2_LIB.BASEBOARD_FAB2(SCH_1):XDP_PCH_TCK1
  J9A3    55   IO55  SCONN60_C21100002  I26
  R8B1     1      A  RES         I95
  U7C1   AL56  JTAG_TCK  LBG_CORE_QAT_EXT_D  I73

XDP_PRDY_N      @BASEBOARD_FAB2_LIB.BASEBOARD_FAB2(SCH_1):XDP_PRDY_N
  J9A3     5    IO5  SCONN60_C21100002  I26
  R1L39    2      B  RES         I76
  U1L5     9   A<0>  TTL3126_QFNLF  I109
  U7C1   AD54  PRDY_N  LBG_CORE_QAT_EXT_D  I73

XDP_PREQ_N      @BASEBOARD_FAB2_LIB.BASEBOARD_FAB2(SCH_1):XDP_PREQ_N
  J9A3     3    IO3  SCONN60_C21100002  I26
  R1L41    2      B  RES         I77
  U1L5    12   A<0>  TTL3126_QFNLF  I109
  U7C1   U54  PREQ_N  LBG_CORE_QAT_EXT_D  I73

XDP_PRESENT_N   @BASEBOARD_FAB2_LIB.BASEBOARD_FAB2(SCH_1):XDP_PRESENT_N
  J9A3    60   IO60  SCONN60_C21100002  I26
  R9A4     1      A  RES         I55
  U2D1   AV21  DEBUG_EN_N  SKX_EXT_B_BGA1  I169
  U5D1   AV21  DEBUG_EN_N  SKX_EXT_B_BGA1  I204

XDP_PWRGD_RST_N   @BASEBOARD_FAB2_LIB.BASEBOARD_FAB2(SCH_1):XDP_PWRGD_RST_N
  C1L8     1      A  CAP_A       I14
  J9A3    41   IO41  SCONN60_C21100002  I26
  R1L23    1      A  RES         I13
  U8D7   M11  PB19D  LCMXO2_A_256BGA  I179

XDP_RSMRST_N    @BASEBOARD_FAB2_LIB.BASEBOARD_FAB2(SCH_1):XDP_RSMRST_N
  J9A3    39   IO39  SCONN60_C21100002  I26
  R9A15    2      B  RES         I60

XDP_RST_CO_N    @BASEBOARD_FAB2_LIB.BASEBOARD_FAB2(SCH_1):XDP_RST_CO_N
  C9A5     1      A  CAP_A       I12
  J9A3    48   IO48  SCONN60_C21100002  I26
  R9A14    1      A  RES         I11
  U1L4     2      A  TTL1G07_A_SOP  I85

XDP_SPI_PCH_MOSI_BOOT_HALT_N   @BASEBOARD_FAB2_LIB.BASEBOARD_FAB2(SCH_1):XDP_SPI_PCH_MOSI_BOOT_HALT_N
  J9A3     6    IO6  SCONN60_C21100002  I26
  R8E2     1      A  RES         I89

XDP_SYSPWROK    @BASEBOARD_FAB2_LIB.BASEBOARD_FAB2(SCH_1):XDP_SYSPWROK
  C9A2     1      A  CAP_A       I10
  J9A3    47   IO47  SCONN60_C21100002  I26
  R1L13    1      A  RES          I6
  U8D7   N11  PB21D  LCMXO2_A_256BGA  I179

XDP_TDI         @BASEBOARD_FAB2_LIB.BASEBOARD_FAB2(SCH_1):XDP_TDI
  J9A3    56   IO56  SCONN60_C21100002  I26
  R8A13    2      B  RES         I79
  U1L1    12   A<0>  TTL3126_QFNLF  I108
  U7C1   AN54  JTAG_TDI  LBG_CORE_QAT_EXT_D  I73

XDP_TDO         @BASEBOARD_FAB2_LIB.BASEBOARD_FAB2(SCH_1):XDP_TDO
  J9A3    52   IO52  SCONN60_C21100002  I26
  R9A11    2      B  RES         I78
  U1L1     9   A<0>  TTL3126_QFNLF  I108
  U7C1   AP56  JTAG_TDO  LBG_CORE_QAT_EXT_D  I73

XDP_TMS         @BASEBOARD_FAB2_LIB.BASEBOARD_FAB2(SCH_1):XDP_TMS
  J9A3    58   IO58  SCONN60_C21100002  I26
  R8A14    2      B  RES         I80
  U1L1     5   A<0>  TTL3126_QFNLF  I108
  U7C1   AH54  JTAG_TMS  LBG_CORE_QAT_EXT_D  I73

XDP_TRST_N      @BASEBOARD_FAB2_LIB.BASEBOARD_FAB2(SCH_1):XDP_TRST_N
  J9A3    54   IO54  SCONN60_C21100002  I26
  R8B2     1      A  RES         I94
  U1L1     2   A<0>  TTL3126_QFNLF  I108
  U7C1   AT56  CPU_TRST_N  LBG_CORE_QAT_EXT_D  I73

XTAL_24MHZ_IN_R   @BASEBOARD_FAB2_LIB.BASEBOARD_FAB2(SCH_1):XTAL_24MHZ_IN_R
  EU9F3    9  XTAL1  PI7C9X1172_QFN   I1
  R9F58    2      B  RES         I24

XTAL_24MHZ_OUT_R   @BASEBOARD_FAB2_LIB.BASEBOARD_FAB2(SCH_1):XTAL_24MHZ_OUT_R
  EU9F3   10  XTAL2  PI7C9X1172_QFN   I1
  R9F59    2      B  RES         I25

XTAL_24MHZ_PI7C9X1172_IN   @BASEBOARD_FAB2_LIB.BASEBOARD_FAB2(SCH_1):XTAL_24MHZ_PI7C9X1172_IN
  C9F20    1      A  CAP         I20
  R9F58    1      A  RES         I24
  Y9F1     1      A  CRYSTAL_SM  I19

XTAL_24MHZ_PI7C9X1172_OUT   @BASEBOARD_FAB2_LIB.BASEBOARD_FAB2(SCH_1):XTAL_24MHZ_PI7C9X1172_OUT
  C9F21    1      A  CAP         I21
  R9F59    1      A  RES         I25
  Y9F1     2      B  CRYSTAL_SM  I19

XTAL_25MHZ_IN   @BASEBOARD_FAB2_LIB.BASEBOARD_FAB2(SCH_1):XTAL_25MHZ_IN
  C9E9     1      A  CAP         I112
  R9E20    1      A  RES         I110
  Y9E1     1      A  CRYSTAL_2013  I109

XTAL_25MHZ_IN_R   @BASEBOARD_FAB2_LIB.BASEBOARD_FAB2(SCH_1):XTAL_25MHZ_IN_R
  EU9E1   46  XTAL1  SPRINGVILLE_SM1  I72
  R9E20    2      B  RES         I110

XTAL_25MHZ_OUT   @BASEBOARD_FAB2_LIB.BASEBOARD_FAB2(SCH_1):XTAL_25MHZ_OUT
  EU9E1   45  XTAL2  SPRINGVILLE_SM1  I72
  R9E18    2      B  RES         I201

XTAL_25MHZ_OUT_R   @BASEBOARD_FAB2_LIB.BASEBOARD_FAB2(SCH_1):XTAL_25MHZ_OUT_R
  C9E8     1      A  CAP         I111
  R9E18    1      A  RES         I201
  Y9E1     3      B  CRYSTAL_2013  I109

XTAL_33K_RTC1   @BASEBOARD_FAB2_LIB.BASEBOARD_FAB2(SCH_1):XTAL_33K_RTC1
  C7C13    1      A  CAP         I56
  R7C6     1      A  RES         I54
  U7C1   K17  RTCX1  LBG_CORE_QAT_EXT_D  I40
  Y7C2     1      A  CRYSTAL_SM  I55

XTAL_33K_RTC2   @BASEBOARD_FAB2_LIB.BASEBOARD_FAB2(SCH_1):XTAL_33K_RTC2
  C7C15    1      A  CAP         I46
  R7C6     2      B  RES         I54
  U7C1   H17  RTCX2  LBG_CORE_QAT_EXT_D  I40
  Y7C2     2      B  CRYSTAL_SM  I55

XTAL_CK_MNG_IN   @BASEBOARD_FAB2_LIB.BASEBOARD_FAB2(SCH_1):XTAL_CK_MNG_IN
  C8F18    1      A  CAP         I49
  EU8F2   19  X1_25  ICS9FGP204_MLFP  I34
  Y8F1     1      A  CRYSTAL_2013LF  I52

XTAL_CK_MNG_OUT   @BASEBOARD_FAB2_LIB.BASEBOARD_FAB2(SCH_1):XTAL_CK_MNG_OUT
  C8F19    1      A  CAP         I53
  EU8F2   20  X2_25  ICS9FGP204_MLFP  I34
  Y8F1     3      B  CRYSTAL_2013LF  I52

XTAL_KR_25M_IN   @BASEBOARD_FAB2_LIB.BASEBOARD_FAB2(SCH_1):XTAL_KR_25M_IN
  C8C1     1      A  CAP         I79
  U7C1   BV16  LAN_XTAL_IN  LBG_CORE_QAT_EXT_D  I73
  Y8C1     1      A  CRYSTAL_2013  I76

XTAL_KR_25M_OUT   @BASEBOARD_FAB2_LIB.BASEBOARD_FAB2(SCH_1):XTAL_KR_25M_OUT
  C8C2     1      A  CAP         I77
  U7C1   BY16  LAN_XTAL_OUT  LBG_CORE_QAT_EXT_D  I73
  Y8C1     3      B  CRYSTAL_2013  I76

XTAL_PCH_48M_IN   @BASEBOARD_FAB2_LIB.BASEBOARD_FAB2(SCH_1):XTAL_PCH_48M_IN
  C7C4     1      A  CAP         I50
  R7C1     1      A  RES         I48
  U7C1   B35  XTAL_IN  LBG_CORE_QAT_EXT_D  I40
  Y7C1     1      A  CRYSTAL_2013  I49

XTAL_PCH_48M_OUT   @BASEBOARD_FAB2_LIB.BASEBOARD_FAB2(SCH_1):XTAL_PCH_48M_OUT
  C7C5     1      A  CAP         I47
  R7C1     2      B  RES         I48
  U7C1   D35  XTAL_OUT  LBG_CORE_QAT_EXT_D  I40
  Y7C1     3      B  CRYSTAL_2013  I49
END OF SIGNAL CROSS REFERENCE
**** Part Type 'BATTERY' ('BATTERY_PLCLF-202168-001') ****
**** Part Type 'CAPP' ('CAPP_2626-270UF,16V,20%,OSCON,A') ****
**** Part Type 'CAPP' ('CAPP_3018-470UF,2.5V,20%,ALUM,A') ****
**** Part Type 'CAPP' ('CAPP_3018-470UF,6.3V,20%,POSCAA') ****
**** Part Type 'CAPP' ('CAPP_3018-68UF,16V,20%,TANT,72A') ****
**** Part Type 'CAPP' ('CAPP_4040LF-470UF,16V,20%,ALUMA') ****
**** Part Type 'CAPP' ('CAPP_7343-220UF,4V,20%,POSCAP,A') ****
**** Part Type 'CAPP' ('CAPP_7343HLF-330UF,10V,20%,POSA') ****
**** Part Type 'CAPP' ('CAPP_7343LF-330UF,6.3V,20%,POSA') ****
**** Part Type 'CAPP' ('CAPP_SM-470UF,2V,20%,ALUM,6990A') ****
**** Part Type 'CAPTIVE_SCREW_TH' ('CAPTIVE_SCREW_TH-HDW,H57868-001') ****
**** Part Type 'CAP_0402' ('CAP_0402-0.027UF,16V,10%,X7R,AA') ****
**** Part Type 'CAP_0402' ('CAP_0402-0.047UF,25V,10%,X7R,AA') ****
**** Part Type 'CAP_0402' ('CAP_0402-0.220UF,16V,10%,X7R,AA') ****
**** Part Type 'CAP_0402' ('CAP_0402-0.22UF,16V,10%,EMPTY,A') ****
**** Part Type 'CAP_0402' ('CAP_0402-0.22UF,16V,10%,X7R,A3A') ****
**** Part Type 'CAP_0402' ('CAP_0402-1.0UF,16V,10%,X6S,D97A') ****
**** Part Type 'CAP_0402' ('CAP_0402-1.0UF,16V,10%,X7S,G71A') ****
**** Part Type 'CAP' ('CAP_0402LF-0.022UF,16V,10%,X7RA') ****
**** Part Type 'CAP' ('CAP_0402LF-0.039UF,25V,10%,X7RA') ****
**** Part Type 'CAP' ('CAP_0402LF-10.0PF,50V,5%,COG,AA') ****
**** Part Type 'CAP' ('CAP_0402LF-100.0PF,50V,5%,COG,A') ****
**** Part Type 'CAP' ('CAP_0402LF-1000PF,50V,10%,EMPTA') ****
**** Part Type 'CAP' ('CAP_0402LF-1000PF,50V,10%,X7R,A') ****
**** Part Type 'CAP' ('CAP_0402LF-12.0PF,50V,5%,COG,AA') ****
**** Part Type 'CAP' ('CAP_0402LF-15.0PF,50V,5%,COG,AA') ****
**** Part Type 'CAP' ('CAP_0402LF-18PF,50V,5%,C0G,A36A') ****
**** Part Type 'CAP' ('CAP_0402LF-22.0PF,50V,5%,COG,AA') ****
**** Part Type 'CAP' ('CAP_0402LF-2200PF,50V,10%,X7R,A') ****
**** Part Type 'CAP' ('CAP_0402LF-220PF,50V,10%,X7R,AA') ****
**** Part Type 'CAP' ('CAP_0402LF-27.0PF,50V,5%,COG,AA') ****
**** Part Type 'CAP' ('CAP_0402LF-270PF,50V,10%,X7R,AA') ****
**** Part Type 'CAP' ('CAP_0402LF-33.0PF,50V,5%,COG,AA') ****
**** Part Type 'CAP' ('CAP_0402LF-3300PF,50V,10%,EMPTA') ****
**** Part Type 'CAP' ('CAP_0402LF-47.0PF,50V,5%,COG,AA') ****
**** Part Type 'CAP' ('CAP_0402LF-47.0PF,50V,5%,EMPTYA') ****
**** Part Type 'CAP' ('CAP_0402LF-4700PF,50V,10%,EMPTA') ****
**** Part Type 'CAP' ('CAP_0402LF-470PF,50V,10%,EMPTYA') ****
**** Part Type 'CAP' ('CAP_0402LF-470PF,50V,10%,X7R,AA') ****
**** Part Type 'CAP' ('CAP_0603-0.47UF,16V,10%,X7R,20A') ****
**** Part Type 'CAP' ('CAP_0603-10UF,6.3V,20%,EMPTY,EA') ****
**** Part Type 'CAP' ('CAP_0603-10UF,6.3V,20%,X6S,E15A') ****
**** Part Type 'CAP' ('CAP_0603-4.7UF,6.3V,10%,X6S,E1A') ****
**** Part Type 'CAP' ('CAP_0603LF-0.033UF,50V,10%,X7RA') ****
**** Part Type 'CAP' ('CAP_0603LF-0.1UF,25V,10%,X7R,6A') ****
**** Part Type 'CAP' ('CAP_0603LF-10UF,4V,20%,X6S,E15A') ****
**** Part Type 'CAP' ('CAP_0805-100UF,4V,20%,X5R,6024A') ****
**** Part Type 'CAP' ('CAP_0805-10UF,16V,10%,X6S,C953A') ****
**** Part Type 'CAP' ('CAP_0805-10UF,16V,10%,X7R,G106A') ****
**** Part Type 'CAP' ('CAP_0805-22UF,6.3V,20%,X6S,C95A') ****
**** Part Type 'CAP' ('CAP_0805-47UF,4V,20%,X6S,C9533A') ****
**** Part Type 'CAP' ('CAP_0805LF-22UF,4V,20%,X6S,C95A') ****
**** Part Type 'CAP' ('CAP_1206-0.068UF,50V,20%,X7R,1A') ****
**** Part Type 'CAP' ('CAP_1206LF-22UF,16V,10%,X6S,D3A') ****
**** Part Type 'CAP' ('CAP_1210-100UF,16V,20%,X5R,644A') ****
**** Part Type 'CAP' ('CAP_1210-47UF,16V,20%,EMPTY,D3A') ****
**** Part Type 'CAP' ('CAP_1210-47UF,16V,20%,X6S,D384A') ****
**** Part Type 'CAP_A' ('CAP_A_0402V-0.01UF,25V,10%,EMPA') ****
**** Part Type 'CAP_A' ('CAP_A_0402V-0.01UF,25V,10%,X7RA') ****
**** Part Type 'CAP_A' ('CAP_A_0402V-0.1UF,16V,10%,EMPTA') ****
**** Part Type 'CAP_A' ('CAP_A_0402V-0.1UF,16V,10%,X7R,A') ****
**** Part Type 'CAP_A' ('CAP_A_0402V-1.0UF,6.3V,10%,EMPA') ****
**** Part Type 'CAP_A' ('CAP_A_0402V-1.0UF,6.3V,10%,X6SA') ****
**** Part Type 'CAP_A' ('CAP_A_0603V-22.0UF,4V,20%,EMPTA') ****
**** Part Type 'CAP_A' ('CAP_A_0603V-22.0UF,4V,20%,X6S,A') ****
**** Part Type 'CAP_A' ('CAP_A_0603V-47UF,4V,20%,X5R,60A') ****
**** Part Type 'CHOKE_4PIN' ('CHOKE_4PIN_SMLF-90 OHM,EMPTY,7A') ****
**** Part Type 'CHOKE_4PIN_SM_B' ('CHOKE_4PIN_SM_B-67 OHM,EMPTY,7A') ****
**** Part Type 'CONN12_C73564003' ('CONN12_C73564003_PIP-CONN,C735A') ****
**** Part Type 'CONN12_G98257001_THMT' ('CONN12_G98257001_THMT-CONN,G98A') ****
**** Part Type 'CONN14_H54902001_PIP' ('CONN14_H54902001_PIP-CONN,H549A') ****
**** Part Type 'CONN17_H71061002_PIP1' ('CONN17_H71061002_PIP1-CONN,H71A') ****
**** Part Type 'CONN36_G97614001_CP' ('CONN36_G97614001_CP-CONN,G9761A') ****
**** Part Type 'CONN3_C95678002_PIP' ('CONN3_C95678002_PIP-CONN,C9567A') ****
**** Part Type 'CONN3_G98259001_PIP' ('CONN3_G98259001_PIP-CONN,G9825A') ****
**** Part Type 'CONN4_D42317002_PIP' ('CONN4_D42317002_PIP-CONN,D4231A') ****
**** Part Type 'CONN4_H73295001_PIP' ('CONN4_H73295001_PIP-CONN,H7329A') ****
**** Part Type 'CONN4_H73295001_PIP' ('CONN4_H73295001_PIP-EMPTY,H732A') ****
**** Part Type 'CONN6_C74770005' ('CONN6_C74770005_PIP-HDR,C74770A') ****
**** Part Type 'CONN72_G97614002_A_CP' ('CONN72_G97614002_A_CP-CONN,G97A') ****
**** Part Type 'CONN76_H22707001_THMT1' ('CONN76_H22707001_THMT1-CONN,H2A') ****
**** Part Type 'CONN7_E82125014_PIP_TH' ('CONN7_E82125014_PIP_TH-CONN,E8A') ****
**** Part Type 'CONN7_E82125014_PIP_TH' ('CONN7_E82125014_PIP_TH-EMPTY,EA') ****
**** Part Type 'CONN8_C77962004' ('CONN8_C77962004_PIP-CONN,C7796A') ****
**** Part Type 'CONN8_H62179001_PIP' ('CONN8_H62179001_PIP-CONN,H6217A') ****
**** Part Type 'CONN9_H51826001_PIP2' ('CONN9_H51826001_PIP2-CONN,H518A') ****
**** Part Type 'CRYSTAL_2013' ('CRYSTAL_2013-25.000MHZ,IC,D717A') ****
**** Part Type 'CRYSTAL_2013' ('CRYSTAL_2013-25.000MHZ,IC,H196A') ****
**** Part Type 'CRYSTAL_2013' ('CRYSTAL_2013-48.000MHZ,IC,D717A') ****
**** Part Type 'CRYSTAL_2013LF' ('CRYSTAL_2013LF-25.000MHZ,IC,D7B') ****
**** Part Type 'CRYSTAL_SM' ('CRYSTAL_SM-24.000MHZ,IC,D95126A') ****
**** Part Type 'CRYSTAL_SM' ('CRYSTAL_SM-32.768KHZ,IC,C13544A') ****
**** Part Type 'CSD87384M_SM' ('CSD87384M_SM-IC,H66258-001') ****
**** Part Type 'DIODE2A_DUAL' ('DIODE2A_DUAL_SMLF-BAS70-05,DIOA') ****
**** Part Type 'DIODEAC_DUAL_ARRAY_SM9' ('DIODEAC_DUAL_ARRAY_SM9-ESD3V3UA') ****
**** Part Type 'DIODE_SM' ('DIODE_SM-1N4148W,IC,D89194-001') ****
**** Part Type 'DIODE_SM' ('DIODE_SM-MBRS340T3G,EMPTY,C819A') ****
**** Part Type 'DIODE_SM' ('DIODE_SM-SDMK0340L,EMPTY,H7179A') ****
**** Part Type 'DIODE_SM' ('DIODE_SM-SDMK0340L,IC,H71799-0A') ****
**** Part Type 'DIODE_SMLF' ('DIODE_SMLF-1N5819HW,IC,D55839-A') ****
**** Part Type 'DIODE_SMLF' ('DIODE_SMLF-BAT54WS,IC,C73510-0A') ****
**** Part Type 'FERRITE_SM' ('FERRITE_SM-120,FB,693286-027') ****
**** Part Type 'FERRITE_SM' ('FERRITE_SM-22,FB,656554-051') ****
**** Part Type 'FERRITE' ('FERRITE_SMLF-30,FB,693286-021') ****
**** Part Type 'FERRITE' ('FERRITE_SMLF-300,EMPTY,693286-A') ****
**** Part Type 'FERRITE' ('FERRITE_SMLF-300,FB,693286-046') ****
**** Part Type 'FERRITE' ('FERRITE_SMLF-60,FB,693286-001') ****
**** Part Type 'FERRITE' ('FERRITE_SMLF-600,FB,656554-043') ****
**** Part Type 'FET_N_DUAL_SMLF' ('FET_N_DUAL_SMLF-2N7002DW,FET,DA') ****
**** Part Type 'FET_N_DUAL_SMLF' ('FET_N_DUAL_SMLF-NTJD4001N,FET,A') ****
**** Part Type 'FET_N' ('FET_N_SOT23-2N7002,FET,C79254-A') ****
**** Part Type 'FET_N' ('FET_N_SOT23LF-2N7002,FET,C7925A') ****
**** Part Type 'FSA3357_SM' ('FSA3357_SM-IC,C63273-001') ****
**** Part Type 'FUSE_SM' ('FUSE_SM-IC,C94311-016') ****
**** Part Type 'FUSE' ('FUSE_SMLF-IC,C94311-006') ****
**** Part Type 'FUSE_SMT' ('FUSE_SMT-IC,H45581-001') ****
**** Part Type 'GTL2014_SM' ('GTL2014_SM-IC,D66151-001') ****
**** Part Type 'ICS9FGP204_MLFP' ('ICS9FGP204_MLFP-IC,E95226-001') ****
**** Part Type 'INDUCTOR' ('INDUCTOR_SM-0.12UH,IND,D92183-A') ****
**** Part Type 'INDUCTOR' ('INDUCTOR_SM-0.3UH,IND,D92183-0A') ****
**** Part Type 'INDUCTOR' ('INDUCTOR_SM-0.47UH,IND,E13358-A') ****
**** Part Type 'INDUCTOR' ('INDUCTOR_SM-1.00UH,IND,E98679-A') ****
**** Part Type 'INDUCTOR' ('INDUCTOR_SM-100NH,IND,D92183-0A') ****
**** Part Type 'INDUCTOR' ('INDUCTOR_SM-100NH,IND,D92183-0B') ****
**** Part Type 'INDUCTOR' ('INDUCTOR_SM-150NH,IND,D92183-0A') ****
**** Part Type 'INDUCTOR' ('INDUCTOR_SM-2.2UH,IND,E98761-0A') ****
**** Part Type 'INDUCTOR' ('INDUCTOR_SMT-0.022UH,IND,72189A') ****
**** Part Type 'IR354XX_SM' ('IR354XX_SM-IR35411,IC,H73688-0A') ****
**** Part Type 'IR354XX_SM' ('IR354XX_SM-IR35412,IC,H73684-0A') ****
**** Part Type 'K4B1G16_BGA1' ('K4B1G16_BGA1-IC,G38649-001') ****
**** Part Type 'LBG_CORE_QAT_EXT_D' ('LBG_CORE_QAT_EXT_D_BGA1-IC,H91A') ****
**** Part Type 'LCMXO2_A_256BGA' ('LCMXO2_A_256BGA-IC,H63395-001') ****
**** Part Type 'LED_1NC' ('LED_1NC-BLUE,IC,C96565-012') ****
**** Part Type 'LED_1NCLF' ('LED_1NCLF-GREEN,IC,C96565-011') ****
**** Part Type 'LED_1NCLF' ('LED_1NCLF-YELLOW,IC,C96565-003') ****
**** Part Type 'LED_A1' ('LED_A1-RED,IC,D14725-005') ****
**** Part Type 'LED_A1LF' ('LED_A1LF-GREEN,IC,C97278-010') ****
**** Part Type 'LED_A1LF' ('LED_A1LF-GREEN,IC,D14725-022') ****
**** Part Type 'M25PE16_SM' ('M25PE16_SM-IC,H77797-001') ****
**** Part Type 'MAX9634_SOT' ('MAX9634_SOT-IC,H35789-001') ****
**** Part Type 'MIC5166_DFN' ('MIC5166_DFN-IC,H55101-001') ****
**** Part Type 'MOSFETN_1D3S_SOT5' ('MOSFETN_1D3S_SOT5-IC,G68777-001') ****
**** Part Type 'MOSFET_N_LCC3' ('MOSFET_N_LCC3-BSZ019N03LS,NFETA') ****
**** Part Type 'MTG_KEYHOLE_TH' ('MTG_KEYHOLE_TH-EMPTY,NA') ****
**** Part Type 'NB3W1200L_LCC' ('NB3W1200L_LCC-IC,H13585-001') ****
**** Part Type 'NC7SB3157' ('NC7SB3157_SMLF-IC,C99406-001') ****
**** Part Type 'NCP3232L_SM' ('NCP3232L_SM-IC,H86355-001') ****
**** Part Type 'NPN_DUAL' ('NPN_DUAL_SSOPLF-MBT3904,EMPTY,A') ****
**** Part Type 'NPN_DUAL' ('NPN_DUAL_SSOPLF-MBT3904,XSTR,CA') ****
**** Part Type 'NPN_SM' ('NPN_SM-MMBT3904,IC,C52245-001') ****
**** Part Type 'OSC_C_6P10' ('OSC_C_6P10-156.25MHZ,OSC,G6383A') ****
**** Part Type 'OSC_C_SM4' ('OSC_C_SM4-24MHZ,OSC,D34520-021') ****
**** Part Type 'PCA9517_SM' ('PCA9517_SM-IC,G77073-001-GND=GA') ****
**** Part Type 'PCA9617_SSOP' ('PCA9617_SSOP-IC,G81764-001-GNDA') ****
**** Part Type 'PI3B3257A_TSSOPLF' ('PI3B3257A_TSSOPLF-IC,E16801-001') ****
**** Part Type 'PI7C9X1172_QFN' ('PI7C9X1172_QFN-IC,H66899-001') ****
**** Part Type 'PNP' ('PNP_TO92-MPS2907,IC,G73554-001') ****
**** Part Type 'PXE1110B_QFN' ('PXE1110B_QFN-IC,H89187-001') ****
**** Part Type 'PXE1610B_QFN' ('PXE1610B_QFN-IC,H79206-001') ****
**** Part Type 'PXM1310B_QFN' ('PXM1310B_QFN-IC,H89186-001') ****
**** Part Type 'RCC_DFX1940' ('RCC_DFX1940_ID4-EMPTY,N_A') ****
**** Part Type 'RES' ('RES_0402-0.0,5%,1/16W,CHIP,G21A') ****
**** Part Type 'RES' ('RES_0402-0.0,5%,1/16W,EMPTY,G2A') ****
**** Part Type 'RES' ('RES_0402-1.0,1%,1/16W,CHIP,G21A') ****
**** Part Type 'RES' ('RES_0402-1.00K,1%,1/16W,CHIP,GA') ****
**** Part Type 'RES' ('RES_0402-1.00K,1%,1/16W,EMPTY,A') ****
**** Part Type 'RES' ('RES_0402-1.0K,0.1%,1/16W,CHIP,A') ****
**** Part Type 'RES' ('RES_0402-1.0M,1%,1/16W,EMPTY,GA') ****
**** Part Type 'RES' ('RES_0402-1.37K,1%,1/16W,CHIP,GA') ****
**** Part Type 'RES' ('RES_0402-1.5K,1%,1/16W,CHIP,G2A') ****
**** Part Type 'RES' ('RES_0402-1.8K,1%,1/16W,CHIP,G2A') ****
**** Part Type 'RES' ('RES_0402-10.0,1%,1/16W,CHIP,G2A') ****
**** Part Type 'RES' ('RES_0402-10.0,1%,1/16W,EMPTY,GA') ****
**** Part Type 'RES' ('RES_0402-10.0K,1%,1/16W,CHIP,GA') ****
**** Part Type 'RES' ('RES_0402-10.0K,1%,1/16W,EMPTY,A') ****
**** Part Type 'RES' ('RES_0402-100.0,1%,1/16W,CHIP,GA') ****
**** Part Type 'RES' ('RES_0402-100.0,1%,1/16W,EMPTY,A') ****
**** Part Type 'RES' ('RES_0402-100.0K,1%,1/16W,CHIP,A') ****
**** Part Type 'RES' ('RES_0402-100.0K,1%,1/16W,CHIP,B') ****
**** Part Type 'RES' ('RES_0402-100.0K,1%,1/16W,EMPTYA') ****
**** Part Type 'RES' ('RES_0402-105.0K,1%,1/16W,CHIP,A') ****
**** Part Type 'RES' ('RES_0402-110,1%,1/16W,EMPTY,G2A') ****
**** Part Type 'RES' ('RES_0402-113,1%,1/16W,CHIP,G21A') ****
**** Part Type 'RES' ('RES_0402-11K,1%,1/16W,CHIP,G21A') ****
**** Part Type 'RES' ('RES_0402-12.1K,1%,1/16W,CHIP,GA') ****
**** Part Type 'RES' ('RES_0402-12K,1%,1/16W,CHIP,G21A') ****
**** Part Type 'RES' ('RES_0402-13K,1.0%,1/16W,CHIP,GA') ****
**** Part Type 'RES' ('RES_0402-15.0K,1%,1/16W,CHIP,GA') ****
**** Part Type 'RES' ('RES_0402-150.0,1%,1/16W,CHIP,GA') ****
**** Part Type 'RES' ('RES_0402-150.0K,1%,1/16W,CHIP,A') ****
**** Part Type 'RES' ('RES_0402-169,1.0%,1/16W,CHIP,GA') ****
**** Part Type 'RES' ('RES_0402-16K,1.0%,1/16W,CHIP,GA') ****
**** Part Type 'RES' ('RES_0402-2,1.0%,1/16W,CHIP,G21A') ****
**** Part Type 'RES' ('RES_0402-2.0K,1%,1/16W,CHIP,G2A') ****
**** Part Type 'RES' ('RES_0402-2.0K,1%,1/16W,EMPTY,GA') ****
**** Part Type 'RES' ('RES_0402-2.2,5%,1/16W,EMPTY,G2A') ****
**** Part Type 'RES' ('RES_0402-2.21K,1%,1/16W,CHIP,GA') ****
**** Part Type 'RES' ('RES_0402-2.26K,1.0%,1/16W,CHIPA') ****
**** Part Type 'RES' ('RES_0402-2.26K,1.0%,1/16W,EMPTA') ****
**** Part Type 'RES' ('RES_0402-2.67K,1%,1/16W,CHIP,GA') ****
**** Part Type 'RES' ('RES_0402-2.7K,1%,1/16W,CHIP,G2A') ****
**** Part Type 'RES' ('RES_0402-2.7K,1%,1/16W,EMPTY,GA') ****
**** Part Type 'RES' ('RES_0402-20.0,1%,1/16W,CHIP,G2A') ****
**** Part Type 'RES' ('RES_0402-20.0,1%,1/16W,EMPTY,GA') ****
**** Part Type 'RES' ('RES_0402-20.0K,1%,1/16W,CHIP,GA') ****
**** Part Type 'RES' ('RES_0402-20.0K,1%,1/16W,EMPTY,A') ****
**** Part Type 'RES' ('RES_0402-200.0,1%,1/16W,CHIP,GA') ****
**** Part Type 'RES' ('RES_0402-200.0K,1%,1/16W,CHIP,A') ****
**** Part Type 'RES' ('RES_0402-22.1,1.0%,1/16W,CHIP,A') ****
**** Part Type 'RES' ('RES_0402-221,1.0%,1/16W,CHIP,GA') ****
**** Part Type 'RES' ('RES_0402-23.2K,1%,1/16W,CHIP,GA') ****
**** Part Type 'RES' ('RES_0402-24.9K,1%,1/16W,CHIP,GA') ****
**** Part Type 'RES' ('RES_0402-240,1.0%,1/16W,CHIP,GA') ****
**** Part Type 'RES' ('RES_0402-240,1.0%,1/16W,EMPTY,A') ****
**** Part Type 'RES' ('RES_0402-249,0.1%,1/16W,CHIP,GA') ****
**** Part Type 'RES' ('RES_0402-249K,1.0%,1/16W,CHIP,A') ****
**** Part Type 'RES' ('RES_0402-27.4,1%,1/16W,CHIP,G2A') ****
**** Part Type 'RES' ('RES_0402-274K,1.0%,1/16W,CHIP,A') ****
**** Part Type 'RES' ('RES_0402-3.16K,1%,1/16W,CHIP,GA') ****
**** Part Type 'RES' ('RES_0402-3.32K,1%,1/16W,CHIP,GA') ****
**** Part Type 'RES' ('RES_0402-3.32K,1%,1/16W,EMPTY,A') ****
**** Part Type 'RES' ('RES_0402-3.3K,5%,1/16W,CHIP,G2A') ****
**** Part Type 'RES' ('RES_0402-3.48K,1.0%,1/16W,CHIPA') ****
**** Part Type 'RES' ('RES_0402-3.74K,1%,1/16W,CHIP,GA') ****
**** Part Type 'RES' ('RES_0402-301.0,1%,1/16W,CHIP,GA') ****
**** Part Type 'RES' ('RES_0402-33.0K,5%,1/16W,CHIP,GA') ****
**** Part Type 'RES' ('RES_0402-33.2,1%,1/16W,CHIP,G2A') ****
**** Part Type 'RES' ('RES_0402-33.2,1%,1/16W,EMPTY,GA') ****
**** Part Type 'RES' ('RES_0402-330,5%,1/16W,CHIP,G21A') ****
**** Part Type 'RES' ('RES_0402-348,1%,1/16W,CHIP,G21A') ****
**** Part Type 'RES' ('RES_0402-348,1%,1/16W,EMPTY,G2A') ****
**** Part Type 'RES' ('RES_0402-4.02K,1%,1/16W,CHIP,GA') ****
**** Part Type 'RES' ('RES_0402-4.75K,1%,1/16W,CHIP,GA') ****
**** Part Type 'RES' ('RES_0402-4.75K,1%,1/16W,EMPTY,A') ****
**** Part Type 'RES' ('RES_0402-4.99K,1%,1/16W,CHIP,GA') ****
**** Part Type 'RES' ('RES_0402-40.2K,1%,1/16W,CHIP,GA') ****
**** Part Type 'RES' ('RES_0402-42.2,1.0%,1/16W,EMPTYA') ****
**** Part Type 'RES' ('RES_0402-470.0,5%,1/16W,CHIP,GA') ****
**** Part Type 'RES' ('RES_0402-475.0,1%,1/16W,CHIP,GA') ****
**** Part Type 'RES' ('RES_0402-49.9,1%,1/16W,CHIP,G2A') ****
**** Part Type 'RES' ('RES_0402-49.9,1%,1/16W,EMPTY,GA') ****
**** Part Type 'RES' ('RES_0402-49.9K,1%,1/16W,CHIP,GA') ****
**** Part Type 'RES' ('RES_0402-5.11K,1%,1/16W,CHIP,GA') ****
**** Part Type 'RES' ('RES_0402-5.36K,1.0%,1/16W,CHIPA') ****
**** Part Type 'RES' ('RES_0402-5.76K,1%,1/16W,CHIP,GA') ****
**** Part Type 'RES' ('RES_0402-51,5.0%,1/16W,CHIP,G2A') ****
**** Part Type 'RES' ('RES_0402-51.1,1.0%,1/16W,CHIP,A') ****
**** Part Type 'RES' ('RES_0402-560,5%,1/16W,CHIP,G21A') ****
**** Part Type 'RES' ('RES_0402-6.19K,1%,1/16W,CHIP,GA') ****
**** Part Type 'RES' ('RES_0402-6.34K,1%,1/16W,CHIP,GA') ****
**** Part Type 'RES' ('RES_0402-63.4K,1.0%,1/16W,CHIPA') ****
**** Part Type 'RES' ('RES_0402-64.9,1.0%,1/16W,CHIP,A') ****
**** Part Type 'RES' ('RES_0402-64.9K,1%,1/16W,CHIP,GA') ****
**** Part Type 'RES' ('RES_0402-665,1.0%,1/16W,CHIP,GA') ****
**** Part Type 'RES' ('RES_0402-68.1K,1%,1/16W,EMPTY,A') ****
**** Part Type 'RES' ('RES_0402-69.8K,1%,1/16W,CHIP,GA') ****
**** Part Type 'RES' ('RES_0402-7.5K,1%,1/16W,CHIP,G2A') ****
**** Part Type 'RES' ('RES_0402-7.87K,1.0%,1/16W,CHIPA') ****
**** Part Type 'RES' ('RES_0402-75,1.0%,1/16W,CHIP,G2A') ****
**** Part Type 'RES' ('RES_0402-75K,1%,1/16W,CHIP,G21A') ****
**** Part Type 'RES' ('RES_0402-8.06K,1%,1/16W,CHIP,GA') ****
**** Part Type 'RES' ('RES_0402-8.2K,1%,1/16W,CHIP,G2A') ****
**** Part Type 'RES' ('RES_0402-8.2K,1%,1/16W,EMPTY,GA') ****
**** Part Type 'RES' ('RES_0402-90.9,1%,1/16W,CHIP,G2A') ****
**** Part Type 'RES' ('RES_0402-90.9K,1%,1/16W,CHIP,GA') ****
**** Part Type 'RES' ('RES_0603-0,5.0%,1/10W,CHIP,G22A') ****
**** Part Type 'RES' ('RES_0603-0,5.0%,1/10W,EMPTY,G2A') ****
**** Part Type 'RES' ('RES_0603-10.0,1%,1/10W,CHIP,G2A') ****
**** Part Type 'RES' ('RES_0603-100.0,1%,1/10W,CHIP,GA') ****
**** Part Type 'RES' ('RES_0603-100.0K,1%,1/10W,CHIP,A') ****
**** Part Type 'RES' ('RES_0603-10M,1.0%,1/10W,CHIP,GA') ****
**** Part Type 'RES' ('RES_0603-120.0,1%,1/10W,CHIP,GA') ****
**** Part Type 'RES' ('RES_0603-2.2,1.0%,1/10W,CHIP,GA') ****
**** Part Type 'RES' ('RES_0603-200K,0.1%,1/10W,CHIP,A') ****
**** Part Type 'RES' ('RES_0603-475.0,1%,1/10W,CHIP,GA') ****
**** Part Type 'RES' ('RES_0805-0.0,5%,1/8W,CHIP,G221A') ****
**** Part Type 'RES' ('RES_1206-0.002,1%,1W,CHIP,G521A') ****
**** Part Type 'RES' ('RES_2010-0.001,1%,1W,CHIP,E309A') ****
**** Part Type 'RES_PWR_6PAD' ('RES_PWR_6PAD-0.001,1%,3W,CHIP,A') ****
**** Part Type 'RT8240_QFN' ('RT8240_QFN-IC,H66262-001') ****
**** Part Type 'RT9059_DFN' ('RT9059_DFN-IC,H65765-001') ****
**** Part Type 'SC2K2P50V3KX-GP_SMD-BCG6' ('SC2K2P50V3KX-GP_SMD-BCG6-SC2K2A') ****
**** Part Type 'SCONN10_C12536004' ('SCONN10_C12536004_SMLF-CONN,C1A') ****
**** Part Type 'SCONN11_H67026001_SM' ('SCONN11_H67026001_SM-CONN,H670A') ****
**** Part Type 'SCONN120_A28699018_SM' ('SCONN120_A28699018_SM-SCONN,A2A') ****
**** Part Type 'SCONN120_H61426002_SM' ('SCONN120_H61426002_SM-CONN,H61A') ****
**** Part Type 'SCONN200_H68296001_SM' ('SCONN200_H68296001_SM-CONN,H68A') ****
**** Part Type 'SCONN24_H46321001_SM' ('SCONN24_H46321001_SM-SCONN,H46A') ****
**** Part Type 'SCONN288_H44441003_PIP' ('SCONN288_H44441003_PIP-SCONN,HA') ****
**** Part Type 'SCONN288_H44441004_PIP' ('SCONN288_H44441004_PIP-SCONN,HA') ****
**** Part Type 'SCONN3_D53458001_SM' ('SCONN3_D53458001_SM-EMPTY,D534A') ****
**** Part Type 'SCONN60_C21100002' ('SCONN60_C21100002_SMLF-CONN,C2A') ****
**** Part Type 'SCONN64_H87568002_A_SMT' ('SCONN64_H87568002_A_SMT-CONN,HA') ****
**** Part Type 'SCONN75K_H17033002_SMT1' ('SCONN75K_H17033002_SMT1-SCONN,A') ****
**** Part Type 'SCONN80_E67482007_SM' ('SCONN80_E67482007_SM-CONN,E674A') ****
**** Part Type 'SHUNT' ('SHUNT_SH0201-EMPTY,N_A') ****
**** Part Type 'SKX_EXT_B_BGA1' ('SKX_EXT_B_BGA1-IC,TBD') ****
**** Part Type 'SLG55021_SM' ('SLG55021_SM-IC,G56246-001') ****
**** Part Type 'SNLABEL_A' ('SNLABEL_A_LABEL-EMPTY,N_A') ****
**** Part Type 'SOCKET_P_MECH_A_LEFT' ('SOCKET_P_MECH_A_LEFT-P0,PLASTIA') ****
**** Part Type 'SOCKET_P_MECH_A_RIGHT' ('SOCKET_P_MECH_A_RIGHT-P0,PLASTA') ****
**** Part Type 'SPRINGVILLE_SM1' ('SPRINGVILLE_SM1-IC,G47144-004') ****
**** Part Type 'STANDOFF_TH1' ('STANDOFF_TH1-SO,H72821-001') ****
**** Part Type 'SWITCH_D37771002_SM' ('SWITCH_D37771002_SM-IC,D37771-A') ****
**** Part Type 'SWITCH_D90553001_SMLF' ('SWITCH_D90553001_SMLF-IC,D9055A') ****
**** Part Type 'SW_H67881001_SM' ('SW_H67881001_SM-IC,H67881-001') ****
**** Part Type 'TMP421_TSSOP' ('TMP421_TSSOP-IC,G62962-001') ****
**** Part Type 'TPS2061_SM' ('TPS2061_SM-IC,H66405-001') ****
**** Part Type 'TPS3700_SM' ('TPS3700_SM-IC,H69492-001') ****
**** Part Type 'TPS54821_LCC' ('TPS54821_LCC-IC,H63269-001') ****
**** Part Type 'TTL08_QFN15' ('TTL08_QFN15-74LVC08A,IC,D90404B') ****
**** Part Type 'TTL1G07_A_SOP' ('TTL1G07_A_SOP-74LVC1G07,IC,C88B') ****
**** Part Type 'TTL1G08' ('TTL1G08_SOTLF-NC7SZ08,IC,D1032B') ****
**** Part Type 'TTL1G08' ('TTL1G08_SOTLF-NC7SZ08,IC,D1032C') ****
**** Part Type 'TTL1G126_A_SOT' ('TTL1G126_A_SOT-74HC1G126,IC,A7B') ****
**** Part Type 'TTL1G32_A' ('TTL1G32_A_SOT-74LVC1G32,IC,E60B') ****
**** Part Type 'TTL1G86_SOTLF' ('TTL1G86_SOTLF-74AHCT1G86,IC,D3B') ****
**** Part Type 'TTL2G07_SOT23LF' ('TTL2G07_SOT23LF-74LVC2G07,IC,DB') ****
**** Part Type 'TTL2G14' ('TTL2G14_SMLF-74LVC2G14,IC,D184B') ****
**** Part Type 'TTL3126_QFNLF' ('TTL3126_QFNLF-74CBTLV3126,IC,DB') ****
**** Part Type 'VERT_BATT_3PIN_PIP' ('VERT_BATT_3PIN_PIP-3PVERT,C686A') ****
**** Part Type 'W25Q128_SKT16' ('W25Q128_SKT16-IC,H12709-001') ****
**** Part Type 'W25Q256_XSOI' ('W25Q256_XSOI-IC,H25002-001') ****
**** Part Type 'ZENER_SM' ('ZENER_SM-13V,IC,H69095-001') ****

END.
